FILE_TYPE=LIBRARY_PARTS;
primitive 'SKX_EXT_B','SKX_EXT_B_BGA','SKX_EXT_B_BGA1','SKX_EXT_B_INT';
  pin
    'BCLK0_DN':
      PIN_NUMBER='(AU24,0,0,0,0,0,0,0,0,0,0,0,0,0,0,0,0,0,0,0,0,0,0,0,0,0,0,0,0,0)';
      INPUT_LOAD='(-0.01,0.01)';
    'BCLK0_DP':
      PIN_NUMBER='(AW24,0,0,0,0,0,0,0,0,0,0,0,0,0,0,0,0,0,0,0,0,0,0,0,0,0,0,0,0,0)';
      INPUT_LOAD='(-0.01,0.01)';
    'BCLK1_DN':
      PIN_NUMBER='(CR26,0,0,0,0,0,0,0,0,0,0,0,0,0,0,0,0,0,0,0,0,0,0,0,0,0,0,0,0,0)';
      INPUT_LOAD='(-0.01,0.01)';
    'BCLK1_DP':
      PIN_NUMBER='(CP27,0,0,0,0,0,0,0,0,0,0,0,0,0,0,0,0,0,0,0,0,0,0,0,0,0,0,0,0,0)';
      INPUT_LOAD='(-0.01,0.01)';
    'BCLK2_DN':
      PIN_NUMBER='(CT25,0,0,0,0,0,0,0,0,0,0,0,0,0,0,0,0,0,0,0,0,0,0,0,0,0,0,0,0,0)';
      INPUT_LOAD='(-0.01,0.01)';
    'BCLK2_DP':
      PIN_NUMBER='(CU26,0,0,0,0,0,0,0,0,0,0,0,0,0,0,0,0,0,0,0,0,0,0,0,0,0,0,0,0,0)';
      INPUT_LOAD='(-0.01,0.01)';
    'BIST_ENABLE':
      PIN_NUMBER='(BA20,0,0,0,0,0,0,0,0,0,0,0,0,0,0,0,0,0,0,0,0,0,0,0,0,0,0,0,0,0)';
      INPUT_LOAD='(-0.01,0.01)';
    'BMCINIT':
      PIN_NUMBER='(BD23,0,0,0,0,0,0,0,0,0,0,0,0,0,0,0,0,0,0,0,0,0,0,0,0,0,0,0,0,0)';
      INPUT_LOAD='(-0.01,0.01)';
    'BPM_N'<7>:
      PIN_NUMBER='(AC12,0,0,0,0,0,0,0,0,0,0,0,0,0,0,0,0,0,0,0,0,0,0,0,0,0,0,0,0,0)';
      BIDIRECTIONAL='TRUE';
      INPUT_LOAD='(-0.01,0.01)';
      OUTPUT_LOAD='(1.0,-1.0)';
    'BPM_N'<6>:
      PIN_NUMBER='(AE12,0,0,0,0,0,0,0,0,0,0,0,0,0,0,0,0,0,0,0,0,0,0,0,0,0,0,0,0,0)';
      BIDIRECTIONAL='TRUE';
      INPUT_LOAD='(-0.01,0.01)';
      OUTPUT_LOAD='(1.0,-1.0)';
    'BPM_N'<5>:
      PIN_NUMBER='(Y11,0,0,0,0,0,0,0,0,0,0,0,0,0,0,0,0,0,0,0,0,0,0,0,0,0,0,0,0,0)';
      BIDIRECTIONAL='TRUE';
      INPUT_LOAD='(-0.01,0.01)';
      OUTPUT_LOAD='(1.0,-1.0)';
    'BPM_N'<4>:
      PIN_NUMBER='(AA12,0,0,0,0,0,0,0,0,0,0,0,0,0,0,0,0,0,0,0,0,0,0,0,0,0,0,0,0,0)';
      BIDIRECTIONAL='TRUE';
      INPUT_LOAD='(-0.01,0.01)';
      OUTPUT_LOAD='(1.0,-1.0)';
    'BPM_N'<3>:
      PIN_NUMBER='(AF11,0,0,0,0,0,0,0,0,0,0,0,0,0,0,0,0,0,0,0,0,0,0,0,0,0,0,0,0,0)';
      BIDIRECTIONAL='TRUE';
      INPUT_LOAD='(-0.01,0.01)';
      OUTPUT_LOAD='(1.0,-1.0)';
    'BPM_N'<2>:
      PIN_NUMBER='(AG10,0,0,0,0,0,0,0,0,0,0,0,0,0,0,0,0,0,0,0,0,0,0,0,0,0,0,0,0,0)';
      BIDIRECTIONAL='TRUE';
      INPUT_LOAD='(-0.01,0.01)';
      OUTPUT_LOAD='(1.0,-1.0)';
    'BPM_N'<1>:
      PIN_NUMBER='(AH11,0,0,0,0,0,0,0,0,0,0,0,0,0,0,0,0,0,0,0,0,0,0,0,0,0,0,0,0,0)';
      BIDIRECTIONAL='TRUE';
      INPUT_LOAD='(-0.01,0.01)';
      OUTPUT_LOAD='(1.0,-1.0)';
    'BPM_N'<0>:
      PIN_NUMBER='(AJ10,0,0,0,0,0,0,0,0,0,0,0,0,0,0,0,0,0,0,0,0,0,0,0,0,0,0,0,0,0)';
      BIDIRECTIONAL='TRUE';
      INPUT_LOAD='(-0.01,0.01)';
      OUTPUT_LOAD='(1.0,-1.0)';
    'CATERR_N':
      PIN_NUMBER='(AL14,0,0,0,0,0,0,0,0,0,0,0,0,0,0,0,0,0,0,0,0,0,0,0,0,0,0,0,0,0)';
      BIDIRECTIONAL='TRUE';
      INPUT_LOAD='(-0.01,0.01)';
      OUTPUT_LOAD='(1.0,-1.0)';
    'CD_HFI0_I2CCLK':
      PIN_NUMBER='(0,0,0,0,0,0,0,0,BN22,0,0,0,0,0,0,0,0,0,0,0,0,0,0,0,0,0,0,0,0,0)';
      BIDIRECTIONAL='TRUE';
      INPUT_LOAD='(-0.01,0.01)';
      OUTPUT_LOAD='(1.0,-1.0)';
    'CD_HFI0_I2CDAT':
      PIN_NUMBER='(0,0,0,0,0,0,0,0,BP23,0,0,0,0,0,0,0,0,0,0,0,0,0,0,0,0,0,0,0,0,0)';
      BIDIRECTIONAL='TRUE';
      INPUT_LOAD='(-0.01,0.01)';
      OUTPUT_LOAD='(1.0,-1.0)';
    'CD_HFI0_INT_N':
      PIN_NUMBER='(0,0,0,0,0,0,0,0,BP19,0,0,0,0,0,0,0,0,0,0,0,0,0,0,0,0,0,0,0,0,0)';
      INPUT_LOAD='(-0.01,0.01)';
    'CD_HFI0_LED_N':
      PIN_NUMBER='(0,0,0,0,0,0,0,0,BK21,0,0,0,0,0,0,0,0,0,0,0,0,0,0,0,0,0,0,0,0,0)';
      OUTPUT_LOAD='(1.0,-1.0)';
    'CD_HFI0_MODPRST_N':
      PIN_NUMBER='(0,0,0,0,0,0,0,0,BR20,0,0,0,0,0,0,0,0,0,0,0,0,0,0,0,0,0,0,0,0,0)';
      INPUT_LOAD='(-0.01,0.01)';
    'CD_HFI0_RESET_N':
      PIN_NUMBER='(0,0,0,0,0,0,0,0,BN24,0,0,0,0,0,0,0,0,0,0,0,0,0,0,0,0,0,0,0,0,0)';
      OUTPUT_LOAD='(1.0,-1.0)';
    'CD_HFI1_I2CCLK':
      PIN_NUMBER='(0,0,0,0,0,0,0,0,BJ22,0,0,0,0,0,0,0,0,0,0,0,0,0,0,0,0,0,0,0,0,0)';
      BIDIRECTIONAL='TRUE';
      INPUT_LOAD='(-0.01,0.01)';
      OUTPUT_LOAD='(1.0,-1.0)';
    'CD_HFI1_I2CDAT':
      PIN_NUMBER='(0,0,0,0,0,0,0,0,BH23,0,0,0,0,0,0,0,0,0,0,0,0,0,0,0,0,0,0,0,0,0)';
      BIDIRECTIONAL='TRUE';
      INPUT_LOAD='(-0.01,0.01)';
      OUTPUT_LOAD='(1.0,-1.0)';
    'CD_HFI1_INT_N':
      PIN_NUMBER='(0,0,0,0,0,0,0,0,BM21,0,0,0,0,0,0,0,0,0,0,0,0,0,0,0,0,0,0,0,0,0)';
      INPUT_LOAD='(-0.01,0.01)';
    'CD_HFI1_LED_N':
      PIN_NUMBER='(0,0,0,0,0,0,0,0,BM23,0,0,0,0,0,0,0,0,0,0,0,0,0,0,0,0,0,0,0,0,0)';
      OUTPUT_LOAD='(1.0,-1.0)';
    'CD_HFI1_MODPRST_N':
      PIN_NUMBER='(0,0,0,0,0,0,0,0,BT19,0,0,0,0,0,0,0,0,0,0,0,0,0,0,0,0,0,0,0,0,0)';
      INPUT_LOAD='(-0.01,0.01)';
    'CD_HFI1_RESET_N':
      PIN_NUMBER='(0,0,0,0,0,0,0,0,BK23,0,0,0,0,0,0,0,0,0,0,0,0,0,0,0,0,0,0,0,0,0)';
      OUTPUT_LOAD='(1.0,-1.0)';
    'CD_HFI_REFCLK_DN':
      PIN_NUMBER='(0,0,0,0,0,0,0,0,BE16,0,0,0,0,0,0,0,0,0,0,0,0,0,0,0,0,0,0,0,0,0)';
      INPUT_LOAD='(-0.01,0.01)';
    'CD_HFI_REFCLK_DP':
      PIN_NUMBER='(0,0,0,0,0,0,0,0,BG16,0,0,0,0,0,0,0,0,0,0,0,0,0,0,0,0,0,0,0,0,0)';
      INPUT_LOAD='(-0.01,0.01)';
    'CD_PE_REFCLK_DN':
      PIN_NUMBER='(0,0,0,0,0,0,0,0,BU24,0,0,0,0,0,0,0,0,0,0,0,0,0,0,0,0,0,0,0,0,0)';
      INPUT_LOAD='(-0.01,0.01)';
    'CD_PE_REFCLK_DP':
      PIN_NUMBER='(0,0,0,0,0,0,0,0,BW24,0,0,0,0,0,0,0,0,0,0,0,0,0,0,0,0,0,0,0,0,0)';
      INPUT_LOAD='(-0.01,0.01)';
    'CD_POR_N':
      PIN_NUMBER='(0,0,0,0,0,0,0,0,CF25,0,0,0,0,0,0,0,0,0,0,0,0,0,0,0,0,0,0,0,0,0)';
      BIDIRECTIONAL='TRUE';
      INPUT_LOAD='(-0.01,0.01)';
      OUTPUT_LOAD='(1.0,-1.0)';
    'CD_TCLK':
      PIN_NUMBER='(0,0,0,0,0,0,0,0,CB23,0,0,0,0,0,0,0,0,0,0,0,0,0,0,0,0,0,0,0,0,0)';
      INPUT_LOAD='(-0.01,0.01)';
    'CD_TDI':
      PIN_NUMBER='(0,0,0,0,0,0,0,0,BY21,0,0,0,0,0,0,0,0,0,0,0,0,0,0,0,0,0,0,0,0,0)';
      INPUT_LOAD='(-0.01,0.01)';
    'CD_TDO':
      PIN_NUMBER='(0,0,0,0,0,0,0,0,CC22,0,0,0,0,0,0,0,0,0,0,0,0,0,0,0,0,0,0,0,0,0)';
      OUTPUT_LOAD='(1.0,-1.0)';
    'CD_TMS':
      PIN_NUMBER='(0,0,0,0,0,0,0,0,CE24,0,0,0,0,0,0,0,0,0,0,0,0,0,0,0,0,0,0,0,0,0)';
      INPUT_LOAD='(-0.01,0.01)';
    'CD_TRST_N':
      PIN_NUMBER='(0,0,0,0,0,0,0,0,CD23,0,0,0,0,0,0,0,0,0,0,0,0,0,0,0,0,0,0,0,0,0)';
      INPUT_LOAD='(-0.01,0.01)';
    'CD_VCCIN'<3>:
      PIN_NUMBER='(0,0,0,0,0,0,0,0,0,0,0,0,0,0,0,0,0,0,0,0,BY27,0,0,0,0,0,0,0,0,0)';
      PINUSE='POWER';
      NO_LOAD_CHECK='Both';
      NO_IO_CHECK='Both';
      NO_ASSERT_CHECK='TRUE';
      NO_DIR_CHECK='TRUE';
      ALLOW_CONNECT='TRUE';
    'CD_VCCIN'<2>:
      PIN_NUMBER='(0,0,0,0,0,0,0,0,0,0,0,0,0,0,0,0,0,0,0,0,BV27,0,0,0,0,0,0,0,0,0)';
      PINUSE='POWER';
      NO_LOAD_CHECK='Both';
      NO_IO_CHECK='Both';
      NO_ASSERT_CHECK='TRUE';
      NO_DIR_CHECK='TRUE';
      ALLOW_CONNECT='TRUE';
    'CD_VCCIN'<1>:
      PIN_NUMBER='(0,0,0,0,0,0,0,0,0,0,0,0,0,0,0,0,0,0,0,0,BU26,0,0,0,0,0,0,0,0,0)';
      PINUSE='POWER';
      NO_LOAD_CHECK='Both';
      NO_IO_CHECK='Both';
      NO_ASSERT_CHECK='TRUE';
      NO_DIR_CHECK='TRUE';
      ALLOW_CONNECT='TRUE';
    'CD_VCCIN'<0>:
      PIN_NUMBER='(0,0,0,0,0,0,0,0,0,0,0,0,0,0,0,0,0,0,0,0,BT27,0,0,0,0,0,0,0,0,0)';
      PINUSE='POWER';
      NO_LOAD_CHECK='Both';
      NO_IO_CHECK='Both';
      NO_ASSERT_CHECK='TRUE';
      NO_DIR_CHECK='TRUE';
      ALLOW_CONNECT='TRUE';
    'CD_VCCP'<15>:
      PIN_NUMBER='(0,0,0,0,0,0,0,0,0,0,0,0,0,0,0,0,0,0,0,0,BM11,0,0,0,0,0,0,0,0,0)';
      PINUSE='POWER';
      NO_LOAD_CHECK='Both';
      NO_IO_CHECK='Both';
      NO_ASSERT_CHECK='TRUE';
      NO_DIR_CHECK='TRUE';
      ALLOW_CONNECT='TRUE';
    'CD_VCCP'<14>:
      PIN_NUMBER='(0,0,0,0,0,0,0,0,0,0,0,0,0,0,0,0,0,0,0,0,BN12,0,0,0,0,0,0,0,0,0)';
      PINUSE='POWER';
      NO_LOAD_CHECK='Both';
      NO_IO_CHECK='Both';
      NO_ASSERT_CHECK='TRUE';
      NO_DIR_CHECK='TRUE';
      ALLOW_CONNECT='TRUE';
    'CD_VCCP'<13>:
      PIN_NUMBER='(0,0,0,0,0,0,0,0,0,0,0,0,0,0,0,0,0,0,0,0,BN14,0,0,0,0,0,0,0,0,0)';
      PINUSE='POWER';
      NO_LOAD_CHECK='Both';
      NO_IO_CHECK='Both';
      NO_ASSERT_CHECK='TRUE';
      NO_DIR_CHECK='TRUE';
      ALLOW_CONNECT='TRUE';
    'CD_VCCP'<12>:
      PIN_NUMBER='(0,0,0,0,0,0,0,0,0,0,0,0,0,0,0,0,0,0,0,0,BP11,0,0,0,0,0,0,0,0,0)';
      PINUSE='POWER';
      NO_LOAD_CHECK='Both';
      NO_IO_CHECK='Both';
      NO_ASSERT_CHECK='TRUE';
      NO_DIR_CHECK='TRUE';
      ALLOW_CONNECT='TRUE';
    'CD_VCCP'<11>:
      PIN_NUMBER='(0,0,0,0,0,0,0,0,0,0,0,0,0,0,0,0,0,0,0,0,BP13,0,0,0,0,0,0,0,0,0)';
      PINUSE='POWER';
      NO_LOAD_CHECK='Both';
      NO_IO_CHECK='Both';
      NO_ASSERT_CHECK='TRUE';
      NO_DIR_CHECK='TRUE';
      ALLOW_CONNECT='TRUE';
    'CD_VCCP'<10>:
      PIN_NUMBER='(0,0,0,0,0,0,0,0,0,0,0,0,0,0,0,0,0,0,0,0,BP15,0,0,0,0,0,0,0,0,0)';
      PINUSE='POWER';
      NO_LOAD_CHECK='Both';
      NO_IO_CHECK='Both';
      NO_ASSERT_CHECK='TRUE';
      NO_DIR_CHECK='TRUE';
      ALLOW_CONNECT='TRUE';
    'CD_VCCP'<9>:
      PIN_NUMBER='(0,0,0,0,0,0,0,0,0,0,0,0,0,0,0,0,0,0,0,0,BR12,0,0,0,0,0,0,0,0,0)';
      PINUSE='POWER';
      NO_LOAD_CHECK='Both';
      NO_IO_CHECK='Both';
      NO_ASSERT_CHECK='TRUE';
      NO_DIR_CHECK='TRUE';
      ALLOW_CONNECT='TRUE';
    'CD_VCCP'<8>:
      PIN_NUMBER='(0,0,0,0,0,0,0,0,0,0,0,0,0,0,0,0,0,0,0,0,BR14,0,0,0,0,0,0,0,0,0)';
      PINUSE='POWER';
      NO_LOAD_CHECK='Both';
      NO_IO_CHECK='Both';
      NO_ASSERT_CHECK='TRUE';
      NO_DIR_CHECK='TRUE';
      ALLOW_CONNECT='TRUE';
    'CD_VCCP'<7>:
      PIN_NUMBER='(0,0,0,0,0,0,0,0,0,0,0,0,0,0,0,0,0,0,0,0,BT11,0,0,0,0,0,0,0,0,0)';
      PINUSE='POWER';
      NO_LOAD_CHECK='Both';
      NO_IO_CHECK='Both';
      NO_ASSERT_CHECK='TRUE';
      NO_DIR_CHECK='TRUE';
      ALLOW_CONNECT='TRUE';
    'CD_VCCP'<6>:
      PIN_NUMBER='(0,0,0,0,0,0,0,0,0,0,0,0,0,0,0,0,0,0,0,0,BT13,0,0,0,0,0,0,0,0,0)';
      PINUSE='POWER';
      NO_LOAD_CHECK='Both';
      NO_IO_CHECK='Both';
      NO_ASSERT_CHECK='TRUE';
      NO_DIR_CHECK='TRUE';
      ALLOW_CONNECT='TRUE';
    'CD_VCCP'<5>:
      PIN_NUMBER='(0,0,0,0,0,0,0,0,0,0,0,0,0,0,0,0,0,0,0,0,BT15,0,0,0,0,0,0,0,0,0)';
      PINUSE='POWER';
      NO_LOAD_CHECK='Both';
      NO_IO_CHECK='Both';
      NO_ASSERT_CHECK='TRUE';
      NO_DIR_CHECK='TRUE';
      ALLOW_CONNECT='TRUE';
    'CD_VCCP'<4>:
      PIN_NUMBER='(0,0,0,0,0,0,0,0,0,0,0,0,0,0,0,0,0,0,0,0,BU12,0,0,0,0,0,0,0,0,0)';
      PINUSE='POWER';
      NO_LOAD_CHECK='Both';
      NO_IO_CHECK='Both';
      NO_ASSERT_CHECK='TRUE';
      NO_DIR_CHECK='TRUE';
      ALLOW_CONNECT='TRUE';
    'CD_VCCP'<3>:
      PIN_NUMBER='(0,0,0,0,0,0,0,0,0,0,0,0,0,0,0,0,0,0,0,0,BU14,0,0,0,0,0,0,0,0,0)';
      PINUSE='POWER';
      NO_LOAD_CHECK='Both';
      NO_IO_CHECK='Both';
      NO_ASSERT_CHECK='TRUE';
      NO_DIR_CHECK='TRUE';
      ALLOW_CONNECT='TRUE';
    'CD_VCCP'<2>:
      PIN_NUMBER='(0,0,0,0,0,0,0,0,0,0,0,0,0,0,0,0,0,0,0,0,BV11,0,0,0,0,0,0,0,0,0)';
      PINUSE='POWER';
      NO_LOAD_CHECK='Both';
      NO_IO_CHECK='Both';
      NO_ASSERT_CHECK='TRUE';
      NO_DIR_CHECK='TRUE';
      ALLOW_CONNECT='TRUE';
    'CD_VCCP'<1>:
      PIN_NUMBER='(0,0,0,0,0,0,0,0,0,0,0,0,0,0,0,0,0,0,0,0,BV13,0,0,0,0,0,0,0,0,0)';
      PINUSE='POWER';
      NO_LOAD_CHECK='Both';
      NO_IO_CHECK='Both';
      NO_ASSERT_CHECK='TRUE';
      NO_DIR_CHECK='TRUE';
      ALLOW_CONNECT='TRUE';
    'CD_VCCP'<0>:
      PIN_NUMBER='(0,0,0,0,0,0,0,0,0,0,0,0,0,0,0,0,0,0,0,0,BV15,0,0,0,0,0,0,0,0,0)';
      PINUSE='POWER';
      NO_LOAD_CHECK='Both';
      NO_IO_CHECK='Both';
      NO_ASSERT_CHECK='TRUE';
      NO_DIR_CHECK='TRUE';
      ALLOW_CONNECT='TRUE';
    'CD_VCCP_SENSE'<1>:
      PIN_NUMBER='(0,0,0,0,0,0,0,0,0,0,0,0,0,0,0,0,0,0,0,0,0,BT17,0,0,0,0,0,0,0,0)';
      PINUSE='POWER';
      NO_LOAD_CHECK='Both';
      NO_IO_CHECK='Both';
      NO_ASSERT_CHECK='TRUE';
      NO_DIR_CHECK='TRUE';
      ALLOW_CONNECT='TRUE';
    'CD_VCCP_SENSE'<0>:
      PIN_NUMBER='(0,0,0,0,0,0,0,0,0,0,0,0,0,0,0,0,0,0,0,0,0,BU16,0,0,0,0,0,0,0,0)';
      PINUSE='POWER';
      NO_LOAD_CHECK='Both';
      NO_IO_CHECK='Both';
      NO_ASSERT_CHECK='TRUE';
      NO_DIR_CHECK='TRUE';
      ALLOW_CONNECT='TRUE';
    'CD_VCC_CORE'<12>:
      PIN_NUMBER='(0,0,0,0,0,0,0,0,0,0,0,0,0,0,0,0,0,0,0,0,BD13,0,0,0,0,0,0,0,0,0)';
      PINUSE='POWER';
      NO_LOAD_CHECK='Both';
      NO_IO_CHECK='Both';
      NO_ASSERT_CHECK='TRUE';
      NO_DIR_CHECK='TRUE';
      ALLOW_CONNECT='TRUE';
    'CD_VCC_CORE'<11>:
      PIN_NUMBER='(0,0,0,0,0,0,0,0,0,0,0,0,0,0,0,0,0,0,0,0,BE12,0,0,0,0,0,0,0,0,0)';
      PINUSE='POWER';
      NO_LOAD_CHECK='Both';
      NO_IO_CHECK='Both';
      NO_ASSERT_CHECK='TRUE';
      NO_DIR_CHECK='TRUE';
      ALLOW_CONNECT='TRUE';
    'CD_VCC_CORE'<10>:
      PIN_NUMBER='(0,0,0,0,0,0,0,0,0,0,0,0,0,0,0,0,0,0,0,0,BE14,0,0,0,0,0,0,0,0,0)';
      PINUSE='POWER';
      NO_LOAD_CHECK='Both';
      NO_IO_CHECK='Both';
      NO_ASSERT_CHECK='TRUE';
      NO_DIR_CHECK='TRUE';
      ALLOW_CONNECT='TRUE';
    'CD_VCC_CORE'<9>:
      PIN_NUMBER='(0,0,0,0,0,0,0,0,0,0,0,0,0,0,0,0,0,0,0,0,BF11,0,0,0,0,0,0,0,0,0)';
      PINUSE='POWER';
      NO_LOAD_CHECK='Both';
      NO_IO_CHECK='Both';
      NO_ASSERT_CHECK='TRUE';
      NO_DIR_CHECK='TRUE';
      ALLOW_CONNECT='TRUE';
    'CD_VCC_CORE'<8>:
      PIN_NUMBER='(0,0,0,0,0,0,0,0,0,0,0,0,0,0,0,0,0,0,0,0,BF13,0,0,0,0,0,0,0,0,0)';
      PINUSE='POWER';
      NO_LOAD_CHECK='Both';
      NO_IO_CHECK='Both';
      NO_ASSERT_CHECK='TRUE';
      NO_DIR_CHECK='TRUE';
      ALLOW_CONNECT='TRUE';
    'CD_VCC_CORE'<7>:
      PIN_NUMBER='(0,0,0,0,0,0,0,0,0,0,0,0,0,0,0,0,0,0,0,0,BG12,0,0,0,0,0,0,0,0,0)';
      PINUSE='POWER';
      NO_LOAD_CHECK='Both';
      NO_IO_CHECK='Both';
      NO_ASSERT_CHECK='TRUE';
      NO_DIR_CHECK='TRUE';
      ALLOW_CONNECT='TRUE';
    'CD_VCC_CORE'<6>:
      PIN_NUMBER='(0,0,0,0,0,0,0,0,0,0,0,0,0,0,0,0,0,0,0,0,BG14,0,0,0,0,0,0,0,0,0)';
      PINUSE='POWER';
      NO_LOAD_CHECK='Both';
      NO_IO_CHECK='Both';
      NO_ASSERT_CHECK='TRUE';
      NO_DIR_CHECK='TRUE';
      ALLOW_CONNECT='TRUE';
    'CD_VCC_CORE'<5>:
      PIN_NUMBER='(0,0,0,0,0,0,0,0,0,0,0,0,0,0,0,0,0,0,0,0,BH13,0,0,0,0,0,0,0,0,0)';
      PINUSE='POWER';
      NO_LOAD_CHECK='Both';
      NO_IO_CHECK='Both';
      NO_ASSERT_CHECK='TRUE';
      NO_DIR_CHECK='TRUE';
      ALLOW_CONNECT='TRUE';
    'CD_VCC_CORE'<4>:
      PIN_NUMBER='(0,0,0,0,0,0,0,0,0,0,0,0,0,0,0,0,0,0,0,0,BJ12,0,0,0,0,0,0,0,0,0)';
      PINUSE='POWER';
      NO_LOAD_CHECK='Both';
      NO_IO_CHECK='Both';
      NO_ASSERT_CHECK='TRUE';
      NO_DIR_CHECK='TRUE';
      ALLOW_CONNECT='TRUE';
    'CD_VCC_CORE'<3>:
      PIN_NUMBER='(0,0,0,0,0,0,0,0,0,0,0,0,0,0,0,0,0,0,0,0,BJ14,0,0,0,0,0,0,0,0,0)';
      PINUSE='POWER';
      NO_LOAD_CHECK='Both';
      NO_IO_CHECK='Both';
      NO_ASSERT_CHECK='TRUE';
      NO_DIR_CHECK='TRUE';
      ALLOW_CONNECT='TRUE';
    'CD_VCC_CORE'<2>:
      PIN_NUMBER='(0,0,0,0,0,0,0,0,0,0,0,0,0,0,0,0,0,0,0,0,BK13,0,0,0,0,0,0,0,0,0)';
      PINUSE='POWER';
      NO_LOAD_CHECK='Both';
      NO_IO_CHECK='Both';
      NO_ASSERT_CHECK='TRUE';
      NO_DIR_CHECK='TRUE';
      ALLOW_CONNECT='TRUE';
    'CD_VCC_CORE'<1>:
      PIN_NUMBER='(0,0,0,0,0,0,0,0,0,0,0,0,0,0,0,0,0,0,0,0,BK15,0,0,0,0,0,0,0,0,0)';
      PINUSE='POWER';
      NO_LOAD_CHECK='Both';
      NO_IO_CHECK='Both';
      NO_ASSERT_CHECK='TRUE';
      NO_DIR_CHECK='TRUE';
      ALLOW_CONNECT='TRUE';
    'CD_VCC_CORE'<0>:
      PIN_NUMBER='(0,0,0,0,0,0,0,0,0,0,0,0,0,0,0,0,0,0,0,0,BL14,0,0,0,0,0,0,0,0,0)';
      PINUSE='POWER';
      NO_LOAD_CHECK='Both';
      NO_IO_CHECK='Both';
      NO_ASSERT_CHECK='TRUE';
      NO_DIR_CHECK='TRUE';
      ALLOW_CONNECT='TRUE';
    'CD_VCC_CORE_SENSE':
      PIN_NUMBER='(0,0,0,0,0,0,0,0,0,0,0,0,0,0,0,0,0,0,0,0,0,BN16,0,0,0,0,0,0,0,0)';
      PINUSE='POWER';
      NO_LOAD_CHECK='Both';
      NO_IO_CHECK='Both';
      NO_ASSERT_CHECK='TRUE';
      NO_DIR_CHECK='TRUE';
      ALLOW_CONNECT='TRUE';
    'CD_VPP'<3>:
      PIN_NUMBER='(0,0,0,0,0,0,0,0,0,0,0,0,0,0,0,0,0,0,0,0,A8,0,0,0,0,0,0,0,0,0)';
      PINUSE='POWER';
      NO_LOAD_CHECK='Both';
      NO_IO_CHECK='Both';
      NO_ASSERT_CHECK='TRUE';
      NO_DIR_CHECK='TRUE';
      ALLOW_CONNECT='TRUE';
    'CD_VPP'<2>:
      PIN_NUMBER='(0,0,0,0,0,0,0,0,0,0,0,0,0,0,0,0,0,0,0,0,A10,0,0,0,0,0,0,0,0,0)';
      PINUSE='POWER';
      NO_LOAD_CHECK='Both';
      NO_IO_CHECK='Both';
      NO_ASSERT_CHECK='TRUE';
      NO_DIR_CHECK='TRUE';
      ALLOW_CONNECT='TRUE';
    'CD_VPP'<1>:
      PIN_NUMBER='(0,0,0,0,0,0,0,0,0,0,0,0,0,0,0,0,0,0,0,0,A12,0,0,0,0,0,0,0,0,0)';
      PINUSE='POWER';
      NO_LOAD_CHECK='Both';
      NO_IO_CHECK='Both';
      NO_ASSERT_CHECK='TRUE';
      NO_DIR_CHECK='TRUE';
      ALLOW_CONNECT='TRUE';
    'CD_VPP'<0>:
      PIN_NUMBER='(0,0,0,0,0,0,0,0,0,0,0,0,0,0,0,0,0,0,0,0,B11,0,0,0,0,0,0,0,0,0)';
      PINUSE='POWER';
      NO_LOAD_CHECK='Both';
      NO_IO_CHECK='Both';
      NO_ASSERT_CHECK='TRUE';
      NO_DIR_CHECK='TRUE';
      ALLOW_CONNECT='TRUE';
    'CD_VSS_VCC_CORE_SENSE':
      PIN_NUMBER='(0,0,0,0,0,0,0,0,0,0,0,0,0,0,0,0,0,0,0,0,0,BL16,0,0,0,0,0,0,0,0)';
      PINUSE='POWER';
      NO_LOAD_CHECK='Both';
      NO_IO_CHECK='Both';
      NO_ASSERT_CHECK='TRUE';
      NO_DIR_CHECK='TRUE';
      ALLOW_CONNECT='TRUE';
    'DDR012_DRAM_PWR_OK':
      PIN_NUMBER='(AN30,0,0,0,0,0,0,0,0,0,0,0,0,0,0,0,0,0,0,0,0,0,0,0,0,0,0,0,0,0)';
      INPUT_LOAD='(-0.01,0.01)';
    'DDR012_RCOMP'<2>:
      PIN_NUMBER='(AC42,0,0,0,0,0,0,0,0,0,0,0,0,0,0,0,0,0,0,0,0,0,0,0,0,0,0,0,0,0)';
      BIDIRECTIONAL='TRUE';
      INPUT_LOAD='(-0.01,0.01)';
      OUTPUT_LOAD='(1.0,-1.0)';
    'DDR012_RCOMP'<1>:
      PIN_NUMBER='(AB43,0,0,0,0,0,0,0,0,0,0,0,0,0,0,0,0,0,0,0,0,0,0,0,0,0,0,0,0,0)';
      BIDIRECTIONAL='TRUE';
      INPUT_LOAD='(-0.01,0.01)';
      OUTPUT_LOAD='(1.0,-1.0)';
    'DDR012_RCOMP'<0>:
      PIN_NUMBER='(Y43,0,0,0,0,0,0,0,0,0,0,0,0,0,0,0,0,0,0,0,0,0,0,0,0,0,0,0,0,0)';
      BIDIRECTIONAL='TRUE';
      INPUT_LOAD='(-0.01,0.01)';
      OUTPUT_LOAD='(1.0,-1.0)';
    'DDR012_RESET_N':
      PIN_NUMBER='(U64,0,0,0,0,0,0,0,0,0,0,0,0,0,0,0,0,0,0,0,0,0,0,0,0,0,0,0,0,0)';
      OUTPUT_LOAD='(1.0,-1.0)';
    'DDR012_SPDSCL':
      PIN_NUMBER='(AJ18,0,0,0,0,0,0,0,0,0,0,0,0,0,0,0,0,0,0,0,0,0,0,0,0,0,0,0,0,0)';
      BIDIRECTIONAL='TRUE';
      INPUT_LOAD='(-0.01,0.01)';
      OUTPUT_LOAD='(1.0,-1.0)';
    'DDR012_SPDSDA':
      PIN_NUMBER='(AF17,0,0,0,0,0,0,0,0,0,0,0,0,0,0,0,0,0,0,0,0,0,0,0,0,0,0,0,0,0)';
      BIDIRECTIONAL='TRUE';
      INPUT_LOAD='(-0.01,0.01)';
      OUTPUT_LOAD='(1.0,-1.0)';
    'DDR0_ACT_N':
      PIN_NUMBER='(0,0,J60,0,0,0,0,0,0,0,0,0,0,0,0,0,0,0,0,0,0,0,0,0,0,0,0,0,0,0)';
      OUTPUT_LOAD='(1.0,-1.0)';
    'DDR0_ALERT_N':
      PIN_NUMBER='(0,0,B61,0,0,0,0,0,0,0,0,0,0,0,0,0,0,0,0,0,0,0,0,0,0,0,0,0,0,0)';
      INPUT_LOAD='(-0.01,0.01)';
    'DDR0_BA'<1>:
      PIN_NUMBER='(0,0,G54,0,0,0,0,0,0,0,0,0,0,0,0,0,0,0,0,0,0,0,0,0,0,0,0,0,0,0)';
      OUTPUT_LOAD='(1.0,-1.0)';
    'DDR0_BA'<0>:
      PIN_NUMBER='(0,0,C52,0,0,0,0,0,0,0,0,0,0,0,0,0,0,0,0,0,0,0,0,0,0,0,0,0,0,0)';
      OUTPUT_LOAD='(1.0,-1.0)';
    'DDR0_BG'<1>:
      PIN_NUMBER='(0,0,F63,0,0,0,0,0,0,0,0,0,0,0,0,0,0,0,0,0,0,0,0,0,0,0,0,0,0,0)';
      OUTPUT_LOAD='(1.0,-1.0)';
    'DDR0_BG'<0>:
      PIN_NUMBER='(0,0,D61,0,0,0,0,0,0,0,0,0,0,0,0,0,0,0,0,0,0,0,0,0,0,0,0,0,0,0)';
      OUTPUT_LOAD='(1.0,-1.0)';
    'DDR0_CAVREF':
      PIN_NUMBER='(AJ64,0,0,0,0,0,0,0,0,0,0,0,0,0,0,0,0,0,0,0,0,0,0,0,0,0,0,0,0,0)';
      OUTPUT_LOAD='(1.0,-1.0)';
    'DDR0_CID'<2>:
      PIN_NUMBER='(0,0,G46,0,0,0,0,0,0,0,0,0,0,0,0,0,0,0,0,0,0,0,0,0,0,0,0,0,0,0)';
      OUTPUT_LOAD='(1.0,-1.0)';
    'DDR0_CKE'<3>:
      PIN_NUMBER='(0,0,D63,0,0,0,0,0,0,0,0,0,0,0,0,0,0,0,0,0,0,0,0,0,0,0,0,0,0,0)';
      OUTPUT_LOAD='(1.0,-1.0)';
    'DDR0_CKE'<2>:
      PIN_NUMBER='(0,0,B63,0,0,0,0,0,0,0,0,0,0,0,0,0,0,0,0,0,0,0,0,0,0,0,0,0,0,0)';
      OUTPUT_LOAD='(1.0,-1.0)';
    'DDR0_CKE'<1>:
      PIN_NUMBER='(0,0,C64,0,0,0,0,0,0,0,0,0,0,0,0,0,0,0,0,0,0,0,0,0,0,0,0,0,0,0)';
      OUTPUT_LOAD='(1.0,-1.0)';
    'DDR0_CKE'<0>:
      PIN_NUMBER='(0,0,C62,0,0,0,0,0,0,0,0,0,0,0,0,0,0,0,0,0,0,0,0,0,0,0,0,0,0,0)';
      OUTPUT_LOAD='(1.0,-1.0)';
    'DDR0_CLK_DN'<3>:
      PIN_NUMBER='(0,0,C56,0,0,0,0,0,0,0,0,0,0,0,0,0,0,0,0,0,0,0,0,0,0,0,0,0,0,0)';
      OUTPUT_LOAD='(1.0,-1.0)';
    'DDR0_CLK_DN'<2>:
      PIN_NUMBER='(0,0,J56,0,0,0,0,0,0,0,0,0,0,0,0,0,0,0,0,0,0,0,0,0,0,0,0,0,0,0)';
      OUTPUT_LOAD='(1.0,-1.0)';
    'DDR0_CLK_DN'<1>:
      PIN_NUMBER='(0,0,C54,0,0,0,0,0,0,0,0,0,0,0,0,0,0,0,0,0,0,0,0,0,0,0,0,0,0,0)';
      OUTPUT_LOAD='(1.0,-1.0)';
    'DDR0_CLK_DN'<0>:
      PIN_NUMBER='(0,0,F55,0,0,0,0,0,0,0,0,0,0,0,0,0,0,0,0,0,0,0,0,0,0,0,0,0,0,0)';
      OUTPUT_LOAD='(1.0,-1.0)';
    'DDR0_CLK_DP'<3>:
      PIN_NUMBER='(0,0,B57,0,0,0,0,0,0,0,0,0,0,0,0,0,0,0,0,0,0,0,0,0,0,0,0,0,0,0)';
      OUTPUT_LOAD='(1.0,-1.0)';
    'DDR0_CLK_DP'<2>:
      PIN_NUMBER='(0,0,G56,0,0,0,0,0,0,0,0,0,0,0,0,0,0,0,0,0,0,0,0,0,0,0,0,0,0,0)';
      OUTPUT_LOAD='(1.0,-1.0)';
    'DDR0_CLK_DP'<1>:
      PIN_NUMBER='(0,0,B55,0,0,0,0,0,0,0,0,0,0,0,0,0,0,0,0,0,0,0,0,0,0,0,0,0,0,0)';
      OUTPUT_LOAD='(1.0,-1.0)';
    'DDR0_CLK_DP'<0>:
      PIN_NUMBER='(0,0,D55,0,0,0,0,0,0,0,0,0,0,0,0,0,0,0,0,0,0,0,0,0,0,0,0,0,0,0)';
      OUTPUT_LOAD='(1.0,-1.0)';
    'DDR0_CS_N'<7>:
      PIN_NUMBER='(0,0,K45,0,0,0,0,0,0,0,0,0,0,0,0,0,0,0,0,0,0,0,0,0,0,0,0,0,0,0)';
      OUTPUT_LOAD='(1.0,-1.0)';
    'DDR0_CS_N'<6>:
      PIN_NUMBER='(0,0,F45,0,0,0,0,0,0,0,0,0,0,0,0,0,0,0,0,0,0,0,0,0,0,0,0,0,0,0)';
      OUTPUT_LOAD='(1.0,-1.0)';
    'DDR0_CS_N'<5>:
      PIN_NUMBER='(0,0,D49,0,0,0,0,0,0,0,0,0,0,0,0,0,0,0,0,0,0,0,0,0,0,0,0,0,0,0)';
      OUTPUT_LOAD='(1.0,-1.0)';
    'DDR0_CS_N'<4>:
      PIN_NUMBER='(0,0,B51,0,0,0,0,0,0,0,0,0,0,0,0,0,0,0,0,0,0,0,0,0,0,0,0,0,0,0)';
      OUTPUT_LOAD='(1.0,-1.0)';
    'DDR0_CS_N'<3>:
      PIN_NUMBER='(0,0,F47,0,0,0,0,0,0,0,0,0,0,0,0,0,0,0,0,0,0,0,0,0,0,0,0,0,0,0)';
      OUTPUT_LOAD='(1.0,-1.0)';
    'DDR0_CS_N'<2>:
      PIN_NUMBER='(0,0,D47,0,0,0,0,0,0,0,0,0,0,0,0,0,0,0,0,0,0,0,0,0,0,0,0,0,0,0)';
      OUTPUT_LOAD='(1.0,-1.0)';
    'DDR0_CS_N'<1>:
      PIN_NUMBER='(0,0,F49,0,0,0,0,0,0,0,0,0,0,0,0,0,0,0,0,0,0,0,0,0,0,0,0,0,0,0)';
      OUTPUT_LOAD='(1.0,-1.0)';
    'DDR0_CS_N'<0>:
      PIN_NUMBER='(0,0,G52,0,0,0,0,0,0,0,0,0,0,0,0,0,0,0,0,0,0,0,0,0,0,0,0,0,0,0)';
      OUTPUT_LOAD='(1.0,-1.0)';
    'DDR0_DQ'<63>:
      PIN_NUMBER='(0,0,K23,0,0,0,0,0,0,0,0,0,0,0,0,0,0,0,0,0,0,0,0,0,0,0,0,0,0,0)';
      BIDIRECTIONAL='TRUE';
      INPUT_LOAD='(-0.01,0.01)';
      OUTPUT_LOAD='(1.0,-1.0)';
    'DDR0_DQ'<62>:
      PIN_NUMBER='(0,0,H23,0,0,0,0,0,0,0,0,0,0,0,0,0,0,0,0,0,0,0,0,0,0,0,0,0,0,0)';
      BIDIRECTIONAL='TRUE';
      INPUT_LOAD='(-0.01,0.01)';
      OUTPUT_LOAD='(1.0,-1.0)';
    'DDR0_DQ'<61>:
      PIN_NUMBER='(0,0,N26,0,0,0,0,0,0,0,0,0,0,0,0,0,0,0,0,0,0,0,0,0,0,0,0,0,0,0)';
      BIDIRECTIONAL='TRUE';
      INPUT_LOAD='(-0.01,0.01)';
      OUTPUT_LOAD='(1.0,-1.0)';
    'DDR0_DQ'<60>:
      PIN_NUMBER='(0,0,L26,0,0,0,0,0,0,0,0,0,0,0,0,0,0,0,0,0,0,0,0,0,0,0,0,0,0,0)';
      BIDIRECTIONAL='TRUE';
      INPUT_LOAD='(-0.01,0.01)';
      OUTPUT_LOAD='(1.0,-1.0)';
    'DDR0_DQ'<59>:
      PIN_NUMBER='(0,0,T23,0,0,0,0,0,0,0,0,0,0,0,0,0,0,0,0,0,0,0,0,0,0,0,0,0,0,0)';
      BIDIRECTIONAL='TRUE';
      INPUT_LOAD='(-0.01,0.01)';
      OUTPUT_LOAD='(1.0,-1.0)';
    'DDR0_DQ'<58>:
      PIN_NUMBER='(0,0,P23,0,0,0,0,0,0,0,0,0,0,0,0,0,0,0,0,0,0,0,0,0,0,0,0,0,0,0)';
      BIDIRECTIONAL='TRUE';
      INPUT_LOAD='(-0.01,0.01)';
      OUTPUT_LOAD='(1.0,-1.0)';
    'DDR0_DQ'<57>:
      PIN_NUMBER='(0,0,P25,0,0,0,0,0,0,0,0,0,0,0,0,0,0,0,0,0,0,0,0,0,0,0,0,0,0,0)';
      BIDIRECTIONAL='TRUE';
      INPUT_LOAD='(-0.01,0.01)';
      OUTPUT_LOAD='(1.0,-1.0)';
    'DDR0_DQ'<56>:
      PIN_NUMBER='(0,0,K25,0,0,0,0,0,0,0,0,0,0,0,0,0,0,0,0,0,0,0,0,0,0,0,0,0,0,0)';
      BIDIRECTIONAL='TRUE';
      INPUT_LOAD='(-0.01,0.01)';
      OUTPUT_LOAD='(1.0,-1.0)';
    'DDR0_DQ'<55>:
      PIN_NUMBER='(0,0,P29,0,0,0,0,0,0,0,0,0,0,0,0,0,0,0,0,0,0,0,0,0,0,0,0,0,0,0)';
      BIDIRECTIONAL='TRUE';
      INPUT_LOAD='(-0.01,0.01)';
      OUTPUT_LOAD='(1.0,-1.0)';
    'DDR0_DQ'<54>:
      PIN_NUMBER='(0,0,K29,0,0,0,0,0,0,0,0,0,0,0,0,0,0,0,0,0,0,0,0,0,0,0,0,0,0,0)';
      BIDIRECTIONAL='TRUE';
      INPUT_LOAD='(-0.01,0.01)';
      OUTPUT_LOAD='(1.0,-1.0)';
    'DDR0_DQ'<53>:
      PIN_NUMBER='(0,0,N32,0,0,0,0,0,0,0,0,0,0,0,0,0,0,0,0,0,0,0,0,0,0,0,0,0,0,0)';
      BIDIRECTIONAL='TRUE';
      INPUT_LOAD='(-0.01,0.01)';
      OUTPUT_LOAD='(1.0,-1.0)';
    'DDR0_DQ'<52>:
      PIN_NUMBER='(0,0,L32,0,0,0,0,0,0,0,0,0,0,0,0,0,0,0,0,0,0,0,0,0,0,0,0,0,0,0)';
      BIDIRECTIONAL='TRUE';
      INPUT_LOAD='(-0.01,0.01)';
      OUTPUT_LOAD='(1.0,-1.0)';
    'DDR0_DQ'<51>:
      PIN_NUMBER='(0,0,N28,0,0,0,0,0,0,0,0,0,0,0,0,0,0,0,0,0,0,0,0,0,0,0,0,0,0,0)';
      BIDIRECTIONAL='TRUE';
      INPUT_LOAD='(-0.01,0.01)';
      OUTPUT_LOAD='(1.0,-1.0)';
    'DDR0_DQ'<50>:
      PIN_NUMBER='(0,0,L28,0,0,0,0,0,0,0,0,0,0,0,0,0,0,0,0,0,0,0,0,0,0,0,0,0,0,0)';
      BIDIRECTIONAL='TRUE';
      INPUT_LOAD='(-0.01,0.01)';
      OUTPUT_LOAD='(1.0,-1.0)';
    'DDR0_DQ'<49>:
      PIN_NUMBER='(0,0,P31,0,0,0,0,0,0,0,0,0,0,0,0,0,0,0,0,0,0,0,0,0,0,0,0,0,0,0)';
      BIDIRECTIONAL='TRUE';
      INPUT_LOAD='(-0.01,0.01)';
      OUTPUT_LOAD='(1.0,-1.0)';
    'DDR0_DQ'<48>:
      PIN_NUMBER='(0,0,K31,0,0,0,0,0,0,0,0,0,0,0,0,0,0,0,0,0,0,0,0,0,0,0,0,0,0,0)';
      BIDIRECTIONAL='TRUE';
      INPUT_LOAD='(-0.01,0.01)';
      OUTPUT_LOAD='(1.0,-1.0)';
    'DDR0_DQ'<47>:
      PIN_NUMBER='(0,0,P35,0,0,0,0,0,0,0,0,0,0,0,0,0,0,0,0,0,0,0,0,0,0,0,0,0,0,0)';
      BIDIRECTIONAL='TRUE';
      INPUT_LOAD='(-0.01,0.01)';
      OUTPUT_LOAD='(1.0,-1.0)';
    'DDR0_DQ'<46>:
      PIN_NUMBER='(0,0,K35,0,0,0,0,0,0,0,0,0,0,0,0,0,0,0,0,0,0,0,0,0,0,0,0,0,0,0)';
      BIDIRECTIONAL='TRUE';
      INPUT_LOAD='(-0.01,0.01)';
      OUTPUT_LOAD='(1.0,-1.0)';
    'DDR0_DQ'<45>:
      PIN_NUMBER='(0,0,N38,0,0,0,0,0,0,0,0,0,0,0,0,0,0,0,0,0,0,0,0,0,0,0,0,0,0,0)';
      BIDIRECTIONAL='TRUE';
      INPUT_LOAD='(-0.01,0.01)';
      OUTPUT_LOAD='(1.0,-1.0)';
    'DDR0_DQ'<44>:
      PIN_NUMBER='(0,0,L38,0,0,0,0,0,0,0,0,0,0,0,0,0,0,0,0,0,0,0,0,0,0,0,0,0,0,0)';
      BIDIRECTIONAL='TRUE';
      INPUT_LOAD='(-0.01,0.01)';
      OUTPUT_LOAD='(1.0,-1.0)';
    'DDR0_DQ'<43>:
      PIN_NUMBER='(0,0,N34,0,0,0,0,0,0,0,0,0,0,0,0,0,0,0,0,0,0,0,0,0,0,0,0,0,0,0)';
      BIDIRECTIONAL='TRUE';
      INPUT_LOAD='(-0.01,0.01)';
      OUTPUT_LOAD='(1.0,-1.0)';
    'DDR0_DQ'<42>:
      PIN_NUMBER='(0,0,L34,0,0,0,0,0,0,0,0,0,0,0,0,0,0,0,0,0,0,0,0,0,0,0,0,0,0,0)';
      BIDIRECTIONAL='TRUE';
      INPUT_LOAD='(-0.01,0.01)';
      OUTPUT_LOAD='(1.0,-1.0)';
    'DDR0_DQ'<41>:
      PIN_NUMBER='(0,0,P37,0,0,0,0,0,0,0,0,0,0,0,0,0,0,0,0,0,0,0,0,0,0,0,0,0,0,0)';
      BIDIRECTIONAL='TRUE';
      INPUT_LOAD='(-0.01,0.01)';
      OUTPUT_LOAD='(1.0,-1.0)';
    'DDR0_DQ'<40>:
      PIN_NUMBER='(0,0,K37,0,0,0,0,0,0,0,0,0,0,0,0,0,0,0,0,0,0,0,0,0,0,0,0,0,0,0)';
      BIDIRECTIONAL='TRUE';
      INPUT_LOAD='(-0.01,0.01)';
      OUTPUT_LOAD='(1.0,-1.0)';
    'DDR0_DQ'<39>:
      PIN_NUMBER='(0,0,F39,0,0,0,0,0,0,0,0,0,0,0,0,0,0,0,0,0,0,0,0,0,0,0,0,0,0,0)';
      BIDIRECTIONAL='TRUE';
      INPUT_LOAD='(-0.01,0.01)';
      OUTPUT_LOAD='(1.0,-1.0)';
    'DDR0_DQ'<38>:
      PIN_NUMBER='(0,0,B39,0,0,0,0,0,0,0,0,0,0,0,0,0,0,0,0,0,0,0,0,0,0,0,0,0,0,0)';
      BIDIRECTIONAL='TRUE';
      INPUT_LOAD='(-0.01,0.01)';
      OUTPUT_LOAD='(1.0,-1.0)';
    'DDR0_DQ'<37>:
      PIN_NUMBER='(0,0,F41,0,0,0,0,0,0,0,0,0,0,0,0,0,0,0,0,0,0,0,0,0,0,0,0,0,0,0)';
      BIDIRECTIONAL='TRUE';
      INPUT_LOAD='(-0.01,0.01)';
      OUTPUT_LOAD='(1.0,-1.0)';
    'DDR0_DQ'<36>:
      PIN_NUMBER='(0,0,E42,0,0,0,0,0,0,0,0,0,0,0,0,0,0,0,0,0,0,0,0,0,0,0,0,0,0,0)';
      BIDIRECTIONAL='TRUE';
      INPUT_LOAD='(-0.01,0.01)';
      OUTPUT_LOAD='(1.0,-1.0)';
    'DDR0_DQ'<35>:
      PIN_NUMBER='(0,0,E38,0,0,0,0,0,0,0,0,0,0,0,0,0,0,0,0,0,0,0,0,0,0,0,0,0,0,0)';
      BIDIRECTIONAL='TRUE';
      INPUT_LOAD='(-0.01,0.01)';
      OUTPUT_LOAD='(1.0,-1.0)';
    'DDR0_DQ'<34>:
      PIN_NUMBER='(0,0,C38,0,0,0,0,0,0,0,0,0,0,0,0,0,0,0,0,0,0,0,0,0,0,0,0,0,0,0)';
      BIDIRECTIONAL='TRUE';
      INPUT_LOAD='(-0.01,0.01)';
      OUTPUT_LOAD='(1.0,-1.0)';
    'DDR0_DQ'<33>:
      PIN_NUMBER='(0,0,B41,0,0,0,0,0,0,0,0,0,0,0,0,0,0,0,0,0,0,0,0,0,0,0,0,0,0,0)';
      BIDIRECTIONAL='TRUE';
      INPUT_LOAD='(-0.01,0.01)';
      OUTPUT_LOAD='(1.0,-1.0)';
    'DDR0_DQ'<32>:
      PIN_NUMBER='(0,0,C42,0,0,0,0,0,0,0,0,0,0,0,0,0,0,0,0,0,0,0,0,0,0,0,0,0,0,0)';
      BIDIRECTIONAL='TRUE';
      INPUT_LOAD='(-0.01,0.01)';
      OUTPUT_LOAD='(1.0,-1.0)';
    'DDR0_DQ'<31>:
      PIN_NUMBER='(0,0,R74,0,0,0,0,0,0,0,0,0,0,0,0,0,0,0,0,0,0,0,0,0,0,0,0,0,0,0)';
      BIDIRECTIONAL='TRUE';
      INPUT_LOAD='(-0.01,0.01)';
      OUTPUT_LOAD='(1.0,-1.0)';
    'DDR0_DQ'<30>:
      PIN_NUMBER='(0,0,L74,0,0,0,0,0,0,0,0,0,0,0,0,0,0,0,0,0,0,0,0,0,0,0,0,0,0,0)';
      BIDIRECTIONAL='TRUE';
      INPUT_LOAD='(-0.01,0.01)';
      OUTPUT_LOAD='(1.0,-1.0)';
    'DDR0_DQ'<29>:
      PIN_NUMBER='(0,0,P77,0,0,0,0,0,0,0,0,0,0,0,0,0,0,0,0,0,0,0,0,0,0,0,0,0,0,0)';
      BIDIRECTIONAL='TRUE';
      INPUT_LOAD='(-0.01,0.01)';
      OUTPUT_LOAD='(1.0,-1.0)';
    'DDR0_DQ'<28>:
      PIN_NUMBER='(0,0,M77,0,0,0,0,0,0,0,0,0,0,0,0,0,0,0,0,0,0,0,0,0,0,0,0,0,0,0)';
      BIDIRECTIONAL='TRUE';
      INPUT_LOAD='(-0.01,0.01)';
      OUTPUT_LOAD='(1.0,-1.0)';
    'DDR0_DQ'<27>:
      PIN_NUMBER='(0,0,P73,0,0,0,0,0,0,0,0,0,0,0,0,0,0,0,0,0,0,0,0,0,0,0,0,0,0,0)';
      BIDIRECTIONAL='TRUE';
      INPUT_LOAD='(-0.01,0.01)';
      OUTPUT_LOAD='(1.0,-1.0)';
    'DDR0_DQ'<26>:
      PIN_NUMBER='(0,0,M73,0,0,0,0,0,0,0,0,0,0,0,0,0,0,0,0,0,0,0,0,0,0,0,0,0,0,0)';
      BIDIRECTIONAL='TRUE';
      INPUT_LOAD='(-0.01,0.01)';
      OUTPUT_LOAD='(1.0,-1.0)';
    'DDR0_DQ'<25>:
      PIN_NUMBER='(0,0,R76,0,0,0,0,0,0,0,0,0,0,0,0,0,0,0,0,0,0,0,0,0,0,0,0,0,0,0)';
      BIDIRECTIONAL='TRUE';
      INPUT_LOAD='(-0.01,0.01)';
      OUTPUT_LOAD='(1.0,-1.0)';
    'DDR0_DQ'<24>:
      PIN_NUMBER='(0,0,L76,0,0,0,0,0,0,0,0,0,0,0,0,0,0,0,0,0,0,0,0,0,0,0,0,0,0,0)';
      BIDIRECTIONAL='TRUE';
      INPUT_LOAD='(-0.01,0.01)';
      OUTPUT_LOAD='(1.0,-1.0)';
    'DDR0_DQ'<23>:
      PIN_NUMBER='(0,0,N80,0,0,0,0,0,0,0,0,0,0,0,0,0,0,0,0,0,0,0,0,0,0,0,0,0,0,0)';
      BIDIRECTIONAL='TRUE';
      INPUT_LOAD='(-0.01,0.01)';
      OUTPUT_LOAD='(1.0,-1.0)';
    'DDR0_DQ'<22>:
      PIN_NUMBER='(0,0,R82,0,0,0,0,0,0,0,0,0,0,0,0,0,0,0,0,0,0,0,0,0,0,0,0,0,0,0)';
      BIDIRECTIONAL='TRUE';
      INPUT_LOAD='(-0.01,0.01)';
      OUTPUT_LOAD='(1.0,-1.0)';
    'DDR0_DQ'<21>:
      PIN_NUMBER='(0,0,V79,0,0,0,0,0,0,0,0,0,0,0,0,0,0,0,0,0,0,0,0,0,0,0,0,0,0,0)';
      BIDIRECTIONAL='TRUE';
      INPUT_LOAD='(-0.01,0.01)';
      OUTPUT_LOAD='(1.0,-1.0)';
    'DDR0_DQ'<20>:
      PIN_NUMBER='(0,0,W80,0,0,0,0,0,0,0,0,0,0,0,0,0,0,0,0,0,0,0,0,0,0,0,0,0,0,0)';
      BIDIRECTIONAL='TRUE';
      INPUT_LOAD='(-0.01,0.01)';
      OUTPUT_LOAD='(1.0,-1.0)';
    'DDR0_DQ'<19>:
      PIN_NUMBER='(0,0,M81,0,0,0,0,0,0,0,0,0,0,0,0,0,0,0,0,0,0,0,0,0,0,0,0,0,0,0)';
      BIDIRECTIONAL='TRUE';
      INPUT_LOAD='(-0.01,0.01)';
      OUTPUT_LOAD='(1.0,-1.0)';
    'DDR0_DQ'<18>:
      PIN_NUMBER='(0,0,N82,0,0,0,0,0,0,0,0,0,0,0,0,0,0,0,0,0,0,0,0,0,0,0,0,0,0,0)';
      BIDIRECTIONAL='TRUE';
      INPUT_LOAD='(-0.01,0.01)';
      OUTPUT_LOAD='(1.0,-1.0)';
    'DDR0_DQ'<17>:
      PIN_NUMBER='(0,0,T79,0,0,0,0,0,0,0,0,0,0,0,0,0,0,0,0,0,0,0,0,0,0,0,0,0,0,0)';
      BIDIRECTIONAL='TRUE';
      INPUT_LOAD='(-0.01,0.01)';
      OUTPUT_LOAD='(1.0,-1.0)';
    'DDR0_DQ'<16>:
      PIN_NUMBER='(0,0,V81,0,0,0,0,0,0,0,0,0,0,0,0,0,0,0,0,0,0,0,0,0,0,0,0,0,0,0)';
      BIDIRECTIONAL='TRUE';
      INPUT_LOAD='(-0.01,0.01)';
      OUTPUT_LOAD='(1.0,-1.0)';
    'DDR0_DQ'<15>:
      PIN_NUMBER='(0,0,N84,0,0,0,0,0,0,0,0,0,0,0,0,0,0,0,0,0,0,0,0,0,0,0,0,0,0,0)';
      BIDIRECTIONAL='TRUE';
      INPUT_LOAD='(-0.01,0.01)';
      OUTPUT_LOAD='(1.0,-1.0)';
    'DDR0_DQ'<14>:
      PIN_NUMBER='(0,0,N86,0,0,0,0,0,0,0,0,0,0,0,0,0,0,0,0,0,0,0,0,0,0,0,0,0,0,0)';
      BIDIRECTIONAL='TRUE';
      INPUT_LOAD='(-0.01,0.01)';
      OUTPUT_LOAD='(1.0,-1.0)';
    'DDR0_DQ'<13>:
      PIN_NUMBER='(0,0,AA84,0,0,0,0,0,0,0,0,0,0,0,0,0,0,0,0,0,0,0,0,0,0,0,0,0,0,0)';
      BIDIRECTIONAL='TRUE';
      INPUT_LOAD='(-0.01,0.01)';
      OUTPUT_LOAD='(1.0,-1.0)';
    'DDR0_DQ'<12>:
      PIN_NUMBER='(0,0,AA86,0,0,0,0,0,0,0,0,0,0,0,0,0,0,0,0,0,0,0,0,0,0,0,0,0,0,0)';
      BIDIRECTIONAL='TRUE';
      INPUT_LOAD='(-0.01,0.01)';
      OUTPUT_LOAD='(1.0,-1.0)';
    'DDR0_DQ'<11>:
      PIN_NUMBER='(0,0,L84,0,0,0,0,0,0,0,0,0,0,0,0,0,0,0,0,0,0,0,0,0,0,0,0,0,0,0)';
      BIDIRECTIONAL='TRUE';
      INPUT_LOAD='(-0.01,0.01)';
      OUTPUT_LOAD='(1.0,-1.0)';
    'DDR0_DQ'<10>:
      PIN_NUMBER='(0,0,L86,0,0,0,0,0,0,0,0,0,0,0,0,0,0,0,0,0,0,0,0,0,0,0,0,0,0,0)';
      BIDIRECTIONAL='TRUE';
      INPUT_LOAD='(-0.01,0.01)';
      OUTPUT_LOAD='(1.0,-1.0)';
    'DDR0_DQ'<9>:
      PIN_NUMBER='(0,0,W84,0,0,0,0,0,0,0,0,0,0,0,0,0,0,0,0,0,0,0,0,0,0,0,0,0,0,0)';
      BIDIRECTIONAL='TRUE';
      INPUT_LOAD='(-0.01,0.01)';
      OUTPUT_LOAD='(1.0,-1.0)';
    'DDR0_DQ'<8>:
      PIN_NUMBER='(0,0,W86,0,0,0,0,0,0,0,0,0,0,0,0,0,0,0,0,0,0,0,0,0,0,0,0,0,0,0)';
      BIDIRECTIONAL='TRUE';
      INPUT_LOAD='(-0.01,0.01)';
      OUTPUT_LOAD='(1.0,-1.0)';
    'DDR0_DQ'<7>:
      PIN_NUMBER='(0,0,AG84,0,0,0,0,0,0,0,0,0,0,0,0,0,0,0,0,0,0,0,0,0,0,0,0,0,0,0)';
      BIDIRECTIONAL='TRUE';
      INPUT_LOAD='(-0.01,0.01)';
      OUTPUT_LOAD='(1.0,-1.0)';
    'DDR0_DQ'<6>:
      PIN_NUMBER='(0,0,AG86,0,0,0,0,0,0,0,0,0,0,0,0,0,0,0,0,0,0,0,0,0,0,0,0,0,0,0)';
      BIDIRECTIONAL='TRUE';
      INPUT_LOAD='(-0.01,0.01)';
      OUTPUT_LOAD='(1.0,-1.0)';
    'DDR0_DQ'<5>:
      PIN_NUMBER='(0,0,AR84,0,0,0,0,0,0,0,0,0,0,0,0,0,0,0,0,0,0,0,0,0,0,0,0,0,0,0)';
      BIDIRECTIONAL='TRUE';
      INPUT_LOAD='(-0.01,0.01)';
      OUTPUT_LOAD='(1.0,-1.0)';
    'DDR0_DQ'<4>:
      PIN_NUMBER='(0,0,AR86,0,0,0,0,0,0,0,0,0,0,0,0,0,0,0,0,0,0,0,0,0,0,0,0,0,0,0)';
      BIDIRECTIONAL='TRUE';
      INPUT_LOAD='(-0.01,0.01)';
      OUTPUT_LOAD='(1.0,-1.0)';
    'DDR0_DQ'<3>:
      PIN_NUMBER='(0,0,AE84,0,0,0,0,0,0,0,0,0,0,0,0,0,0,0,0,0,0,0,0,0,0,0,0,0,0,0)';
      BIDIRECTIONAL='TRUE';
      INPUT_LOAD='(-0.01,0.01)';
      OUTPUT_LOAD='(1.0,-1.0)';
    'DDR0_DQ'<2>:
      PIN_NUMBER='(0,0,AE86,0,0,0,0,0,0,0,0,0,0,0,0,0,0,0,0,0,0,0,0,0,0,0,0,0,0,0)';
      BIDIRECTIONAL='TRUE';
      INPUT_LOAD='(-0.01,0.01)';
      OUTPUT_LOAD='(1.0,-1.0)';
    'DDR0_DQ'<1>:
      PIN_NUMBER='(0,0,AN84,0,0,0,0,0,0,0,0,0,0,0,0,0,0,0,0,0,0,0,0,0,0,0,0,0,0,0)';
      BIDIRECTIONAL='TRUE';
      INPUT_LOAD='(-0.01,0.01)';
      OUTPUT_LOAD='(1.0,-1.0)';
    'DDR0_DQ'<0>:
      PIN_NUMBER='(0,0,AN86,0,0,0,0,0,0,0,0,0,0,0,0,0,0,0,0,0,0,0,0,0,0,0,0,0,0,0)';
      BIDIRECTIONAL='TRUE';
      INPUT_LOAD='(-0.01,0.01)';
      OUTPUT_LOAD='(1.0,-1.0)';
    'DDR0_DQS_DN'<17>:
      PIN_NUMBER='(0,0,AB67,0,0,0,0,0,0,0,0,0,0,0,0,0,0,0,0,0,0,0,0,0,0,0,0,0,0,0)';
      BIDIRECTIONAL='TRUE';
      INPUT_LOAD='(-0.01,0.01)';
      OUTPUT_LOAD='(1.0,-1.0)';
    'DDR0_DQS_DN'<16>:
      PIN_NUMBER='(0,0,J24,0,0,0,0,0,0,0,0,0,0,0,0,0,0,0,0,0,0,0,0,0,0,0,0,0,0,0)';
      BIDIRECTIONAL='TRUE';
      INPUT_LOAD='(-0.01,0.01)';
      OUTPUT_LOAD='(1.0,-1.0)';
    'DDR0_DQS_DN'<15>:
      PIN_NUMBER='(0,0,J30,0,0,0,0,0,0,0,0,0,0,0,0,0,0,0,0,0,0,0,0,0,0,0,0,0,0,0)';
      BIDIRECTIONAL='TRUE';
      INPUT_LOAD='(-0.01,0.01)';
      OUTPUT_LOAD='(1.0,-1.0)';
    'DDR0_DQS_DN'<14>:
      PIN_NUMBER='(0,0,J36,0,0,0,0,0,0,0,0,0,0,0,0,0,0,0,0,0,0,0,0,0,0,0,0,0,0,0)';
      BIDIRECTIONAL='TRUE';
      INPUT_LOAD='(-0.01,0.01)';
      OUTPUT_LOAD='(1.0,-1.0)';
    'DDR0_DQS_DN'<13>:
      PIN_NUMBER='(0,0,A40,0,0,0,0,0,0,0,0,0,0,0,0,0,0,0,0,0,0,0,0,0,0,0,0,0,0,0)';
      BIDIRECTIONAL='TRUE';
      INPUT_LOAD='(-0.01,0.01)';
      OUTPUT_LOAD='(1.0,-1.0)';
    'DDR0_DQS_DN'<12>:
      PIN_NUMBER='(0,0,K75,0,0,0,0,0,0,0,0,0,0,0,0,0,0,0,0,0,0,0,0,0,0,0,0,0,0,0)';
      BIDIRECTIONAL='TRUE';
      INPUT_LOAD='(-0.01,0.01)';
      OUTPUT_LOAD='(1.0,-1.0)';
    'DDR0_DQS_DN'<11>:
      PIN_NUMBER='(0,0,U82,0,0,0,0,0,0,0,0,0,0,0,0,0,0,0,0,0,0,0,0,0,0,0,0,0,0,0)';
      BIDIRECTIONAL='TRUE';
      INPUT_LOAD='(-0.01,0.01)';
      OUTPUT_LOAD='(1.0,-1.0)';
    'DDR0_DQS_DN'<10>:
      PIN_NUMBER='(0,0,U84,0,0,0,0,0,0,0,0,0,0,0,0,0,0,0,0,0,0,0,0,0,0,0,0,0,0,0)';
      BIDIRECTIONAL='TRUE';
      INPUT_LOAD='(-0.01,0.01)';
      OUTPUT_LOAD='(1.0,-1.0)';
    'DDR0_DQS_DN'<9>:
      PIN_NUMBER='(0,0,AL84,0,0,0,0,0,0,0,0,0,0,0,0,0,0,0,0,0,0,0,0,0,0,0,0,0,0,0)';
      BIDIRECTIONAL='TRUE';
      INPUT_LOAD='(-0.01,0.01)';
      OUTPUT_LOAD='(1.0,-1.0)';
    'DDR0_DQS_DN'<8>:
      PIN_NUMBER='(0,0,AH67,0,0,0,0,0,0,0,0,0,0,0,0,0,0,0,0,0,0,0,0,0,0,0,0,0,0,0)';
      BIDIRECTIONAL='TRUE';
      INPUT_LOAD='(-0.01,0.01)';
      OUTPUT_LOAD='(1.0,-1.0)';
    'DDR0_DQS_DN'<7>:
      PIN_NUMBER='(0,0,N24,0,0,0,0,0,0,0,0,0,0,0,0,0,0,0,0,0,0,0,0,0,0,0,0,0,0,0)';
      BIDIRECTIONAL='TRUE';
      INPUT_LOAD='(-0.01,0.01)';
      OUTPUT_LOAD='(1.0,-1.0)';
    'DDR0_DQS_DN'<6>:
      PIN_NUMBER='(0,0,R30,0,0,0,0,0,0,0,0,0,0,0,0,0,0,0,0,0,0,0,0,0,0,0,0,0,0,0)';
      BIDIRECTIONAL='TRUE';
      INPUT_LOAD='(-0.01,0.01)';
      OUTPUT_LOAD='(1.0,-1.0)';
    'DDR0_DQS_DN'<5>:
      PIN_NUMBER='(0,0,R36,0,0,0,0,0,0,0,0,0,0,0,0,0,0,0,0,0,0,0,0,0,0,0,0,0,0,0)';
      BIDIRECTIONAL='TRUE';
      INPUT_LOAD='(-0.01,0.01)';
      OUTPUT_LOAD='(1.0,-1.0)';
    'DDR0_DQS_DN'<4>:
      PIN_NUMBER='(0,0,G40,0,0,0,0,0,0,0,0,0,0,0,0,0,0,0,0,0,0,0,0,0,0,0,0,0,0,0)';
      BIDIRECTIONAL='TRUE';
      INPUT_LOAD='(-0.01,0.01)';
      OUTPUT_LOAD='(1.0,-1.0)';
    'DDR0_DQS_DN'<3>:
      PIN_NUMBER='(0,0,T75,0,0,0,0,0,0,0,0,0,0,0,0,0,0,0,0,0,0,0,0,0,0,0,0,0,0,0)';
      BIDIRECTIONAL='TRUE';
      INPUT_LOAD='(-0.01,0.01)';
      OUTPUT_LOAD='(1.0,-1.0)';
    'DDR0_DQS_DN'<2>:
      PIN_NUMBER='(0,0,P79,0,0,0,0,0,0,0,0,0,0,0,0,0,0,0,0,0,0,0,0,0,0,0,0,0,0,0)';
      BIDIRECTIONAL='TRUE';
      INPUT_LOAD='(-0.01,0.01)';
      OUTPUT_LOAD='(1.0,-1.0)';
    'DDR0_DQS_DN'<1>:
      PIN_NUMBER='(0,0,R84,0,0,0,0,0,0,0,0,0,0,0,0,0,0,0,0,0,0,0,0,0,0,0,0,0,0,0)';
      BIDIRECTIONAL='TRUE';
      INPUT_LOAD='(-0.01,0.01)';
      OUTPUT_LOAD='(1.0,-1.0)';
    'DDR0_DQS_DN'<0>:
      PIN_NUMBER='(0,0,AJ84,0,0,0,0,0,0,0,0,0,0,0,0,0,0,0,0,0,0,0,0,0,0,0,0,0,0,0)';
      BIDIRECTIONAL='TRUE';
      INPUT_LOAD='(-0.01,0.01)';
      OUTPUT_LOAD='(1.0,-1.0)';
    'DDR0_DQS_DP'<17>:
      PIN_NUMBER='(0,0,AD67,0,0,0,0,0,0,0,0,0,0,0,0,0,0,0,0,0,0,0,0,0,0,0,0,0,0,0)';
      BIDIRECTIONAL='TRUE';
      INPUT_LOAD='(-0.01,0.01)';
      OUTPUT_LOAD='(1.0,-1.0)';
    'DDR0_DQS_DP'<16>:
      PIN_NUMBER='(0,0,L24,0,0,0,0,0,0,0,0,0,0,0,0,0,0,0,0,0,0,0,0,0,0,0,0,0,0,0)';
      BIDIRECTIONAL='TRUE';
      INPUT_LOAD='(-0.01,0.01)';
      OUTPUT_LOAD='(1.0,-1.0)';
    'DDR0_DQS_DP'<15>:
      PIN_NUMBER='(0,0,L30,0,0,0,0,0,0,0,0,0,0,0,0,0,0,0,0,0,0,0,0,0,0,0,0,0,0,0)';
      BIDIRECTIONAL='TRUE';
      INPUT_LOAD='(-0.01,0.01)';
      OUTPUT_LOAD='(1.0,-1.0)';
    'DDR0_DQS_DP'<14>:
      PIN_NUMBER='(0,0,L36,0,0,0,0,0,0,0,0,0,0,0,0,0,0,0,0,0,0,0,0,0,0,0,0,0,0,0)';
      BIDIRECTIONAL='TRUE';
      INPUT_LOAD='(-0.01,0.01)';
      OUTPUT_LOAD='(1.0,-1.0)';
    'DDR0_DQS_DP'<13>:
      PIN_NUMBER='(0,0,C40,0,0,0,0,0,0,0,0,0,0,0,0,0,0,0,0,0,0,0,0,0,0,0,0,0,0,0)';
      BIDIRECTIONAL='TRUE';
      INPUT_LOAD='(-0.01,0.01)';
      OUTPUT_LOAD='(1.0,-1.0)';
    'DDR0_DQS_DP'<12>:
      PIN_NUMBER='(0,0,M75,0,0,0,0,0,0,0,0,0,0,0,0,0,0,0,0,0,0,0,0,0,0,0,0,0,0,0)';
      BIDIRECTIONAL='TRUE';
      INPUT_LOAD='(-0.01,0.01)';
      OUTPUT_LOAD='(1.0,-1.0)';
    'DDR0_DQS_DP'<11>:
      PIN_NUMBER='(0,0,T81,0,0,0,0,0,0,0,0,0,0,0,0,0,0,0,0,0,0,0,0,0,0,0,0,0,0,0)';
      BIDIRECTIONAL='TRUE';
      INPUT_LOAD='(-0.01,0.01)';
      OUTPUT_LOAD='(1.0,-1.0)';
    'DDR0_DQS_DP'<10>:
      PIN_NUMBER='(0,0,V85,0,0,0,0,0,0,0,0,0,0,0,0,0,0,0,0,0,0,0,0,0,0,0,0,0,0,0)';
      BIDIRECTIONAL='TRUE';
      INPUT_LOAD='(-0.01,0.01)';
      OUTPUT_LOAD='(1.0,-1.0)';
    'DDR0_DQS_DP'<9>:
      PIN_NUMBER='(0,0,AM85,0,0,0,0,0,0,0,0,0,0,0,0,0,0,0,0,0,0,0,0,0,0,0,0,0,0,0)';
      BIDIRECTIONAL='TRUE';
      INPUT_LOAD='(-0.01,0.01)';
      OUTPUT_LOAD='(1.0,-1.0)';
    'DDR0_DQS_DP'<8>:
      PIN_NUMBER='(0,0,AF67,0,0,0,0,0,0,0,0,0,0,0,0,0,0,0,0,0,0,0,0,0,0,0,0,0,0,0)';
      BIDIRECTIONAL='TRUE';
      INPUT_LOAD='(-0.01,0.01)';
      OUTPUT_LOAD='(1.0,-1.0)';
    'DDR0_DQS_DP'<7>:
      PIN_NUMBER='(0,0,R24,0,0,0,0,0,0,0,0,0,0,0,0,0,0,0,0,0,0,0,0,0,0,0,0,0,0,0)';
      BIDIRECTIONAL='TRUE';
      INPUT_LOAD='(-0.01,0.01)';
      OUTPUT_LOAD='(1.0,-1.0)';
    'DDR0_DQS_DP'<6>:
      PIN_NUMBER='(0,0,N30,0,0,0,0,0,0,0,0,0,0,0,0,0,0,0,0,0,0,0,0,0,0,0,0,0,0,0)';
      BIDIRECTIONAL='TRUE';
      INPUT_LOAD='(-0.01,0.01)';
      OUTPUT_LOAD='(1.0,-1.0)';
    'DDR0_DQS_DP'<5>:
      PIN_NUMBER='(0,0,N36,0,0,0,0,0,0,0,0,0,0,0,0,0,0,0,0,0,0,0,0,0,0,0,0,0,0,0)';
      BIDIRECTIONAL='TRUE';
      INPUT_LOAD='(-0.01,0.01)';
      OUTPUT_LOAD='(1.0,-1.0)';
    'DDR0_DQS_DP'<4>:
      PIN_NUMBER='(0,0,E40,0,0,0,0,0,0,0,0,0,0,0,0,0,0,0,0,0,0,0,0,0,0,0,0,0,0,0)';
      BIDIRECTIONAL='TRUE';
      INPUT_LOAD='(-0.01,0.01)';
      OUTPUT_LOAD='(1.0,-1.0)';
    'DDR0_DQS_DP'<3>:
      PIN_NUMBER='(0,0,P75,0,0,0,0,0,0,0,0,0,0,0,0,0,0,0,0,0,0,0,0,0,0,0,0,0,0,0)';
      BIDIRECTIONAL='TRUE';
      INPUT_LOAD='(-0.01,0.01)';
      OUTPUT_LOAD='(1.0,-1.0)';
    'DDR0_DQS_DP'<2>:
      PIN_NUMBER='(0,0,R80,0,0,0,0,0,0,0,0,0,0,0,0,0,0,0,0,0,0,0,0,0,0,0,0,0,0,0)';
      BIDIRECTIONAL='TRUE';
      INPUT_LOAD='(-0.01,0.01)';
      OUTPUT_LOAD='(1.0,-1.0)';
    'DDR0_DQS_DP'<1>:
      PIN_NUMBER='(0,0,P85,0,0,0,0,0,0,0,0,0,0,0,0,0,0,0,0,0,0,0,0,0,0,0,0,0,0,0)';
      BIDIRECTIONAL='TRUE';
      INPUT_LOAD='(-0.01,0.01)';
      OUTPUT_LOAD='(1.0,-1.0)';
    'DDR0_DQS_DP'<0>:
      PIN_NUMBER='(0,0,AH85,0,0,0,0,0,0,0,0,0,0,0,0,0,0,0,0,0,0,0,0,0,0,0,0,0,0,0)';
      BIDIRECTIONAL='TRUE';
      INPUT_LOAD='(-0.01,0.01)';
      OUTPUT_LOAD='(1.0,-1.0)';
    'DDR0_ECC'<7>:
      PIN_NUMBER='(0,0,AG66,0,0,0,0,0,0,0,0,0,0,0,0,0,0,0,0,0,0,0,0,0,0,0,0,0,0,0)';
      BIDIRECTIONAL='TRUE';
      INPUT_LOAD='(-0.01,0.01)';
      OUTPUT_LOAD='(1.0,-1.0)';
    'DDR0_ECC'<6>:
      PIN_NUMBER='(0,0,AC66,0,0,0,0,0,0,0,0,0,0,0,0,0,0,0,0,0,0,0,0,0,0,0,0,0,0,0)';
      BIDIRECTIONAL='TRUE';
      INPUT_LOAD='(-0.01,0.01)';
      OUTPUT_LOAD='(1.0,-1.0)';
    'DDR0_ECC'<5>:
      PIN_NUMBER='(0,0,AF69,0,0,0,0,0,0,0,0,0,0,0,0,0,0,0,0,0,0,0,0,0,0,0,0,0,0,0)';
      BIDIRECTIONAL='TRUE';
      INPUT_LOAD='(-0.01,0.01)';
      OUTPUT_LOAD='(1.0,-1.0)';
    'DDR0_ECC'<4>:
      PIN_NUMBER='(0,0,AD69,0,0,0,0,0,0,0,0,0,0,0,0,0,0,0,0,0,0,0,0,0,0,0,0,0,0,0)';
      BIDIRECTIONAL='TRUE';
      INPUT_LOAD='(-0.01,0.01)';
      OUTPUT_LOAD='(1.0,-1.0)';
    'DDR0_ECC'<3>:
      PIN_NUMBER='(0,0,AF65,0,0,0,0,0,0,0,0,0,0,0,0,0,0,0,0,0,0,0,0,0,0,0,0,0,0,0)';
      BIDIRECTIONAL='TRUE';
      INPUT_LOAD='(-0.01,0.01)';
      OUTPUT_LOAD='(1.0,-1.0)';
    'DDR0_ECC'<2>:
      PIN_NUMBER='(0,0,AD65,0,0,0,0,0,0,0,0,0,0,0,0,0,0,0,0,0,0,0,0,0,0,0,0,0,0,0)';
      BIDIRECTIONAL='TRUE';
      INPUT_LOAD='(-0.01,0.01)';
      OUTPUT_LOAD='(1.0,-1.0)';
    'DDR0_ECC'<1>:
      PIN_NUMBER='(0,0,AG68,0,0,0,0,0,0,0,0,0,0,0,0,0,0,0,0,0,0,0,0,0,0,0,0,0,0,0)';
      BIDIRECTIONAL='TRUE';
      INPUT_LOAD='(-0.01,0.01)';
      OUTPUT_LOAD='(1.0,-1.0)';
    'DDR0_ECC'<0>:
      PIN_NUMBER='(0,0,AC68,0,0,0,0,0,0,0,0,0,0,0,0,0,0,0,0,0,0,0,0,0,0,0,0,0,0,0)';
      BIDIRECTIONAL='TRUE';
      INPUT_LOAD='(-0.01,0.01)';
      OUTPUT_LOAD='(1.0,-1.0)';
    'DDR0_MA'<17>:
      PIN_NUMBER='(0,0,K47,0,0,0,0,0,0,0,0,0,0,0,0,0,0,0,0,0,0,0,0,0,0,0,0,0,0,0)';
      OUTPUT_LOAD='(1.0,-1.0)';
    'DDR0_MA'<16>:
      PIN_NUMBER='(0,0,D51,0,0,0,0,0,0,0,0,0,0,0,0,0,0,0,0,0,0,0,0,0,0,0,0,0,0,0)';
      OUTPUT_LOAD='(1.0,-1.0)';
    'DDR0_MA'<15>:
      PIN_NUMBER='(0,0,K49,0,0,0,0,0,0,0,0,0,0,0,0,0,0,0,0,0,0,0,0,0,0,0,0,0,0,0)';
      OUTPUT_LOAD='(1.0,-1.0)';
    'DDR0_MA'<14>:
      PIN_NUMBER='(0,0,F51,0,0,0,0,0,0,0,0,0,0,0,0,0,0,0,0,0,0,0,0,0,0,0,0,0,0,0)';
      OUTPUT_LOAD='(1.0,-1.0)';
    'DDR0_MA'<13>:
      PIN_NUMBER='(0,0,J48,0,0,0,0,0,0,0,0,0,0,0,0,0,0,0,0,0,0,0,0,0,0,0,0,0,0,0)';
      OUTPUT_LOAD='(1.0,-1.0)';
    'DDR0_MA'<12>:
      PIN_NUMBER='(0,0,J64,0,0,0,0,0,0,0,0,0,0,0,0,0,0,0,0,0,0,0,0,0,0,0,0,0,0,0)';
      OUTPUT_LOAD='(1.0,-1.0)';
    'DDR0_MA'<11>:
      PIN_NUMBER='(0,0,G62,0,0,0,0,0,0,0,0,0,0,0,0,0,0,0,0,0,0,0,0,0,0,0,0,0,0,0)';
      OUTPUT_LOAD='(1.0,-1.0)';
    'DDR0_MA'<10>:
      PIN_NUMBER='(0,0,J54,0,0,0,0,0,0,0,0,0,0,0,0,0,0,0,0,0,0,0,0,0,0,0,0,0,0,0)';
      OUTPUT_LOAD='(1.0,-1.0)';
    'DDR0_MA'<9>:
      PIN_NUMBER='(0,0,F61,0,0,0,0,0,0,0,0,0,0,0,0,0,0,0,0,0,0,0,0,0,0,0,0,0,0,0)';
      OUTPUT_LOAD='(1.0,-1.0)';
    'DDR0_MA'<8>:
      PIN_NUMBER='(0,0,C60,0,0,0,0,0,0,0,0,0,0,0,0,0,0,0,0,0,0,0,0,0,0,0,0,0,0,0)';
      OUTPUT_LOAD='(1.0,-1.0)';
    'DDR0_MA'<7>:
      PIN_NUMBER='(0,0,G60,0,0,0,0,0,0,0,0,0,0,0,0,0,0,0,0,0,0,0,0,0,0,0,0,0,0,0)';
      OUTPUT_LOAD='(1.0,-1.0)';
    'DDR0_MA'<6>:
      PIN_NUMBER='(0,0,D59,0,0,0,0,0,0,0,0,0,0,0,0,0,0,0,0,0,0,0,0,0,0,0,0,0,0,0)';
      OUTPUT_LOAD='(1.0,-1.0)';
    'DDR0_MA'<5>:
      PIN_NUMBER='(0,0,F59,0,0,0,0,0,0,0,0,0,0,0,0,0,0,0,0,0,0,0,0,0,0,0,0,0,0,0)';
      OUTPUT_LOAD='(1.0,-1.0)';
    'DDR0_MA'<4>:
      PIN_NUMBER='(0,0,G58,0,0,0,0,0,0,0,0,0,0,0,0,0,0,0,0,0,0,0,0,0,0,0,0,0,0,0)';
      OUTPUT_LOAD='(1.0,-1.0)';
    'DDR0_MA'<3>:
      PIN_NUMBER='(0,0,C58,0,0,0,0,0,0,0,0,0,0,0,0,0,0,0,0,0,0,0,0,0,0,0,0,0,0,0)';
      OUTPUT_LOAD='(1.0,-1.0)';
    'DDR0_MA'<2>:
      PIN_NUMBER='(0,0,D57,0,0,0,0,0,0,0,0,0,0,0,0,0,0,0,0,0,0,0,0,0,0,0,0,0,0,0)';
      OUTPUT_LOAD='(1.0,-1.0)';
    'DDR0_MA'<1>:
      PIN_NUMBER='(0,0,F57,0,0,0,0,0,0,0,0,0,0,0,0,0,0,0,0,0,0,0,0,0,0,0,0,0,0,0)';
      OUTPUT_LOAD='(1.0,-1.0)';
    'DDR0_MA'<0>:
      PIN_NUMBER='(0,0,F53,0,0,0,0,0,0,0,0,0,0,0,0,0,0,0,0,0,0,0,0,0,0,0,0,0,0,0)';
      OUTPUT_LOAD='(1.0,-1.0)';
    'DDR0_ODT'<3>:
      PIN_NUMBER='(0,0,G48,0,0,0,0,0,0,0,0,0,0,0,0,0,0,0,0,0,0,0,0,0,0,0,0,0,0,0)';
      OUTPUT_LOAD='(1.0,-1.0)';
    'DDR0_ODT'<2>:
      PIN_NUMBER='(0,0,G50,0,0,0,0,0,0,0,0,0,0,0,0,0,0,0,0,0,0,0,0,0,0,0,0,0,0,0)';
      OUTPUT_LOAD='(1.0,-1.0)';
    'DDR0_ODT'<1>:
      PIN_NUMBER='(0,0,C48,0,0,0,0,0,0,0,0,0,0,0,0,0,0,0,0,0,0,0,0,0,0,0,0,0,0,0)';
      OUTPUT_LOAD='(1.0,-1.0)';
    'DDR0_ODT'<0>:
      PIN_NUMBER='(0,0,C50,0,0,0,0,0,0,0,0,0,0,0,0,0,0,0,0,0,0,0,0,0,0,0,0,0,0,0)';
      OUTPUT_LOAD='(1.0,-1.0)';
    'DDR0_PAR':
      PIN_NUMBER='(0,0,D53,0,0,0,0,0,0,0,0,0,0,0,0,0,0,0,0,0,0,0,0,0,0,0,0,0,0,0)';
      OUTPUT_LOAD='(1.0,-1.0)';
    'DDR1_ACT_N':
      PIN_NUMBER='(0,0,0,T63,0,0,0,0,0,0,0,0,0,0,0,0,0,0,0,0,0,0,0,0,0,0,0,0,0,0)';
      OUTPUT_LOAD='(1.0,-1.0)';
    'DDR1_ALERT_N':
      PIN_NUMBER='(0,0,0,W62,0,0,0,0,0,0,0,0,0,0,0,0,0,0,0,0,0,0,0,0,0,0,0,0,0,0)';
      INPUT_LOAD='(-0.01,0.01)';
    'DDR1_BA'<1>:
      PIN_NUMBER='(0,0,0,K55,0,0,0,0,0,0,0,0,0,0,0,0,0,0,0,0,0,0,0,0,0,0,0,0,0,0)';
      OUTPUT_LOAD='(1.0,-1.0)';
    'DDR1_BA'<0>:
      PIN_NUMBER='(0,0,0,T53,0,0,0,0,0,0,0,0,0,0,0,0,0,0,0,0,0,0,0,0,0,0,0,0,0,0)';
      OUTPUT_LOAD='(1.0,-1.0)';
    'DDR1_BG'<1>:
      PIN_NUMBER='(0,0,0,N60,0,0,0,0,0,0,0,0,0,0,0,0,0,0,0,0,0,0,0,0,0,0,0,0,0,0)';
      OUTPUT_LOAD='(1.0,-1.0)';
    'DDR1_BG'<0>:
      PIN_NUMBER='(0,0,0,M61,0,0,0,0,0,0,0,0,0,0,0,0,0,0,0,0,0,0,0,0,0,0,0,0,0,0)';
      OUTPUT_LOAD='(1.0,-1.0)';
    'DDR1_CAVREF':
      PIN_NUMBER='(AK63,0,0,0,0,0,0,0,0,0,0,0,0,0,0,0,0,0,0,0,0,0,0,0,0,0,0,0,0,0)';
      OUTPUT_LOAD='(1.0,-1.0)';
    'DDR1_CID'<2>:
      PIN_NUMBER='(0,0,0,M47,0,0,0,0,0,0,0,0,0,0,0,0,0,0,0,0,0,0,0,0,0,0,0,0,0,0)';
      OUTPUT_LOAD='(1.0,-1.0)';
    'DDR1_CKE'<3>:
      PIN_NUMBER='(0,0,0,L64,0,0,0,0,0,0,0,0,0,0,0,0,0,0,0,0,0,0,0,0,0,0,0,0,0,0)';
      OUTPUT_LOAD='(1.0,-1.0)';
    'DDR1_CKE'<2>:
      PIN_NUMBER='(0,0,0,K63,0,0,0,0,0,0,0,0,0,0,0,0,0,0,0,0,0,0,0,0,0,0,0,0,0,0)';
      OUTPUT_LOAD='(1.0,-1.0)';
    'DDR1_CKE'<1>:
      PIN_NUMBER='(0,0,0,R64,0,0,0,0,0,0,0,0,0,0,0,0,0,0,0,0,0,0,0,0,0,0,0,0,0,0)';
      OUTPUT_LOAD='(1.0,-1.0)';
    'DDR1_CKE'<0>:
      PIN_NUMBER='(0,0,0,N62,0,0,0,0,0,0,0,0,0,0,0,0,0,0,0,0,0,0,0,0,0,0,0,0,0,0)';
      OUTPUT_LOAD='(1.0,-1.0)';
    'DDR1_CLK_DN'<3>:
      PIN_NUMBER='(0,0,0,R56,0,0,0,0,0,0,0,0,0,0,0,0,0,0,0,0,0,0,0,0,0,0,0,0,0,0)';
      OUTPUT_LOAD='(1.0,-1.0)';
    'DDR1_CLK_DN'<2>:
      PIN_NUMBER='(0,0,0,N56,0,0,0,0,0,0,0,0,0,0,0,0,0,0,0,0,0,0,0,0,0,0,0,0,0,0)';
      OUTPUT_LOAD='(1.0,-1.0)';
    'DDR1_CLK_DN'<1>:
      PIN_NUMBER='(0,0,0,R54,0,0,0,0,0,0,0,0,0,0,0,0,0,0,0,0,0,0,0,0,0,0,0,0,0,0)';
      OUTPUT_LOAD='(1.0,-1.0)';
    'DDR1_CLK_DN'<0>:
      PIN_NUMBER='(0,0,0,M53,0,0,0,0,0,0,0,0,0,0,0,0,0,0,0,0,0,0,0,0,0,0,0,0,0,0)';
      OUTPUT_LOAD='(1.0,-1.0)';
    'DDR1_CLK_DP'<3>:
      PIN_NUMBER='(0,0,0,T57,0,0,0,0,0,0,0,0,0,0,0,0,0,0,0,0,0,0,0,0,0,0,0,0,0,0)';
      OUTPUT_LOAD='(1.0,-1.0)';
    'DDR1_CLK_DP'<2>:
      PIN_NUMBER='(0,0,0,M57,0,0,0,0,0,0,0,0,0,0,0,0,0,0,0,0,0,0,0,0,0,0,0,0,0,0)';
      OUTPUT_LOAD='(1.0,-1.0)';
    'DDR1_CLK_DP'<1>:
      PIN_NUMBER='(0,0,0,T55,0,0,0,0,0,0,0,0,0,0,0,0,0,0,0,0,0,0,0,0,0,0,0,0,0,0)';
      OUTPUT_LOAD='(1.0,-1.0)';
    'DDR1_CLK_DP'<0>:
      PIN_NUMBER='(0,0,0,N54,0,0,0,0,0,0,0,0,0,0,0,0,0,0,0,0,0,0,0,0,0,0,0,0,0,0)';
      OUTPUT_LOAD='(1.0,-1.0)';
    'DDR1_CS_N'<7>:
      PIN_NUMBER='(0,0,0,R46,0,0,0,0,0,0,0,0,0,0,0,0,0,0,0,0,0,0,0,0,0,0,0,0,0,0)';
      OUTPUT_LOAD='(1.0,-1.0)';
    'DDR1_CS_N'<6>:
      PIN_NUMBER='(0,0,0,M45,0,0,0,0,0,0,0,0,0,0,0,0,0,0,0,0,0,0,0,0,0,0,0,0,0,0)';
      OUTPUT_LOAD='(1.0,-1.0)';
    'DDR1_CS_N'<5>:
      PIN_NUMBER='(0,0,0,T49,0,0,0,0,0,0,0,0,0,0,0,0,0,0,0,0,0,0,0,0,0,0,0,0,0,0)';
      OUTPUT_LOAD='(1.0,-1.0)';
    'DDR1_CS_N'<4>:
      PIN_NUMBER='(0,0,0,J50,0,0,0,0,0,0,0,0,0,0,0,0,0,0,0,0,0,0,0,0,0,0,0,0,0,0)';
      OUTPUT_LOAD='(1.0,-1.0)';
    'DDR1_CS_N'<3>:
      PIN_NUMBER='(0,0,0,V47,0,0,0,0,0,0,0,0,0,0,0,0,0,0,0,0,0,0,0,0,0,0,0,0,0,0)';
      OUTPUT_LOAD='(1.0,-1.0)';
    'DDR1_CS_N'<2>:
      PIN_NUMBER='(0,0,0,N46,0,0,0,0,0,0,0,0,0,0,0,0,0,0,0,0,0,0,0,0,0,0,0,0,0,0)';
      OUTPUT_LOAD='(1.0,-1.0)';
    'DDR1_CS_N'<1>:
      PIN_NUMBER='(0,0,0,R50,0,0,0,0,0,0,0,0,0,0,0,0,0,0,0,0,0,0,0,0,0,0,0,0,0,0)';
      OUTPUT_LOAD='(1.0,-1.0)';
    'DDR1_CS_N'<0>:
      PIN_NUMBER='(0,0,0,K51,0,0,0,0,0,0,0,0,0,0,0,0,0,0,0,0,0,0,0,0,0,0,0,0,0,0)';
      OUTPUT_LOAD='(1.0,-1.0)';
    'DDR1_DQ'<63>:
      PIN_NUMBER='(0,0,0,AA26,0,0,0,0,0,0,0,0,0,0,0,0,0,0,0,0,0,0,0,0,0,0,0,0,0,0)';
      BIDIRECTIONAL='TRUE';
      INPUT_LOAD='(-0.01,0.01)';
      OUTPUT_LOAD='(1.0,-1.0)';
    'DDR1_DQ'<62>:
      PIN_NUMBER='(0,0,0,U26,0,0,0,0,0,0,0,0,0,0,0,0,0,0,0,0,0,0,0,0,0,0,0,0,0,0)';
      BIDIRECTIONAL='TRUE';
      INPUT_LOAD='(-0.01,0.01)';
      OUTPUT_LOAD='(1.0,-1.0)';
    'DDR1_DQ'<61>:
      PIN_NUMBER='(0,0,0,Y29,0,0,0,0,0,0,0,0,0,0,0,0,0,0,0,0,0,0,0,0,0,0,0,0,0,0)';
      BIDIRECTIONAL='TRUE';
      INPUT_LOAD='(-0.01,0.01)';
      OUTPUT_LOAD='(1.0,-1.0)';
    'DDR1_DQ'<60>:
      PIN_NUMBER='(0,0,0,V29,0,0,0,0,0,0,0,0,0,0,0,0,0,0,0,0,0,0,0,0,0,0,0,0,0,0)';
      BIDIRECTIONAL='TRUE';
      INPUT_LOAD='(-0.01,0.01)';
      OUTPUT_LOAD='(1.0,-1.0)';
    'DDR1_DQ'<59>:
      PIN_NUMBER='(0,0,0,Y25,0,0,0,0,0,0,0,0,0,0,0,0,0,0,0,0,0,0,0,0,0,0,0,0,0,0)';
      BIDIRECTIONAL='TRUE';
      INPUT_LOAD='(-0.01,0.01)';
      OUTPUT_LOAD='(1.0,-1.0)';
    'DDR1_DQ'<58>:
      PIN_NUMBER='(0,0,0,V25,0,0,0,0,0,0,0,0,0,0,0,0,0,0,0,0,0,0,0,0,0,0,0,0,0,0)';
      BIDIRECTIONAL='TRUE';
      INPUT_LOAD='(-0.01,0.01)';
      OUTPUT_LOAD='(1.0,-1.0)';
    'DDR1_DQ'<57>:
      PIN_NUMBER='(0,0,0,AA28,0,0,0,0,0,0,0,0,0,0,0,0,0,0,0,0,0,0,0,0,0,0,0,0,0,0)';
      BIDIRECTIONAL='TRUE';
      INPUT_LOAD='(-0.01,0.01)';
      OUTPUT_LOAD='(1.0,-1.0)';
    'DDR1_DQ'<56>:
      PIN_NUMBER='(0,0,0,U28,0,0,0,0,0,0,0,0,0,0,0,0,0,0,0,0,0,0,0,0,0,0,0,0,0,0)';
      BIDIRECTIONAL='TRUE';
      INPUT_LOAD='(-0.01,0.01)';
      OUTPUT_LOAD='(1.0,-1.0)';
    'DDR1_DQ'<55>:
      PIN_NUMBER='(0,0,0,F27,0,0,0,0,0,0,0,0,0,0,0,0,0,0,0,0,0,0,0,0,0,0,0,0,0,0)';
      BIDIRECTIONAL='TRUE';
      INPUT_LOAD='(-0.01,0.01)';
      OUTPUT_LOAD='(1.0,-1.0)';
    'DDR1_DQ'<54>:
      PIN_NUMBER='(0,0,0,B27,0,0,0,0,0,0,0,0,0,0,0,0,0,0,0,0,0,0,0,0,0,0,0,0,0,0)';
      BIDIRECTIONAL='TRUE';
      INPUT_LOAD='(-0.01,0.01)';
      OUTPUT_LOAD='(1.0,-1.0)';
    'DDR1_DQ'<53>:
      PIN_NUMBER='(0,0,0,F29,0,0,0,0,0,0,0,0,0,0,0,0,0,0,0,0,0,0,0,0,0,0,0,0,0,0)';
      BIDIRECTIONAL='TRUE';
      INPUT_LOAD='(-0.01,0.01)';
      OUTPUT_LOAD='(1.0,-1.0)';
    'DDR1_DQ'<52>:
      PIN_NUMBER='(0,0,0,E30,0,0,0,0,0,0,0,0,0,0,0,0,0,0,0,0,0,0,0,0,0,0,0,0,0,0)';
      BIDIRECTIONAL='TRUE';
      INPUT_LOAD='(-0.01,0.01)';
      OUTPUT_LOAD='(1.0,-1.0)';
    'DDR1_DQ'<51>:
      PIN_NUMBER='(0,0,0,E26,0,0,0,0,0,0,0,0,0,0,0,0,0,0,0,0,0,0,0,0,0,0,0,0,0,0)';
      BIDIRECTIONAL='TRUE';
      INPUT_LOAD='(-0.01,0.01)';
      OUTPUT_LOAD='(1.0,-1.0)';
    'DDR1_DQ'<50>:
      PIN_NUMBER='(0,0,0,C26,0,0,0,0,0,0,0,0,0,0,0,0,0,0,0,0,0,0,0,0,0,0,0,0,0,0)';
      BIDIRECTIONAL='TRUE';
      INPUT_LOAD='(-0.01,0.01)';
      OUTPUT_LOAD='(1.0,-1.0)';
    'DDR1_DQ'<49>:
      PIN_NUMBER='(0,0,0,B29,0,0,0,0,0,0,0,0,0,0,0,0,0,0,0,0,0,0,0,0,0,0,0,0,0,0)';
      BIDIRECTIONAL='TRUE';
      INPUT_LOAD='(-0.01,0.01)';
      OUTPUT_LOAD='(1.0,-1.0)';
    'DDR1_DQ'<48>:
      PIN_NUMBER='(0,0,0,C30,0,0,0,0,0,0,0,0,0,0,0,0,0,0,0,0,0,0,0,0,0,0,0,0,0,0)';
      BIDIRECTIONAL='TRUE';
      INPUT_LOAD='(-0.01,0.01)';
      OUTPUT_LOAD='(1.0,-1.0)';
    'DDR1_DQ'<47>:
      PIN_NUMBER='(0,0,0,F33,0,0,0,0,0,0,0,0,0,0,0,0,0,0,0,0,0,0,0,0,0,0,0,0,0,0)';
      BIDIRECTIONAL='TRUE';
      INPUT_LOAD='(-0.01,0.01)';
      OUTPUT_LOAD='(1.0,-1.0)';
    'DDR1_DQ'<46>:
      PIN_NUMBER='(0,0,0,B33,0,0,0,0,0,0,0,0,0,0,0,0,0,0,0,0,0,0,0,0,0,0,0,0,0,0)';
      BIDIRECTIONAL='TRUE';
      INPUT_LOAD='(-0.01,0.01)';
      OUTPUT_LOAD='(1.0,-1.0)';
    'DDR1_DQ'<45>:
      PIN_NUMBER='(0,0,0,F35,0,0,0,0,0,0,0,0,0,0,0,0,0,0,0,0,0,0,0,0,0,0,0,0,0,0)';
      BIDIRECTIONAL='TRUE';
      INPUT_LOAD='(-0.01,0.01)';
      OUTPUT_LOAD='(1.0,-1.0)';
    'DDR1_DQ'<44>:
      PIN_NUMBER='(0,0,0,E36,0,0,0,0,0,0,0,0,0,0,0,0,0,0,0,0,0,0,0,0,0,0,0,0,0,0)';
      BIDIRECTIONAL='TRUE';
      INPUT_LOAD='(-0.01,0.01)';
      OUTPUT_LOAD='(1.0,-1.0)';
    'DDR1_DQ'<43>:
      PIN_NUMBER='(0,0,0,E32,0,0,0,0,0,0,0,0,0,0,0,0,0,0,0,0,0,0,0,0,0,0,0,0,0,0)';
      BIDIRECTIONAL='TRUE';
      INPUT_LOAD='(-0.01,0.01)';
      OUTPUT_LOAD='(1.0,-1.0)';
    'DDR1_DQ'<42>:
      PIN_NUMBER='(0,0,0,C32,0,0,0,0,0,0,0,0,0,0,0,0,0,0,0,0,0,0,0,0,0,0,0,0,0,0)';
      BIDIRECTIONAL='TRUE';
      INPUT_LOAD='(-0.01,0.01)';
      OUTPUT_LOAD='(1.0,-1.0)';
    'DDR1_DQ'<41>:
      PIN_NUMBER='(0,0,0,B35,0,0,0,0,0,0,0,0,0,0,0,0,0,0,0,0,0,0,0,0,0,0,0,0,0,0)';
      BIDIRECTIONAL='TRUE';
      INPUT_LOAD='(-0.01,0.01)';
      OUTPUT_LOAD='(1.0,-1.0)';
    'DDR1_DQ'<40>:
      PIN_NUMBER='(0,0,0,C36,0,0,0,0,0,0,0,0,0,0,0,0,0,0,0,0,0,0,0,0,0,0,0,0,0,0)';
      BIDIRECTIONAL='TRUE';
      INPUT_LOAD='(-0.01,0.01)';
      OUTPUT_LOAD='(1.0,-1.0)';
    'DDR1_DQ'<39>:
      PIN_NUMBER='(0,0,0,P41,0,0,0,0,0,0,0,0,0,0,0,0,0,0,0,0,0,0,0,0,0,0,0,0,0,0)';
      BIDIRECTIONAL='TRUE';
      INPUT_LOAD='(-0.01,0.01)';
      OUTPUT_LOAD='(1.0,-1.0)';
    'DDR1_DQ'<38>:
      PIN_NUMBER='(0,0,0,K41,0,0,0,0,0,0,0,0,0,0,0,0,0,0,0,0,0,0,0,0,0,0,0,0,0,0)';
      BIDIRECTIONAL='TRUE';
      INPUT_LOAD='(-0.01,0.01)';
      OUTPUT_LOAD='(1.0,-1.0)';
    'DDR1_DQ'<37>:
      PIN_NUMBER='(0,0,0,T43,0,0,0,0,0,0,0,0,0,0,0,0,0,0,0,0,0,0,0,0,0,0,0,0,0,0)';
      BIDIRECTIONAL='TRUE';
      INPUT_LOAD='(-0.01,0.01)';
      OUTPUT_LOAD='(1.0,-1.0)';
    'DDR1_DQ'<36>:
      PIN_NUMBER='(0,0,0,P43,0,0,0,0,0,0,0,0,0,0,0,0,0,0,0,0,0,0,0,0,0,0,0,0,0,0)';
      BIDIRECTIONAL='TRUE';
      INPUT_LOAD='(-0.01,0.01)';
      OUTPUT_LOAD='(1.0,-1.0)';
    'DDR1_DQ'<35>:
      PIN_NUMBER='(0,0,0,N40,0,0,0,0,0,0,0,0,0,0,0,0,0,0,0,0,0,0,0,0,0,0,0,0,0,0)';
      BIDIRECTIONAL='TRUE';
      INPUT_LOAD='(-0.01,0.01)';
      OUTPUT_LOAD='(1.0,-1.0)';
    'DDR1_DQ'<34>:
      PIN_NUMBER='(0,0,0,L40,0,0,0,0,0,0,0,0,0,0,0,0,0,0,0,0,0,0,0,0,0,0,0,0,0,0)';
      BIDIRECTIONAL='TRUE';
      INPUT_LOAD='(-0.01,0.01)';
      OUTPUT_LOAD='(1.0,-1.0)';
    'DDR1_DQ'<33>:
      PIN_NUMBER='(0,0,0,H43,0,0,0,0,0,0,0,0,0,0,0,0,0,0,0,0,0,0,0,0,0,0,0,0,0,0)';
      BIDIRECTIONAL='TRUE';
      INPUT_LOAD='(-0.01,0.01)';
      OUTPUT_LOAD='(1.0,-1.0)';
    'DDR1_DQ'<32>:
      PIN_NUMBER='(0,0,0,K43,0,0,0,0,0,0,0,0,0,0,0,0,0,0,0,0,0,0,0,0,0,0,0,0,0,0)';
      BIDIRECTIONAL='TRUE';
      INPUT_LOAD='(-0.01,0.01)';
      OUTPUT_LOAD='(1.0,-1.0)';
    'DDR1_DQ'<31>:
      PIN_NUMBER='(0,0,0,G72,0,0,0,0,0,0,0,0,0,0,0,0,0,0,0,0,0,0,0,0,0,0,0,0,0,0)';
      BIDIRECTIONAL='TRUE';
      INPUT_LOAD='(-0.01,0.01)';
      OUTPUT_LOAD='(1.0,-1.0)';
    'DDR1_DQ'<30>:
      PIN_NUMBER='(0,0,0,C72,0,0,0,0,0,0,0,0,0,0,0,0,0,0,0,0,0,0,0,0,0,0,0,0,0,0)';
      BIDIRECTIONAL='TRUE';
      INPUT_LOAD='(-0.01,0.01)';
      OUTPUT_LOAD='(1.0,-1.0)';
    'DDR1_DQ'<29>:
      PIN_NUMBER='(0,0,0,G74,0,0,0,0,0,0,0,0,0,0,0,0,0,0,0,0,0,0,0,0,0,0,0,0,0,0)';
      BIDIRECTIONAL='TRUE';
      INPUT_LOAD='(-0.01,0.01)';
      OUTPUT_LOAD='(1.0,-1.0)';
    'DDR1_DQ'<28>:
      PIN_NUMBER='(0,0,0,F75,0,0,0,0,0,0,0,0,0,0,0,0,0,0,0,0,0,0,0,0,0,0,0,0,0,0)';
      BIDIRECTIONAL='TRUE';
      INPUT_LOAD='(-0.01,0.01)';
      OUTPUT_LOAD='(1.0,-1.0)';
    'DDR1_DQ'<27>:
      PIN_NUMBER='(0,0,0,F71,0,0,0,0,0,0,0,0,0,0,0,0,0,0,0,0,0,0,0,0,0,0,0,0,0,0)';
      BIDIRECTIONAL='TRUE';
      INPUT_LOAD='(-0.01,0.01)';
      OUTPUT_LOAD='(1.0,-1.0)';
    'DDR1_DQ'<26>:
      PIN_NUMBER='(0,0,0,D71,0,0,0,0,0,0,0,0,0,0,0,0,0,0,0,0,0,0,0,0,0,0,0,0,0,0)';
      BIDIRECTIONAL='TRUE';
      INPUT_LOAD='(-0.01,0.01)';
      OUTPUT_LOAD='(1.0,-1.0)';
    'DDR1_DQ'<25>:
      PIN_NUMBER='(0,0,0,C74,0,0,0,0,0,0,0,0,0,0,0,0,0,0,0,0,0,0,0,0,0,0,0,0,0,0)';
      BIDIRECTIONAL='TRUE';
      INPUT_LOAD='(-0.01,0.01)';
      OUTPUT_LOAD='(1.0,-1.0)';
    'DDR1_DQ'<24>:
      PIN_NUMBER='(0,0,0,D75,0,0,0,0,0,0,0,0,0,0,0,0,0,0,0,0,0,0,0,0,0,0,0,0,0,0)';
      BIDIRECTIONAL='TRUE';
      INPUT_LOAD='(-0.01,0.01)';
      OUTPUT_LOAD='(1.0,-1.0)';
    'DDR1_DQ'<23>:
      PIN_NUMBER='(0,0,0,J78,0,0,0,0,0,0,0,0,0,0,0,0,0,0,0,0,0,0,0,0,0,0,0,0,0,0)';
      BIDIRECTIONAL='TRUE';
      INPUT_LOAD='(-0.01,0.01)';
      OUTPUT_LOAD='(1.0,-1.0)';
    'DDR1_DQ'<22>:
      PIN_NUMBER='(0,0,0,E78,0,0,0,0,0,0,0,0,0,0,0,0,0,0,0,0,0,0,0,0,0,0,0,0,0,0)';
      BIDIRECTIONAL='TRUE';
      INPUT_LOAD='(-0.01,0.01)';
      OUTPUT_LOAD='(1.0,-1.0)';
    'DDR1_DQ'<21>:
      PIN_NUMBER='(0,0,0,H81,0,0,0,0,0,0,0,0,0,0,0,0,0,0,0,0,0,0,0,0,0,0,0,0,0,0)';
      BIDIRECTIONAL='TRUE';
      INPUT_LOAD='(-0.01,0.01)';
      OUTPUT_LOAD='(1.0,-1.0)';
    'DDR1_DQ'<20>:
      PIN_NUMBER='(0,0,0,F81,0,0,0,0,0,0,0,0,0,0,0,0,0,0,0,0,0,0,0,0,0,0,0,0,0,0)';
      BIDIRECTIONAL='TRUE';
      INPUT_LOAD='(-0.01,0.01)';
      OUTPUT_LOAD='(1.0,-1.0)';
    'DDR1_DQ'<19>:
      PIN_NUMBER='(0,0,0,H77,0,0,0,0,0,0,0,0,0,0,0,0,0,0,0,0,0,0,0,0,0,0,0,0,0,0)';
      BIDIRECTIONAL='TRUE';
      INPUT_LOAD='(-0.01,0.01)';
      OUTPUT_LOAD='(1.0,-1.0)';
    'DDR1_DQ'<18>:
      PIN_NUMBER='(0,0,0,F77,0,0,0,0,0,0,0,0,0,0,0,0,0,0,0,0,0,0,0,0,0,0,0,0,0,0)';
      BIDIRECTIONAL='TRUE';
      INPUT_LOAD='(-0.01,0.01)';
      OUTPUT_LOAD='(1.0,-1.0)';
    'DDR1_DQ'<17>:
      PIN_NUMBER='(0,0,0,J80,0,0,0,0,0,0,0,0,0,0,0,0,0,0,0,0,0,0,0,0,0,0,0,0,0,0)';
      BIDIRECTIONAL='TRUE';
      INPUT_LOAD='(-0.01,0.01)';
      OUTPUT_LOAD='(1.0,-1.0)';
    'DDR1_DQ'<16>:
      PIN_NUMBER='(0,0,0,E80,0,0,0,0,0,0,0,0,0,0,0,0,0,0,0,0,0,0,0,0,0,0,0,0,0,0)';
      BIDIRECTIONAL='TRUE';
      INPUT_LOAD='(-0.01,0.01)';
      OUTPUT_LOAD='(1.0,-1.0)';
    'DDR1_DQ'<15>:
      PIN_NUMBER='(0,0,0,AC80,0,0,0,0,0,0,0,0,0,0,0,0,0,0,0,0,0,0,0,0,0,0,0,0,0,0)';
      BIDIRECTIONAL='TRUE';
      INPUT_LOAD='(-0.01,0.01)';
      OUTPUT_LOAD='(1.0,-1.0)';
    'DDR1_DQ'<14>:
      PIN_NUMBER='(0,0,0,AE82,0,0,0,0,0,0,0,0,0,0,0,0,0,0,0,0,0,0,0,0,0,0,0,0,0,0)';
      BIDIRECTIONAL='TRUE';
      INPUT_LOAD='(-0.01,0.01)';
      OUTPUT_LOAD='(1.0,-1.0)';
    'DDR1_DQ'<13>:
      PIN_NUMBER='(0,0,0,AH79,0,0,0,0,0,0,0,0,0,0,0,0,0,0,0,0,0,0,0,0,0,0,0,0,0,0)';
      BIDIRECTIONAL='TRUE';
      INPUT_LOAD='(-0.01,0.01)';
      OUTPUT_LOAD='(1.0,-1.0)';
    'DDR1_DQ'<12>:
      PIN_NUMBER='(0,0,0,AJ80,0,0,0,0,0,0,0,0,0,0,0,0,0,0,0,0,0,0,0,0,0,0,0,0,0,0)';
      BIDIRECTIONAL='TRUE';
      INPUT_LOAD='(-0.01,0.01)';
      OUTPUT_LOAD='(1.0,-1.0)';
    'DDR1_DQ'<11>:
      PIN_NUMBER='(0,0,0,AB81,0,0,0,0,0,0,0,0,0,0,0,0,0,0,0,0,0,0,0,0,0,0,0,0,0,0)';
      BIDIRECTIONAL='TRUE';
      INPUT_LOAD='(-0.01,0.01)';
      OUTPUT_LOAD='(1.0,-1.0)';
    'DDR1_DQ'<10>:
      PIN_NUMBER='(0,0,0,AC82,0,0,0,0,0,0,0,0,0,0,0,0,0,0,0,0,0,0,0,0,0,0,0,0,0,0)';
      BIDIRECTIONAL='TRUE';
      INPUT_LOAD='(-0.01,0.01)';
      OUTPUT_LOAD='(1.0,-1.0)';
    'DDR1_DQ'<9>:
      PIN_NUMBER='(0,0,0,AF79,0,0,0,0,0,0,0,0,0,0,0,0,0,0,0,0,0,0,0,0,0,0,0,0,0,0)';
      BIDIRECTIONAL='TRUE';
      INPUT_LOAD='(-0.01,0.01)';
      OUTPUT_LOAD='(1.0,-1.0)';
    'DDR1_DQ'<8>:
      PIN_NUMBER='(0,0,0,AH81,0,0,0,0,0,0,0,0,0,0,0,0,0,0,0,0,0,0,0,0,0,0,0,0,0,0)';
      BIDIRECTIONAL='TRUE';
      INPUT_LOAD='(-0.01,0.01)';
      OUTPUT_LOAD='(1.0,-1.0)';
    'DDR1_DQ'<7>:
      PIN_NUMBER='(0,0,0,AN80,0,0,0,0,0,0,0,0,0,0,0,0,0,0,0,0,0,0,0,0,0,0,0,0,0,0)';
      BIDIRECTIONAL='TRUE';
      INPUT_LOAD='(-0.01,0.01)';
      OUTPUT_LOAD='(1.0,-1.0)';
    'DDR1_DQ'<6>:
      PIN_NUMBER='(0,0,0,AR82,0,0,0,0,0,0,0,0,0,0,0,0,0,0,0,0,0,0,0,0,0,0,0,0,0,0)';
      BIDIRECTIONAL='TRUE';
      INPUT_LOAD='(-0.01,0.01)';
      OUTPUT_LOAD='(1.0,-1.0)';
    'DDR1_DQ'<5>:
      PIN_NUMBER='(0,0,0,AV79,0,0,0,0,0,0,0,0,0,0,0,0,0,0,0,0,0,0,0,0,0,0,0,0,0,0)';
      BIDIRECTIONAL='TRUE';
      INPUT_LOAD='(-0.01,0.01)';
      OUTPUT_LOAD='(1.0,-1.0)';
    'DDR1_DQ'<4>:
      PIN_NUMBER='(0,0,0,AW80,0,0,0,0,0,0,0,0,0,0,0,0,0,0,0,0,0,0,0,0,0,0,0,0,0,0)';
      BIDIRECTIONAL='TRUE';
      INPUT_LOAD='(-0.01,0.01)';
      OUTPUT_LOAD='(1.0,-1.0)';
    'DDR1_DQ'<3>:
      PIN_NUMBER='(0,0,0,AM81,0,0,0,0,0,0,0,0,0,0,0,0,0,0,0,0,0,0,0,0,0,0,0,0,0,0)';
      BIDIRECTIONAL='TRUE';
      INPUT_LOAD='(-0.01,0.01)';
      OUTPUT_LOAD='(1.0,-1.0)';
    'DDR1_DQ'<2>:
      PIN_NUMBER='(0,0,0,AN82,0,0,0,0,0,0,0,0,0,0,0,0,0,0,0,0,0,0,0,0,0,0,0,0,0,0)';
      BIDIRECTIONAL='TRUE';
      INPUT_LOAD='(-0.01,0.01)';
      OUTPUT_LOAD='(1.0,-1.0)';
    'DDR1_DQ'<1>:
      PIN_NUMBER='(0,0,0,AT79,0,0,0,0,0,0,0,0,0,0,0,0,0,0,0,0,0,0,0,0,0,0,0,0,0,0)';
      BIDIRECTIONAL='TRUE';
      INPUT_LOAD='(-0.01,0.01)';
      OUTPUT_LOAD='(1.0,-1.0)';
    'DDR1_DQ'<0>:
      PIN_NUMBER='(0,0,0,AV81,0,0,0,0,0,0,0,0,0,0,0,0,0,0,0,0,0,0,0,0,0,0,0,0,0,0)';
      BIDIRECTIONAL='TRUE';
      INPUT_LOAD='(-0.01,0.01)';
      OUTPUT_LOAD='(1.0,-1.0)';
    'DDR1_DQS_DN'<17>:
      PIN_NUMBER='(0,0,0,G68,0,0,0,0,0,0,0,0,0,0,0,0,0,0,0,0,0,0,0,0,0,0,0,0,0,0)';
      BIDIRECTIONAL='TRUE';
      INPUT_LOAD='(-0.01,0.01)';
      OUTPUT_LOAD='(1.0,-1.0)';
    'DDR1_DQS_DN'<16>:
      PIN_NUMBER='(0,0,0,T27,0,0,0,0,0,0,0,0,0,0,0,0,0,0,0,0,0,0,0,0,0,0,0,0,0,0)';
      BIDIRECTIONAL='TRUE';
      INPUT_LOAD='(-0.01,0.01)';
      OUTPUT_LOAD='(1.0,-1.0)';
    'DDR1_DQS_DN'<15>:
      PIN_NUMBER='(0,0,0,A28,0,0,0,0,0,0,0,0,0,0,0,0,0,0,0,0,0,0,0,0,0,0,0,0,0,0)';
      BIDIRECTIONAL='TRUE';
      INPUT_LOAD='(-0.01,0.01)';
      OUTPUT_LOAD='(1.0,-1.0)';
    'DDR1_DQS_DN'<14>:
      PIN_NUMBER='(0,0,0,A34,0,0,0,0,0,0,0,0,0,0,0,0,0,0,0,0,0,0,0,0,0,0,0,0,0,0)';
      BIDIRECTIONAL='TRUE';
      INPUT_LOAD='(-0.01,0.01)';
      OUTPUT_LOAD='(1.0,-1.0)';
    'DDR1_DQS_DN'<13>:
      PIN_NUMBER='(0,0,0,J42,0,0,0,0,0,0,0,0,0,0,0,0,0,0,0,0,0,0,0,0,0,0,0,0,0,0)';
      BIDIRECTIONAL='TRUE';
      INPUT_LOAD='(-0.01,0.01)';
      OUTPUT_LOAD='(1.0,-1.0)';
    'DDR1_DQS_DN'<12>:
      PIN_NUMBER='(0,0,0,B73,0,0,0,0,0,0,0,0,0,0,0,0,0,0,0,0,0,0,0,0,0,0,0,0,0,0)';
      BIDIRECTIONAL='TRUE';
      INPUT_LOAD='(-0.01,0.01)';
      OUTPUT_LOAD='(1.0,-1.0)';
    'DDR1_DQS_DN'<11>:
      PIN_NUMBER='(0,0,0,D79,0,0,0,0,0,0,0,0,0,0,0,0,0,0,0,0,0,0,0,0,0,0,0,0,0,0)';
      BIDIRECTIONAL='TRUE';
      INPUT_LOAD='(-0.01,0.01)';
      OUTPUT_LOAD='(1.0,-1.0)';
    'DDR1_DQS_DN'<10>:
      PIN_NUMBER='(0,0,0,AG82,0,0,0,0,0,0,0,0,0,0,0,0,0,0,0,0,0,0,0,0,0,0,0,0,0,0)';
      BIDIRECTIONAL='TRUE';
      INPUT_LOAD='(-0.01,0.01)';
      OUTPUT_LOAD='(1.0,-1.0)';
    'DDR1_DQS_DN'<9>:
      PIN_NUMBER='(0,0,0,AU82,0,0,0,0,0,0,0,0,0,0,0,0,0,0,0,0,0,0,0,0,0,0,0,0,0,0)';
      BIDIRECTIONAL='TRUE';
      INPUT_LOAD='(-0.01,0.01)';
      OUTPUT_LOAD='(1.0,-1.0)';
    'DDR1_DQS_DN'<8>:
      PIN_NUMBER='(0,0,0,N68,0,0,0,0,0,0,0,0,0,0,0,0,0,0,0,0,0,0,0,0,0,0,0,0,0,0)';
      BIDIRECTIONAL='TRUE';
      INPUT_LOAD='(-0.01,0.01)';
      OUTPUT_LOAD='(1.0,-1.0)';
    'DDR1_DQS_DN'<7>:
      PIN_NUMBER='(0,0,0,AB27,0,0,0,0,0,0,0,0,0,0,0,0,0,0,0,0,0,0,0,0,0,0,0,0,0,0)';
      BIDIRECTIONAL='TRUE';
      INPUT_LOAD='(-0.01,0.01)';
      OUTPUT_LOAD='(1.0,-1.0)';
    'DDR1_DQS_DN'<6>:
      PIN_NUMBER='(0,0,0,G28,0,0,0,0,0,0,0,0,0,0,0,0,0,0,0,0,0,0,0,0,0,0,0,0,0,0)';
      BIDIRECTIONAL='TRUE';
      INPUT_LOAD='(-0.01,0.01)';
      OUTPUT_LOAD='(1.0,-1.0)';
    'DDR1_DQS_DN'<5>:
      PIN_NUMBER='(0,0,0,G34,0,0,0,0,0,0,0,0,0,0,0,0,0,0,0,0,0,0,0,0,0,0,0,0,0,0)';
      BIDIRECTIONAL='TRUE';
      INPUT_LOAD='(-0.01,0.01)';
      OUTPUT_LOAD='(1.0,-1.0)';
    'DDR1_DQS_DN'<4>:
      PIN_NUMBER='(0,0,0,N42,0,0,0,0,0,0,0,0,0,0,0,0,0,0,0,0,0,0,0,0,0,0,0,0,0,0)';
      BIDIRECTIONAL='TRUE';
      INPUT_LOAD='(-0.01,0.01)';
      OUTPUT_LOAD='(1.0,-1.0)';
    'DDR1_DQS_DN'<3>:
      PIN_NUMBER='(0,0,0,H73,0,0,0,0,0,0,0,0,0,0,0,0,0,0,0,0,0,0,0,0,0,0,0,0,0,0)';
      BIDIRECTIONAL='TRUE';
      INPUT_LOAD='(-0.01,0.01)';
      OUTPUT_LOAD='(1.0,-1.0)';
    'DDR1_DQS_DN'<2>:
      PIN_NUMBER='(0,0,0,K79,0,0,0,0,0,0,0,0,0,0,0,0,0,0,0,0,0,0,0,0,0,0,0,0,0,0)';
      BIDIRECTIONAL='TRUE';
      INPUT_LOAD='(-0.01,0.01)';
      OUTPUT_LOAD='(1.0,-1.0)';
    'DDR1_DQS_DN'<1>:
      PIN_NUMBER='(0,0,0,AD79,0,0,0,0,0,0,0,0,0,0,0,0,0,0,0,0,0,0,0,0,0,0,0,0,0,0)';
      BIDIRECTIONAL='TRUE';
      INPUT_LOAD='(-0.01,0.01)';
      OUTPUT_LOAD='(1.0,-1.0)';
    'DDR1_DQS_DN'<0>:
      PIN_NUMBER='(0,0,0,AP79,0,0,0,0,0,0,0,0,0,0,0,0,0,0,0,0,0,0,0,0,0,0,0,0,0,0)';
      BIDIRECTIONAL='TRUE';
      INPUT_LOAD='(-0.01,0.01)';
      OUTPUT_LOAD='(1.0,-1.0)';
    'DDR1_DQS_DP'<17>:
      PIN_NUMBER='(0,0,0,J68,0,0,0,0,0,0,0,0,0,0,0,0,0,0,0,0,0,0,0,0,0,0,0,0,0,0)';
      BIDIRECTIONAL='TRUE';
      INPUT_LOAD='(-0.01,0.01)';
      OUTPUT_LOAD='(1.0,-1.0)';
    'DDR1_DQS_DP'<16>:
      PIN_NUMBER='(0,0,0,V27,0,0,0,0,0,0,0,0,0,0,0,0,0,0,0,0,0,0,0,0,0,0,0,0,0,0)';
      BIDIRECTIONAL='TRUE';
      INPUT_LOAD='(-0.01,0.01)';
      OUTPUT_LOAD='(1.0,-1.0)';
    'DDR1_DQS_DP'<15>:
      PIN_NUMBER='(0,0,0,C28,0,0,0,0,0,0,0,0,0,0,0,0,0,0,0,0,0,0,0,0,0,0,0,0,0,0)';
      BIDIRECTIONAL='TRUE';
      INPUT_LOAD='(-0.01,0.01)';
      OUTPUT_LOAD='(1.0,-1.0)';
    'DDR1_DQS_DP'<14>:
      PIN_NUMBER='(0,0,0,C34,0,0,0,0,0,0,0,0,0,0,0,0,0,0,0,0,0,0,0,0,0,0,0,0,0,0)';
      BIDIRECTIONAL='TRUE';
      INPUT_LOAD='(-0.01,0.01)';
      OUTPUT_LOAD='(1.0,-1.0)';
    'DDR1_DQS_DP'<13>:
      PIN_NUMBER='(0,0,0,L42,0,0,0,0,0,0,0,0,0,0,0,0,0,0,0,0,0,0,0,0,0,0,0,0,0,0)';
      BIDIRECTIONAL='TRUE';
      INPUT_LOAD='(-0.01,0.01)';
      OUTPUT_LOAD='(1.0,-1.0)';
    'DDR1_DQS_DP'<12>:
      PIN_NUMBER='(0,0,0,D73,0,0,0,0,0,0,0,0,0,0,0,0,0,0,0,0,0,0,0,0,0,0,0,0,0,0)';
      BIDIRECTIONAL='TRUE';
      INPUT_LOAD='(-0.01,0.01)';
      OUTPUT_LOAD='(1.0,-1.0)';
    'DDR1_DQS_DP'<11>:
      PIN_NUMBER='(0,0,0,F79,0,0,0,0,0,0,0,0,0,0,0,0,0,0,0,0,0,0,0,0,0,0,0,0,0,0)';
      BIDIRECTIONAL='TRUE';
      INPUT_LOAD='(-0.01,0.01)';
      OUTPUT_LOAD='(1.0,-1.0)';
    'DDR1_DQS_DP'<10>:
      PIN_NUMBER='(0,0,0,AF81,0,0,0,0,0,0,0,0,0,0,0,0,0,0,0,0,0,0,0,0,0,0,0,0,0,0)';
      BIDIRECTIONAL='TRUE';
      INPUT_LOAD='(-0.01,0.01)';
      OUTPUT_LOAD='(1.0,-1.0)';
    'DDR1_DQS_DP'<9>:
      PIN_NUMBER='(0,0,0,AT81,0,0,0,0,0,0,0,0,0,0,0,0,0,0,0,0,0,0,0,0,0,0,0,0,0,0)';
      BIDIRECTIONAL='TRUE';
      INPUT_LOAD='(-0.01,0.01)';
      OUTPUT_LOAD='(1.0,-1.0)';
    'DDR1_DQS_DP'<8>:
      PIN_NUMBER='(0,0,0,L68,0,0,0,0,0,0,0,0,0,0,0,0,0,0,0,0,0,0,0,0,0,0,0,0,0,0)';
      BIDIRECTIONAL='TRUE';
      INPUT_LOAD='(-0.01,0.01)';
      OUTPUT_LOAD='(1.0,-1.0)';
    'DDR1_DQS_DP'<7>:
      PIN_NUMBER='(0,0,0,Y27,0,0,0,0,0,0,0,0,0,0,0,0,0,0,0,0,0,0,0,0,0,0,0,0,0,0)';
      BIDIRECTIONAL='TRUE';
      INPUT_LOAD='(-0.01,0.01)';
      OUTPUT_LOAD='(1.0,-1.0)';
    'DDR1_DQS_DP'<6>:
      PIN_NUMBER='(0,0,0,E28,0,0,0,0,0,0,0,0,0,0,0,0,0,0,0,0,0,0,0,0,0,0,0,0,0,0)';
      BIDIRECTIONAL='TRUE';
      INPUT_LOAD='(-0.01,0.01)';
      OUTPUT_LOAD='(1.0,-1.0)';
    'DDR1_DQS_DP'<5>:
      PIN_NUMBER='(0,0,0,E34,0,0,0,0,0,0,0,0,0,0,0,0,0,0,0,0,0,0,0,0,0,0,0,0,0,0)';
      BIDIRECTIONAL='TRUE';
      INPUT_LOAD='(-0.01,0.01)';
      OUTPUT_LOAD='(1.0,-1.0)';
    'DDR1_DQS_DP'<4>:
      PIN_NUMBER='(0,0,0,R42,0,0,0,0,0,0,0,0,0,0,0,0,0,0,0,0,0,0,0,0,0,0,0,0,0,0)';
      BIDIRECTIONAL='TRUE';
      INPUT_LOAD='(-0.01,0.01)';
      OUTPUT_LOAD='(1.0,-1.0)';
    'DDR1_DQS_DP'<3>:
      PIN_NUMBER='(0,0,0,F73,0,0,0,0,0,0,0,0,0,0,0,0,0,0,0,0,0,0,0,0,0,0,0,0,0,0)';
      BIDIRECTIONAL='TRUE';
      INPUT_LOAD='(-0.01,0.01)';
      OUTPUT_LOAD='(1.0,-1.0)';
    'DDR1_DQS_DP'<2>:
      PIN_NUMBER='(0,0,0,H79,0,0,0,0,0,0,0,0,0,0,0,0,0,0,0,0,0,0,0,0,0,0,0,0,0,0)';
      BIDIRECTIONAL='TRUE';
      INPUT_LOAD='(-0.01,0.01)';
      OUTPUT_LOAD='(1.0,-1.0)';
    'DDR1_DQS_DP'<1>:
      PIN_NUMBER='(0,0,0,AE80,0,0,0,0,0,0,0,0,0,0,0,0,0,0,0,0,0,0,0,0,0,0,0,0,0,0)';
      BIDIRECTIONAL='TRUE';
      INPUT_LOAD='(-0.01,0.01)';
      OUTPUT_LOAD='(1.0,-1.0)';
    'DDR1_DQS_DP'<0>:
      PIN_NUMBER='(0,0,0,AR80,0,0,0,0,0,0,0,0,0,0,0,0,0,0,0,0,0,0,0,0,0,0,0,0,0,0)';
      BIDIRECTIONAL='TRUE';
      INPUT_LOAD='(-0.01,0.01)';
      OUTPUT_LOAD='(1.0,-1.0)';
    'DDR1_ECC'<7>:
      PIN_NUMBER='(0,0,0,M67,0,0,0,0,0,0,0,0,0,0,0,0,0,0,0,0,0,0,0,0,0,0,0,0,0,0)';
      BIDIRECTIONAL='TRUE';
      INPUT_LOAD='(-0.01,0.01)';
      OUTPUT_LOAD='(1.0,-1.0)';
    'DDR1_ECC'<6>:
      PIN_NUMBER='(0,0,0,H67,0,0,0,0,0,0,0,0,0,0,0,0,0,0,0,0,0,0,0,0,0,0,0,0,0,0)';
      BIDIRECTIONAL='TRUE';
      INPUT_LOAD='(-0.01,0.01)';
      OUTPUT_LOAD='(1.0,-1.0)';
    'DDR1_ECC'<5>:
      PIN_NUMBER='(0,0,0,M69,0,0,0,0,0,0,0,0,0,0,0,0,0,0,0,0,0,0,0,0,0,0,0,0,0,0)';
      BIDIRECTIONAL='TRUE';
      INPUT_LOAD='(-0.01,0.01)';
      OUTPUT_LOAD='(1.0,-1.0)';
    'DDR1_ECC'<4>:
      PIN_NUMBER='(0,0,0,L70,0,0,0,0,0,0,0,0,0,0,0,0,0,0,0,0,0,0,0,0,0,0,0,0,0,0)';
      BIDIRECTIONAL='TRUE';
      INPUT_LOAD='(-0.01,0.01)';
      OUTPUT_LOAD='(1.0,-1.0)';
    'DDR1_ECC'<3>:
      PIN_NUMBER='(0,0,0,L66,0,0,0,0,0,0,0,0,0,0,0,0,0,0,0,0,0,0,0,0,0,0,0,0,0,0)';
      BIDIRECTIONAL='TRUE';
      INPUT_LOAD='(-0.01,0.01)';
      OUTPUT_LOAD='(1.0,-1.0)';
    'DDR1_ECC'<2>:
      PIN_NUMBER='(0,0,0,J66,0,0,0,0,0,0,0,0,0,0,0,0,0,0,0,0,0,0,0,0,0,0,0,0,0,0)';
      BIDIRECTIONAL='TRUE';
      INPUT_LOAD='(-0.01,0.01)';
      OUTPUT_LOAD='(1.0,-1.0)';
    'DDR1_ECC'<1>:
      PIN_NUMBER='(0,0,0,H69,0,0,0,0,0,0,0,0,0,0,0,0,0,0,0,0,0,0,0,0,0,0,0,0,0,0)';
      BIDIRECTIONAL='TRUE';
      INPUT_LOAD='(-0.01,0.01)';
      OUTPUT_LOAD='(1.0,-1.0)';
    'DDR1_ECC'<0>:
      PIN_NUMBER='(0,0,0,J70,0,0,0,0,0,0,0,0,0,0,0,0,0,0,0,0,0,0,0,0,0,0,0,0,0,0)';
      BIDIRECTIONAL='TRUE';
      INPUT_LOAD='(-0.01,0.01)';
      OUTPUT_LOAD='(1.0,-1.0)';
    'DDR1_MA'<17>:
      PIN_NUMBER='(0,0,0,N48,0,0,0,0,0,0,0,0,0,0,0,0,0,0,0,0,0,0,0,0,0,0,0,0,0,0)';
      OUTPUT_LOAD='(1.0,-1.0)';
    'DDR1_MA'<16>:
      PIN_NUMBER='(0,0,0,R52,0,0,0,0,0,0,0,0,0,0,0,0,0,0,0,0,0,0,0,0,0,0,0,0,0,0)';
      OUTPUT_LOAD='(1.0,-1.0)';
    'DDR1_MA'<15>:
      PIN_NUMBER='(0,0,0,N52,0,0,0,0,0,0,0,0,0,0,0,0,0,0,0,0,0,0,0,0,0,0,0,0,0,0)';
      OUTPUT_LOAD='(1.0,-1.0)';
    'DDR1_MA'<14>:
      PIN_NUMBER='(0,0,0,T51,0,0,0,0,0,0,0,0,0,0,0,0,0,0,0,0,0,0,0,0,0,0,0,0,0,0)';
      OUTPUT_LOAD='(1.0,-1.0)';
    'DDR1_MA'<13>:
      PIN_NUMBER='(0,0,0,M51,0,0,0,0,0,0,0,0,0,0,0,0,0,0,0,0,0,0,0,0,0,0,0,0,0,0)';
      OUTPUT_LOAD='(1.0,-1.0)';
    'DDR1_MA'<12>:
      PIN_NUMBER='(0,0,0,T61,0,0,0,0,0,0,0,0,0,0,0,0,0,0,0,0,0,0,0,0,0,0,0,0,0,0)';
      OUTPUT_LOAD='(1.0,-1.0)';
    'DDR1_MA'<11>:
      PIN_NUMBER='(0,0,0,R60,0,0,0,0,0,0,0,0,0,0,0,0,0,0,0,0,0,0,0,0,0,0,0,0,0,0)';
      OUTPUT_LOAD='(1.0,-1.0)';
    'DDR1_MA'<10>:
      PIN_NUMBER='(0,0,0,M55,0,0,0,0,0,0,0,0,0,0,0,0,0,0,0,0,0,0,0,0,0,0,0,0,0,0)';
      OUTPUT_LOAD='(1.0,-1.0)';
    'DDR1_MA'<9>:
      PIN_NUMBER='(0,0,0,K59,0,0,0,0,0,0,0,0,0,0,0,0,0,0,0,0,0,0,0,0,0,0,0,0,0,0)';
      OUTPUT_LOAD='(1.0,-1.0)';
    'DDR1_MA'<8>:
      PIN_NUMBER='(0,0,0,W60,0,0,0,0,0,0,0,0,0,0,0,0,0,0,0,0,0,0,0,0,0,0,0,0,0,0)';
      OUTPUT_LOAD='(1.0,-1.0)';
    'DDR1_MA'<7>:
      PIN_NUMBER='(0,0,0,V61,0,0,0,0,0,0,0,0,0,0,0,0,0,0,0,0,0,0,0,0,0,0,0,0,0,0)';
      OUTPUT_LOAD='(1.0,-1.0)';
    'DDR1_MA'<6>:
      PIN_NUMBER='(0,0,0,T59,0,0,0,0,0,0,0,0,0,0,0,0,0,0,0,0,0,0,0,0,0,0,0,0,0,0)';
      OUTPUT_LOAD='(1.0,-1.0)';
    'DDR1_MA'<5>:
      PIN_NUMBER='(0,0,0,R58,0,0,0,0,0,0,0,0,0,0,0,0,0,0,0,0,0,0,0,0,0,0,0,0,0,0)';
      OUTPUT_LOAD='(1.0,-1.0)';
    'DDR1_MA'<4>:
      PIN_NUMBER='(0,0,0,M59,0,0,0,0,0,0,0,0,0,0,0,0,0,0,0,0,0,0,0,0,0,0,0,0,0,0)';
      OUTPUT_LOAD='(1.0,-1.0)';
    'DDR1_MA'<3>:
      PIN_NUMBER='(0,0,0,N58,0,0,0,0,0,0,0,0,0,0,0,0,0,0,0,0,0,0,0,0,0,0,0,0,0,0)';
      OUTPUT_LOAD='(1.0,-1.0)';
    'DDR1_MA'<2>:
      PIN_NUMBER='(0,0,0,K57,0,0,0,0,0,0,0,0,0,0,0,0,0,0,0,0,0,0,0,0,0,0,0,0,0,0)';
      OUTPUT_LOAD='(1.0,-1.0)';
    'DDR1_MA'<1>:
      PIN_NUMBER='(0,0,0,J58,0,0,0,0,0,0,0,0,0,0,0,0,0,0,0,0,0,0,0,0,0,0,0,0,0,0)';
      OUTPUT_LOAD='(1.0,-1.0)';
    'DDR1_MA'<0>:
      PIN_NUMBER='(0,0,0,J52,0,0,0,0,0,0,0,0,0,0,0,0,0,0,0,0,0,0,0,0,0,0,0,0,0,0)';
      OUTPUT_LOAD='(1.0,-1.0)';
    'DDR1_ODT'<3>:
      PIN_NUMBER='(0,0,0,T47,0,0,0,0,0,0,0,0,0,0,0,0,0,0,0,0,0,0,0,0,0,0,0,0,0,0)';
      OUTPUT_LOAD='(1.0,-1.0)';
    'DDR1_ODT'<2>:
      PIN_NUMBER='(0,0,0,M49,0,0,0,0,0,0,0,0,0,0,0,0,0,0,0,0,0,0,0,0,0,0,0,0,0,0)';
      OUTPUT_LOAD='(1.0,-1.0)';
    'DDR1_ODT'<1>:
      PIN_NUMBER='(0,0,0,R48,0,0,0,0,0,0,0,0,0,0,0,0,0,0,0,0,0,0,0,0,0,0,0,0,0,0)';
      OUTPUT_LOAD='(1.0,-1.0)';
    'DDR1_ODT'<0>:
      PIN_NUMBER='(0,0,0,N50,0,0,0,0,0,0,0,0,0,0,0,0,0,0,0,0,0,0,0,0,0,0,0,0,0,0)';
      OUTPUT_LOAD='(1.0,-1.0)';
    'DDR1_PAR':
      PIN_NUMBER='(0,0,0,K53,0,0,0,0,0,0,0,0,0,0,0,0,0,0,0,0,0,0,0,0,0,0,0,0,0,0)';
      OUTPUT_LOAD='(1.0,-1.0)';
    'DDR2_ACT_N':
      PIN_NUMBER='(0,0,0,0,AB61,0,0,0,0,0,0,0,0,0,0,0,0,0,0,0,0,0,0,0,0,0,0,0,0,0)';
      OUTPUT_LOAD='(1.0,-1.0)';
    'DDR2_ALERT_N':
      PIN_NUMBER='(0,0,0,0,AD61,0,0,0,0,0,0,0,0,0,0,0,0,0,0,0,0,0,0,0,0,0,0,0,0,0)';
      INPUT_LOAD='(-0.01,0.01)';
    'DDR2_BA'<1>:
      PIN_NUMBER='(0,0,0,0,AE56,0,0,0,0,0,0,0,0,0,0,0,0,0,0,0,0,0,0,0,0,0,0,0,0,0)';
      OUTPUT_LOAD='(1.0,-1.0)';
    'DDR2_BA'<0>:
      PIN_NUMBER='(0,0,0,0,W52,0,0,0,0,0,0,0,0,0,0,0,0,0,0,0,0,0,0,0,0,0,0,0,0,0)';
      OUTPUT_LOAD='(1.0,-1.0)';
    'DDR2_BG'<1>:
      PIN_NUMBER='(0,0,0,0,AE62,0,0,0,0,0,0,0,0,0,0,0,0,0,0,0,0,0,0,0,0,0,0,0,0,0)';
      OUTPUT_LOAD='(1.0,-1.0)';
    'DDR2_BG'<0>:
      PIN_NUMBER='(0,0,0,0,AA60,0,0,0,0,0,0,0,0,0,0,0,0,0,0,0,0,0,0,0,0,0,0,0,0,0)';
      OUTPUT_LOAD='(1.0,-1.0)';
    'DDR2_CAVREF':
      PIN_NUMBER='(AH63,0,0,0,0,0,0,0,0,0,0,0,0,0,0,0,0,0,0,0,0,0,0,0,0,0,0,0,0,0)';
      OUTPUT_LOAD='(1.0,-1.0)';
    'DDR2_CID'<2>:
      PIN_NUMBER='(0,0,0,0,AB45,0,0,0,0,0,0,0,0,0,0,0,0,0,0,0,0,0,0,0,0,0,0,0,0,0)';
      OUTPUT_LOAD='(1.0,-1.0)';
    'DDR2_CKE'<3>:
      PIN_NUMBER='(0,0,0,0,AB63,0,0,0,0,0,0,0,0,0,0,0,0,0,0,0,0,0,0,0,0,0,0,0,0,0)';
      OUTPUT_LOAD='(1.0,-1.0)';
    'DDR2_CKE'<2>:
      PIN_NUMBER='(0,0,0,0,V63,0,0,0,0,0,0,0,0,0,0,0,0,0,0,0,0,0,0,0,0,0,0,0,0,0)';
      OUTPUT_LOAD='(1.0,-1.0)';
    'DDR2_CKE'<1>:
      PIN_NUMBER='(0,0,0,0,AD63,0,0,0,0,0,0,0,0,0,0,0,0,0,0,0,0,0,0,0,0,0,0,0,0,0)';
      OUTPUT_LOAD='(1.0,-1.0)';
    'DDR2_CKE'<0>:
      PIN_NUMBER='(0,0,0,0,AA62,0,0,0,0,0,0,0,0,0,0,0,0,0,0,0,0,0,0,0,0,0,0,0,0,0)';
      OUTPUT_LOAD='(1.0,-1.0)';
    'DDR2_CLK_DN'<3>:
      PIN_NUMBER='(0,0,0,0,W56,0,0,0,0,0,0,0,0,0,0,0,0,0,0,0,0,0,0,0,0,0,0,0,0,0)';
      OUTPUT_LOAD='(1.0,-1.0)';
    'DDR2_CLK_DN'<2>:
      PIN_NUMBER='(0,0,0,0,AA56,0,0,0,0,0,0,0,0,0,0,0,0,0,0,0,0,0,0,0,0,0,0,0,0,0)';
      OUTPUT_LOAD='(1.0,-1.0)';
    'DDR2_CLK_DN'<1>:
      PIN_NUMBER='(0,0,0,0,W54,0,0,0,0,0,0,0,0,0,0,0,0,0,0,0,0,0,0,0,0,0,0,0,0,0)';
      OUTPUT_LOAD='(1.0,-1.0)';
    'DDR2_CLK_DN'<0>:
      PIN_NUMBER='(0,0,0,0,AA54,0,0,0,0,0,0,0,0,0,0,0,0,0,0,0,0,0,0,0,0,0,0,0,0,0)';
      OUTPUT_LOAD='(1.0,-1.0)';
    'DDR2_CLK_DP'<3>:
      PIN_NUMBER='(0,0,0,0,V57,0,0,0,0,0,0,0,0,0,0,0,0,0,0,0,0,0,0,0,0,0,0,0,0,0)';
      OUTPUT_LOAD='(1.0,-1.0)';
    'DDR2_CLK_DP'<2>:
      PIN_NUMBER='(0,0,0,0,AB57,0,0,0,0,0,0,0,0,0,0,0,0,0,0,0,0,0,0,0,0,0,0,0,0,0)';
      OUTPUT_LOAD='(1.0,-1.0)';
    'DDR2_CLK_DP'<1>:
      PIN_NUMBER='(0,0,0,0,V55,0,0,0,0,0,0,0,0,0,0,0,0,0,0,0,0,0,0,0,0,0,0,0,0,0)';
      OUTPUT_LOAD='(1.0,-1.0)';
    'DDR2_CLK_DP'<0>:
      PIN_NUMBER='(0,0,0,0,AB55,0,0,0,0,0,0,0,0,0,0,0,0,0,0,0,0,0,0,0,0,0,0,0,0,0)';
      OUTPUT_LOAD='(1.0,-1.0)';
    'DDR2_CS_N'<7>:
      PIN_NUMBER='(0,0,0,0,V45,0,0,0,0,0,0,0,0,0,0,0,0,0,0,0,0,0,0,0,0,0,0,0,0,0)';
      OUTPUT_LOAD='(1.0,-1.0)';
    'DDR2_CS_N'<6>:
      PIN_NUMBER='(0,0,0,0,T45,0,0,0,0,0,0,0,0,0,0,0,0,0,0,0,0,0,0,0,0,0,0,0,0,0)';
      OUTPUT_LOAD='(1.0,-1.0)';
    'DDR2_CS_N'<5>:
      PIN_NUMBER='(0,0,0,0,W48,0,0,0,0,0,0,0,0,0,0,0,0,0,0,0,0,0,0,0,0,0,0,0,0,0)';
      OUTPUT_LOAD='(1.0,-1.0)';
    'DDR2_CS_N'<4>:
      PIN_NUMBER='(0,0,0,0,AB51,0,0,0,0,0,0,0,0,0,0,0,0,0,0,0,0,0,0,0,0,0,0,0,0,0)';
      OUTPUT_LOAD='(1.0,-1.0)';
    'DDR2_CS_N'<3>:
      PIN_NUMBER='(0,0,0,0,AA46,0,0,0,0,0,0,0,0,0,0,0,0,0,0,0,0,0,0,0,0,0,0,0,0,0)';
      OUTPUT_LOAD='(1.0,-1.0)';
    'DDR2_CS_N'<2>:
      PIN_NUMBER='(0,0,0,0,W46,0,0,0,0,0,0,0,0,0,0,0,0,0,0,0,0,0,0,0,0,0,0,0,0,0)';
      OUTPUT_LOAD='(1.0,-1.0)';
    'DDR2_CS_N'<1>:
      PIN_NUMBER='(0,0,0,0,AB49,0,0,0,0,0,0,0,0,0,0,0,0,0,0,0,0,0,0,0,0,0,0,0,0,0)';
      OUTPUT_LOAD='(1.0,-1.0)';
    'DDR2_CS_N'<0>:
      PIN_NUMBER='(0,0,0,0,V51,0,0,0,0,0,0,0,0,0,0,0,0,0,0,0,0,0,0,0,0,0,0,0,0,0)';
      OUTPUT_LOAD='(1.0,-1.0)';
    'DDR2_DQ'<63>:
      PIN_NUMBER='(0,0,0,0,AH23,0,0,0,0,0,0,0,0,0,0,0,0,0,0,0,0,0,0,0,0,0,0,0,0,0)';
      BIDIRECTIONAL='TRUE';
      INPUT_LOAD='(-0.01,0.01)';
      OUTPUT_LOAD='(1.0,-1.0)';
    'DDR2_DQ'<62>:
      PIN_NUMBER='(0,0,0,0,AD23,0,0,0,0,0,0,0,0,0,0,0,0,0,0,0,0,0,0,0,0,0,0,0,0,0)';
      BIDIRECTIONAL='TRUE';
      INPUT_LOAD='(-0.01,0.01)';
      OUTPUT_LOAD='(1.0,-1.0)';
    'DDR2_DQ'<61>:
      PIN_NUMBER='(0,0,0,0,AG26,0,0,0,0,0,0,0,0,0,0,0,0,0,0,0,0,0,0,0,0,0,0,0,0,0)';
      BIDIRECTIONAL='TRUE';
      INPUT_LOAD='(-0.01,0.01)';
      OUTPUT_LOAD='(1.0,-1.0)';
    'DDR2_DQ'<60>:
      PIN_NUMBER='(0,0,0,0,AE26,0,0,0,0,0,0,0,0,0,0,0,0,0,0,0,0,0,0,0,0,0,0,0,0,0)';
      BIDIRECTIONAL='TRUE';
      INPUT_LOAD='(-0.01,0.01)';
      OUTPUT_LOAD='(1.0,-1.0)';
    'DDR2_DQ'<59>:
      PIN_NUMBER='(0,0,0,0,AG22,0,0,0,0,0,0,0,0,0,0,0,0,0,0,0,0,0,0,0,0,0,0,0,0,0)';
      BIDIRECTIONAL='TRUE';
      INPUT_LOAD='(-0.01,0.01)';
      OUTPUT_LOAD='(1.0,-1.0)';
    'DDR2_DQ'<58>:
      PIN_NUMBER='(0,0,0,0,AE22,0,0,0,0,0,0,0,0,0,0,0,0,0,0,0,0,0,0,0,0,0,0,0,0,0)';
      BIDIRECTIONAL='TRUE';
      INPUT_LOAD='(-0.01,0.01)';
      OUTPUT_LOAD='(1.0,-1.0)';
    'DDR2_DQ'<57>:
      PIN_NUMBER='(0,0,0,0,AH25,0,0,0,0,0,0,0,0,0,0,0,0,0,0,0,0,0,0,0,0,0,0,0,0,0)';
      BIDIRECTIONAL='TRUE';
      INPUT_LOAD='(-0.01,0.01)';
      OUTPUT_LOAD='(1.0,-1.0)';
    'DDR2_DQ'<56>:
      PIN_NUMBER='(0,0,0,0,AD25,0,0,0,0,0,0,0,0,0,0,0,0,0,0,0,0,0,0,0,0,0,0,0,0,0)';
      BIDIRECTIONAL='TRUE';
      INPUT_LOAD='(-0.01,0.01)';
      OUTPUT_LOAD='(1.0,-1.0)';
    'DDR2_DQ'<55>:
      PIN_NUMBER='(0,0,0,0,AH29,0,0,0,0,0,0,0,0,0,0,0,0,0,0,0,0,0,0,0,0,0,0,0,0,0)';
      BIDIRECTIONAL='TRUE';
      INPUT_LOAD='(-0.01,0.01)';
      OUTPUT_LOAD='(1.0,-1.0)';
    'DDR2_DQ'<54>:
      PIN_NUMBER='(0,0,0,0,AD29,0,0,0,0,0,0,0,0,0,0,0,0,0,0,0,0,0,0,0,0,0,0,0,0,0)';
      BIDIRECTIONAL='TRUE';
      INPUT_LOAD='(-0.01,0.01)';
      OUTPUT_LOAD='(1.0,-1.0)';
    'DDR2_DQ'<53>:
      PIN_NUMBER='(0,0,0,0,AG32,0,0,0,0,0,0,0,0,0,0,0,0,0,0,0,0,0,0,0,0,0,0,0,0,0)';
      BIDIRECTIONAL='TRUE';
      INPUT_LOAD='(-0.01,0.01)';
      OUTPUT_LOAD='(1.0,-1.0)';
    'DDR2_DQ'<52>:
      PIN_NUMBER='(0,0,0,0,AE32,0,0,0,0,0,0,0,0,0,0,0,0,0,0,0,0,0,0,0,0,0,0,0,0,0)';
      BIDIRECTIONAL='TRUE';
      INPUT_LOAD='(-0.01,0.01)';
      OUTPUT_LOAD='(1.0,-1.0)';
    'DDR2_DQ'<51>:
      PIN_NUMBER='(0,0,0,0,AG28,0,0,0,0,0,0,0,0,0,0,0,0,0,0,0,0,0,0,0,0,0,0,0,0,0)';
      BIDIRECTIONAL='TRUE';
      INPUT_LOAD='(-0.01,0.01)';
      OUTPUT_LOAD='(1.0,-1.0)';
    'DDR2_DQ'<50>:
      PIN_NUMBER='(0,0,0,0,AE28,0,0,0,0,0,0,0,0,0,0,0,0,0,0,0,0,0,0,0,0,0,0,0,0,0)';
      BIDIRECTIONAL='TRUE';
      INPUT_LOAD='(-0.01,0.01)';
      OUTPUT_LOAD='(1.0,-1.0)';
    'DDR2_DQ'<49>:
      PIN_NUMBER='(0,0,0,0,AH31,0,0,0,0,0,0,0,0,0,0,0,0,0,0,0,0,0,0,0,0,0,0,0,0,0)';
      BIDIRECTIONAL='TRUE';
      INPUT_LOAD='(-0.01,0.01)';
      OUTPUT_LOAD='(1.0,-1.0)';
    'DDR2_DQ'<48>:
      PIN_NUMBER='(0,0,0,0,AD31,0,0,0,0,0,0,0,0,0,0,0,0,0,0,0,0,0,0,0,0,0,0,0,0,0)';
      BIDIRECTIONAL='TRUE';
      INPUT_LOAD='(-0.01,0.01)';
      OUTPUT_LOAD='(1.0,-1.0)';
    'DDR2_DQ'<47>:
      PIN_NUMBER='(0,0,0,0,AA32,0,0,0,0,0,0,0,0,0,0,0,0,0,0,0,0,0,0,0,0,0,0,0,0,0)';
      BIDIRECTIONAL='TRUE';
      INPUT_LOAD='(-0.01,0.01)';
      OUTPUT_LOAD='(1.0,-1.0)';
    'DDR2_DQ'<46>:
      PIN_NUMBER='(0,0,0,0,U32,0,0,0,0,0,0,0,0,0,0,0,0,0,0,0,0,0,0,0,0,0,0,0,0,0)';
      BIDIRECTIONAL='TRUE';
      INPUT_LOAD='(-0.01,0.01)';
      OUTPUT_LOAD='(1.0,-1.0)';
    'DDR2_DQ'<45>:
      PIN_NUMBER='(0,0,0,0,Y35,0,0,0,0,0,0,0,0,0,0,0,0,0,0,0,0,0,0,0,0,0,0,0,0,0)';
      BIDIRECTIONAL='TRUE';
      INPUT_LOAD='(-0.01,0.01)';
      OUTPUT_LOAD='(1.0,-1.0)';
    'DDR2_DQ'<44>:
      PIN_NUMBER='(0,0,0,0,V35,0,0,0,0,0,0,0,0,0,0,0,0,0,0,0,0,0,0,0,0,0,0,0,0,0)';
      BIDIRECTIONAL='TRUE';
      INPUT_LOAD='(-0.01,0.01)';
      OUTPUT_LOAD='(1.0,-1.0)';
    'DDR2_DQ'<43>:
      PIN_NUMBER='(0,0,0,0,Y31,0,0,0,0,0,0,0,0,0,0,0,0,0,0,0,0,0,0,0,0,0,0,0,0,0)';
      BIDIRECTIONAL='TRUE';
      INPUT_LOAD='(-0.01,0.01)';
      OUTPUT_LOAD='(1.0,-1.0)';
    'DDR2_DQ'<42>:
      PIN_NUMBER='(0,0,0,0,V31,0,0,0,0,0,0,0,0,0,0,0,0,0,0,0,0,0,0,0,0,0,0,0,0,0)';
      BIDIRECTIONAL='TRUE';
      INPUT_LOAD='(-0.01,0.01)';
      OUTPUT_LOAD='(1.0,-1.0)';
    'DDR2_DQ'<41>:
      PIN_NUMBER='(0,0,0,0,AA34,0,0,0,0,0,0,0,0,0,0,0,0,0,0,0,0,0,0,0,0,0,0,0,0,0)';
      BIDIRECTIONAL='TRUE';
      INPUT_LOAD='(-0.01,0.01)';
      OUTPUT_LOAD='(1.0,-1.0)';
    'DDR2_DQ'<40>:
      PIN_NUMBER='(0,0,0,0,U34,0,0,0,0,0,0,0,0,0,0,0,0,0,0,0,0,0,0,0,0,0,0,0,0,0)';
      BIDIRECTIONAL='TRUE';
      INPUT_LOAD='(-0.01,0.01)';
      OUTPUT_LOAD='(1.0,-1.0)';
    'DDR2_DQ'<39>:
      PIN_NUMBER='(0,0,0,0,AA38,0,0,0,0,0,0,0,0,0,0,0,0,0,0,0,0,0,0,0,0,0,0,0,0,0)';
      BIDIRECTIONAL='TRUE';
      INPUT_LOAD='(-0.01,0.01)';
      OUTPUT_LOAD='(1.0,-1.0)';
    'DDR2_DQ'<38>:
      PIN_NUMBER='(0,0,0,0,U38,0,0,0,0,0,0,0,0,0,0,0,0,0,0,0,0,0,0,0,0,0,0,0,0,0)';
      BIDIRECTIONAL='TRUE';
      INPUT_LOAD='(-0.01,0.01)';
      OUTPUT_LOAD='(1.0,-1.0)';
    'DDR2_DQ'<37>:
      PIN_NUMBER='(0,0,0,0,Y41,0,0,0,0,0,0,0,0,0,0,0,0,0,0,0,0,0,0,0,0,0,0,0,0,0)';
      BIDIRECTIONAL='TRUE';
      INPUT_LOAD='(-0.01,0.01)';
      OUTPUT_LOAD='(1.0,-1.0)';
    'DDR2_DQ'<36>:
      PIN_NUMBER='(0,0,0,0,V41,0,0,0,0,0,0,0,0,0,0,0,0,0,0,0,0,0,0,0,0,0,0,0,0,0)';
      BIDIRECTIONAL='TRUE';
      INPUT_LOAD='(-0.01,0.01)';
      OUTPUT_LOAD='(1.0,-1.0)';
    'DDR2_DQ'<35>:
      PIN_NUMBER='(0,0,0,0,Y37,0,0,0,0,0,0,0,0,0,0,0,0,0,0,0,0,0,0,0,0,0,0,0,0,0)';
      BIDIRECTIONAL='TRUE';
      INPUT_LOAD='(-0.01,0.01)';
      OUTPUT_LOAD='(1.0,-1.0)';
    'DDR2_DQ'<34>:
      PIN_NUMBER='(0,0,0,0,V37,0,0,0,0,0,0,0,0,0,0,0,0,0,0,0,0,0,0,0,0,0,0,0,0,0)';
      BIDIRECTIONAL='TRUE';
      INPUT_LOAD='(-0.01,0.01)';
      OUTPUT_LOAD='(1.0,-1.0)';
    'DDR2_DQ'<33>:
      PIN_NUMBER='(0,0,0,0,AA40,0,0,0,0,0,0,0,0,0,0,0,0,0,0,0,0,0,0,0,0,0,0,0,0,0)';
      BIDIRECTIONAL='TRUE';
      INPUT_LOAD='(-0.01,0.01)';
      OUTPUT_LOAD='(1.0,-1.0)';
    'DDR2_DQ'<32>:
      PIN_NUMBER='(0,0,0,0,U40,0,0,0,0,0,0,0,0,0,0,0,0,0,0,0,0,0,0,0,0,0,0,0,0,0)';
      BIDIRECTIONAL='TRUE';
      INPUT_LOAD='(-0.01,0.01)';
      OUTPUT_LOAD='(1.0,-1.0)';
    'DDR2_DQ'<31>:
      PIN_NUMBER='(0,0,0,0,AT65,0,0,0,0,0,0,0,0,0,0,0,0,0,0,0,0,0,0,0,0,0,0,0,0,0)';
      BIDIRECTIONAL='TRUE';
      INPUT_LOAD='(-0.01,0.01)';
      OUTPUT_LOAD='(1.0,-1.0)';
    'DDR2_DQ'<30>:
      PIN_NUMBER='(0,0,0,0,AM65,0,0,0,0,0,0,0,0,0,0,0,0,0,0,0,0,0,0,0,0,0,0,0,0,0)';
      BIDIRECTIONAL='TRUE';
      INPUT_LOAD='(-0.01,0.01)';
      OUTPUT_LOAD='(1.0,-1.0)';
    'DDR2_DQ'<29>:
      PIN_NUMBER='(0,0,0,0,AR68,0,0,0,0,0,0,0,0,0,0,0,0,0,0,0,0,0,0,0,0,0,0,0,0,0)';
      BIDIRECTIONAL='TRUE';
      INPUT_LOAD='(-0.01,0.01)';
      OUTPUT_LOAD='(1.0,-1.0)';
    'DDR2_DQ'<28>:
      PIN_NUMBER='(0,0,0,0,AN68,0,0,0,0,0,0,0,0,0,0,0,0,0,0,0,0,0,0,0,0,0,0,0,0,0)';
      BIDIRECTIONAL='TRUE';
      INPUT_LOAD='(-0.01,0.01)';
      OUTPUT_LOAD='(1.0,-1.0)';
    'DDR2_DQ'<27>:
      PIN_NUMBER='(0,0,0,0,AR64,0,0,0,0,0,0,0,0,0,0,0,0,0,0,0,0,0,0,0,0,0,0,0,0,0)';
      BIDIRECTIONAL='TRUE';
      INPUT_LOAD='(-0.01,0.01)';
      OUTPUT_LOAD='(1.0,-1.0)';
    'DDR2_DQ'<26>:
      PIN_NUMBER='(0,0,0,0,AN64,0,0,0,0,0,0,0,0,0,0,0,0,0,0,0,0,0,0,0,0,0,0,0,0,0)';
      BIDIRECTIONAL='TRUE';
      INPUT_LOAD='(-0.01,0.01)';
      OUTPUT_LOAD='(1.0,-1.0)';
    'DDR2_DQ'<25>:
      PIN_NUMBER='(0,0,0,0,AT67,0,0,0,0,0,0,0,0,0,0,0,0,0,0,0,0,0,0,0,0,0,0,0,0,0)';
      BIDIRECTIONAL='TRUE';
      INPUT_LOAD='(-0.01,0.01)';
      OUTPUT_LOAD='(1.0,-1.0)';
    'DDR2_DQ'<24>:
      PIN_NUMBER='(0,0,0,0,AM67,0,0,0,0,0,0,0,0,0,0,0,0,0,0,0,0,0,0,0,0,0,0,0,0,0)';
      BIDIRECTIONAL='TRUE';
      INPUT_LOAD='(-0.01,0.01)';
      OUTPUT_LOAD='(1.0,-1.0)';
    'DDR2_DQ'<23>:
      PIN_NUMBER='(0,0,0,0,V69,0,0,0,0,0,0,0,0,0,0,0,0,0,0,0,0,0,0,0,0,0,0,0,0,0)';
      BIDIRECTIONAL='TRUE';
      INPUT_LOAD='(-0.01,0.01)';
      OUTPUT_LOAD='(1.0,-1.0)';
    'DDR2_DQ'<22>:
      PIN_NUMBER='(0,0,0,0,T71,0,0,0,0,0,0,0,0,0,0,0,0,0,0,0,0,0,0,0,0,0,0,0,0,0)';
      BIDIRECTIONAL='TRUE';
      INPUT_LOAD='(-0.01,0.01)';
      OUTPUT_LOAD='(1.0,-1.0)';
    'DDR2_DQ'<21>:
      PIN_NUMBER='(0,0,0,0,AB71,0,0,0,0,0,0,0,0,0,0,0,0,0,0,0,0,0,0,0,0,0,0,0,0,0)';
      BIDIRECTIONAL='TRUE';
      INPUT_LOAD='(-0.01,0.01)';
      OUTPUT_LOAD='(1.0,-1.0)';
    'DDR2_DQ'<20>:
      PIN_NUMBER='(0,0,0,0,AA72,0,0,0,0,0,0,0,0,0,0,0,0,0,0,0,0,0,0,0,0,0,0,0,0,0)';
      BIDIRECTIONAL='TRUE';
      INPUT_LOAD='(-0.01,0.01)';
      OUTPUT_LOAD='(1.0,-1.0)';
    'DDR2_DQ'<19>:
      PIN_NUMBER='(0,0,0,0,T69,0,0,0,0,0,0,0,0,0,0,0,0,0,0,0,0,0,0,0,0,0,0,0,0,0)';
      BIDIRECTIONAL='TRUE';
      INPUT_LOAD='(-0.01,0.01)';
      OUTPUT_LOAD='(1.0,-1.0)';
    'DDR2_DQ'<18>:
      PIN_NUMBER='(0,0,0,0,R70,0,0,0,0,0,0,0,0,0,0,0,0,0,0,0,0,0,0,0,0,0,0,0,0,0)';
      BIDIRECTIONAL='TRUE';
      INPUT_LOAD='(-0.01,0.01)';
      OUTPUT_LOAD='(1.0,-1.0)';
    'DDR2_DQ'<17>:
      PIN_NUMBER='(0,0,0,0,AA70,0,0,0,0,0,0,0,0,0,0,0,0,0,0,0,0,0,0,0,0,0,0,0,0,0)';
      BIDIRECTIONAL='TRUE';
      INPUT_LOAD='(-0.01,0.01)';
      OUTPUT_LOAD='(1.0,-1.0)';
    'DDR2_DQ'<16>:
      PIN_NUMBER='(0,0,0,0,W72,0,0,0,0,0,0,0,0,0,0,0,0,0,0,0,0,0,0,0,0,0,0,0,0,0)';
      BIDIRECTIONAL='TRUE';
      INPUT_LOAD='(-0.01,0.01)';
      OUTPUT_LOAD='(1.0,-1.0)';
    'DDR2_DQ'<15>:
      PIN_NUMBER='(0,0,0,0,Y75,0,0,0,0,0,0,0,0,0,0,0,0,0,0,0,0,0,0,0,0,0,0,0,0,0)';
      BIDIRECTIONAL='TRUE';
      INPUT_LOAD='(-0.01,0.01)';
      OUTPUT_LOAD='(1.0,-1.0)';
    'DDR2_DQ'<14>:
      PIN_NUMBER='(0,0,0,0,AB77,0,0,0,0,0,0,0,0,0,0,0,0,0,0,0,0,0,0,0,0,0,0,0,0,0)';
      BIDIRECTIONAL='TRUE';
      INPUT_LOAD='(-0.01,0.01)';
      OUTPUT_LOAD='(1.0,-1.0)';
    'DDR2_DQ'<13>:
      PIN_NUMBER='(0,0,0,0,AE74,0,0,0,0,0,0,0,0,0,0,0,0,0,0,0,0,0,0,0,0,0,0,0,0,0)';
      BIDIRECTIONAL='TRUE';
      INPUT_LOAD='(-0.01,0.01)';
      OUTPUT_LOAD='(1.0,-1.0)';
    'DDR2_DQ'<12>:
      PIN_NUMBER='(0,0,0,0,AF75,0,0,0,0,0,0,0,0,0,0,0,0,0,0,0,0,0,0,0,0,0,0,0,0,0)';
      BIDIRECTIONAL='TRUE';
      INPUT_LOAD='(-0.01,0.01)';
      OUTPUT_LOAD='(1.0,-1.0)';
    'DDR2_DQ'<11>:
      PIN_NUMBER='(0,0,0,0,W76,0,0,0,0,0,0,0,0,0,0,0,0,0,0,0,0,0,0,0,0,0,0,0,0,0)';
      BIDIRECTIONAL='TRUE';
      INPUT_LOAD='(-0.01,0.01)';
      OUTPUT_LOAD='(1.0,-1.0)';
    'DDR2_DQ'<10>:
      PIN_NUMBER='(0,0,0,0,Y77,0,0,0,0,0,0,0,0,0,0,0,0,0,0,0,0,0,0,0,0,0,0,0,0,0)';
      BIDIRECTIONAL='TRUE';
      INPUT_LOAD='(-0.01,0.01)';
      OUTPUT_LOAD='(1.0,-1.0)';
    'DDR2_DQ'<9>:
      PIN_NUMBER='(0,0,0,0,AC74,0,0,0,0,0,0,0,0,0,0,0,0,0,0,0,0,0,0,0,0,0,0,0,0,0)';
      BIDIRECTIONAL='TRUE';
      INPUT_LOAD='(-0.01,0.01)';
      OUTPUT_LOAD='(1.0,-1.0)';
    'DDR2_DQ'<8>:
      PIN_NUMBER='(0,0,0,0,AE76,0,0,0,0,0,0,0,0,0,0,0,0,0,0,0,0,0,0,0,0,0,0,0,0,0)';
      BIDIRECTIONAL='TRUE';
      INPUT_LOAD='(-0.01,0.01)';
      OUTPUT_LOAD='(1.0,-1.0)';
    'DDR2_DQ'<7>:
      PIN_NUMBER='(0,0,0,0,AK75,0,0,0,0,0,0,0,0,0,0,0,0,0,0,0,0,0,0,0,0,0,0,0,0,0)';
      BIDIRECTIONAL='TRUE';
      INPUT_LOAD='(-0.01,0.01)';
      OUTPUT_LOAD='(1.0,-1.0)';
    'DDR2_DQ'<6>:
      PIN_NUMBER='(0,0,0,0,AM77,0,0,0,0,0,0,0,0,0,0,0,0,0,0,0,0,0,0,0,0,0,0,0,0,0)';
      BIDIRECTIONAL='TRUE';
      INPUT_LOAD='(-0.01,0.01)';
      OUTPUT_LOAD='(1.0,-1.0)';
    'DDR2_DQ'<5>:
      PIN_NUMBER='(0,0,0,0,AR74,0,0,0,0,0,0,0,0,0,0,0,0,0,0,0,0,0,0,0,0,0,0,0,0,0)';
      BIDIRECTIONAL='TRUE';
      INPUT_LOAD='(-0.01,0.01)';
      OUTPUT_LOAD='(1.0,-1.0)';
    'DDR2_DQ'<4>:
      PIN_NUMBER='(0,0,0,0,AT75,0,0,0,0,0,0,0,0,0,0,0,0,0,0,0,0,0,0,0,0,0,0,0,0,0)';
      BIDIRECTIONAL='TRUE';
      INPUT_LOAD='(-0.01,0.01)';
      OUTPUT_LOAD='(1.0,-1.0)';
    'DDR2_DQ'<3>:
      PIN_NUMBER='(0,0,0,0,AJ76,0,0,0,0,0,0,0,0,0,0,0,0,0,0,0,0,0,0,0,0,0,0,0,0,0)';
      BIDIRECTIONAL='TRUE';
      INPUT_LOAD='(-0.01,0.01)';
      OUTPUT_LOAD='(1.0,-1.0)';
    'DDR2_DQ'<2>:
      PIN_NUMBER='(0,0,0,0,AK77,0,0,0,0,0,0,0,0,0,0,0,0,0,0,0,0,0,0,0,0,0,0,0,0,0)';
      BIDIRECTIONAL='TRUE';
      INPUT_LOAD='(-0.01,0.01)';
      OUTPUT_LOAD='(1.0,-1.0)';
    'DDR2_DQ'<1>:
      PIN_NUMBER='(0,0,0,0,AN74,0,0,0,0,0,0,0,0,0,0,0,0,0,0,0,0,0,0,0,0,0,0,0,0,0)';
      BIDIRECTIONAL='TRUE';
      INPUT_LOAD='(-0.01,0.01)';
      OUTPUT_LOAD='(1.0,-1.0)';
    'DDR2_DQ'<0>:
      PIN_NUMBER='(0,0,0,0,AR76,0,0,0,0,0,0,0,0,0,0,0,0,0,0,0,0,0,0,0,0,0,0,0,0,0)';
      BIDIRECTIONAL='TRUE';
      INPUT_LOAD='(-0.01,0.01)';
      OUTPUT_LOAD='(1.0,-1.0)';
    'DDR2_DQS_DN'<17>:
      PIN_NUMBER='(0,0,0,0,AT71,0,0,0,0,0,0,0,0,0,0,0,0,0,0,0,0,0,0,0,0,0,0,0,0,0)';
      BIDIRECTIONAL='TRUE';
      INPUT_LOAD='(-0.01,0.01)';
      OUTPUT_LOAD='(1.0,-1.0)';
    'DDR2_DQS_DN'<16>:
      PIN_NUMBER='(0,0,0,0,AC24,0,0,0,0,0,0,0,0,0,0,0,0,0,0,0,0,0,0,0,0,0,0,0,0,0)';
      BIDIRECTIONAL='TRUE';
      INPUT_LOAD='(-0.01,0.01)';
      OUTPUT_LOAD='(1.0,-1.0)';
    'DDR2_DQS_DN'<15>:
      PIN_NUMBER='(0,0,0,0,AC30,0,0,0,0,0,0,0,0,0,0,0,0,0,0,0,0,0,0,0,0,0,0,0,0,0)';
      BIDIRECTIONAL='TRUE';
      INPUT_LOAD='(-0.01,0.01)';
      OUTPUT_LOAD='(1.0,-1.0)';
    'DDR2_DQS_DN'<14>:
      PIN_NUMBER='(0,0,0,0,T33,0,0,0,0,0,0,0,0,0,0,0,0,0,0,0,0,0,0,0,0,0,0,0,0,0)';
      BIDIRECTIONAL='TRUE';
      INPUT_LOAD='(-0.01,0.01)';
      OUTPUT_LOAD='(1.0,-1.0)';
    'DDR2_DQS_DN'<13>:
      PIN_NUMBER='(0,0,0,0,T39,0,0,0,0,0,0,0,0,0,0,0,0,0,0,0,0,0,0,0,0,0,0,0,0,0)';
      BIDIRECTIONAL='TRUE';
      INPUT_LOAD='(-0.01,0.01)';
      OUTPUT_LOAD='(1.0,-1.0)';
    'DDR2_DQS_DN'<12>:
      PIN_NUMBER='(0,0,0,0,AL66,0,0,0,0,0,0,0,0,0,0,0,0,0,0,0,0,0,0,0,0,0,0,0,0,0)';
      BIDIRECTIONAL='TRUE';
      INPUT_LOAD='(-0.01,0.01)';
      OUTPUT_LOAD='(1.0,-1.0)';
    'DDR2_DQS_DN'<11>:
      PIN_NUMBER='(0,0,0,0,U72,0,0,0,0,0,0,0,0,0,0,0,0,0,0,0,0,0,0,0,0,0,0,0,0,0)';
      BIDIRECTIONAL='TRUE';
      INPUT_LOAD='(-0.01,0.01)';
      OUTPUT_LOAD='(1.0,-1.0)';
    'DDR2_DQS_DN'<10>:
      PIN_NUMBER='(0,0,0,0,AD77,0,0,0,0,0,0,0,0,0,0,0,0,0,0,0,0,0,0,0,0,0,0,0,0,0)';
      BIDIRECTIONAL='TRUE';
      INPUT_LOAD='(-0.01,0.01)';
      OUTPUT_LOAD='(1.0,-1.0)';
    'DDR2_DQS_DN'<9>:
      PIN_NUMBER='(0,0,0,0,AP77,0,0,0,0,0,0,0,0,0,0,0,0,0,0,0,0,0,0,0,0,0,0,0,0,0)';
      BIDIRECTIONAL='TRUE';
      INPUT_LOAD='(-0.01,0.01)';
      OUTPUT_LOAD='(1.0,-1.0)';
    'DDR2_DQS_DN'<8>:
      PIN_NUMBER='(0,0,0,0,BB71,0,0,0,0,0,0,0,0,0,0,0,0,0,0,0,0,0,0,0,0,0,0,0,0,0)';
      BIDIRECTIONAL='TRUE';
      INPUT_LOAD='(-0.01,0.01)';
      OUTPUT_LOAD='(1.0,-1.0)';
    'DDR2_DQS_DN'<7>:
      PIN_NUMBER='(0,0,0,0,AJ24,0,0,0,0,0,0,0,0,0,0,0,0,0,0,0,0,0,0,0,0,0,0,0,0,0)';
      BIDIRECTIONAL='TRUE';
      INPUT_LOAD='(-0.01,0.01)';
      OUTPUT_LOAD='(1.0,-1.0)';
    'DDR2_DQS_DN'<6>:
      PIN_NUMBER='(0,0,0,0,AJ30,0,0,0,0,0,0,0,0,0,0,0,0,0,0,0,0,0,0,0,0,0,0,0,0,0)';
      BIDIRECTIONAL='TRUE';
      INPUT_LOAD='(-0.01,0.01)';
      OUTPUT_LOAD='(1.0,-1.0)';
    'DDR2_DQS_DN'<5>:
      PIN_NUMBER='(0,0,0,0,AB33,0,0,0,0,0,0,0,0,0,0,0,0,0,0,0,0,0,0,0,0,0,0,0,0,0)';
      BIDIRECTIONAL='TRUE';
      INPUT_LOAD='(-0.01,0.01)';
      OUTPUT_LOAD='(1.0,-1.0)';
    'DDR2_DQS_DN'<4>:
      PIN_NUMBER='(0,0,0,0,AB39,0,0,0,0,0,0,0,0,0,0,0,0,0,0,0,0,0,0,0,0,0,0,0,0,0)';
      BIDIRECTIONAL='TRUE';
      INPUT_LOAD='(-0.01,0.01)';
      OUTPUT_LOAD='(1.0,-1.0)';
    'DDR2_DQS_DN'<3>:
      PIN_NUMBER='(0,0,0,0,AU66,0,0,0,0,0,0,0,0,0,0,0,0,0,0,0,0,0,0,0,0,0,0,0,0,0)';
      BIDIRECTIONAL='TRUE';
      INPUT_LOAD='(-0.01,0.01)';
      OUTPUT_LOAD='(1.0,-1.0)';
    'DDR2_DQS_DN'<2>:
      PIN_NUMBER='(0,0,0,0,Y69,0,0,0,0,0,0,0,0,0,0,0,0,0,0,0,0,0,0,0,0,0,0,0,0,0)';
      BIDIRECTIONAL='TRUE';
      INPUT_LOAD='(-0.01,0.01)';
      OUTPUT_LOAD='(1.0,-1.0)';
    'DDR2_DQS_DN'<1>:
      PIN_NUMBER='(0,0,0,0,AA74,0,0,0,0,0,0,0,0,0,0,0,0,0,0,0,0,0,0,0,0,0,0,0,0,0)';
      BIDIRECTIONAL='TRUE';
      INPUT_LOAD='(-0.01,0.01)';
      OUTPUT_LOAD='(1.0,-1.0)';
    'DDR2_DQS_DN'<0>:
      PIN_NUMBER='(0,0,0,0,AL74,0,0,0,0,0,0,0,0,0,0,0,0,0,0,0,0,0,0,0,0,0,0,0,0,0)';
      BIDIRECTIONAL='TRUE';
      INPUT_LOAD='(-0.01,0.01)';
      OUTPUT_LOAD='(1.0,-1.0)';
    'DDR2_DQS_DP'<17>:
      PIN_NUMBER='(0,0,0,0,AV71,0,0,0,0,0,0,0,0,0,0,0,0,0,0,0,0,0,0,0,0,0,0,0,0,0)';
      BIDIRECTIONAL='TRUE';
      INPUT_LOAD='(-0.01,0.01)';
      OUTPUT_LOAD='(1.0,-1.0)';
    'DDR2_DQS_DP'<16>:
      PIN_NUMBER='(0,0,0,0,AE24,0,0,0,0,0,0,0,0,0,0,0,0,0,0,0,0,0,0,0,0,0,0,0,0,0)';
      BIDIRECTIONAL='TRUE';
      INPUT_LOAD='(-0.01,0.01)';
      OUTPUT_LOAD='(1.0,-1.0)';
    'DDR2_DQS_DP'<15>:
      PIN_NUMBER='(0,0,0,0,AE30,0,0,0,0,0,0,0,0,0,0,0,0,0,0,0,0,0,0,0,0,0,0,0,0,0)';
      BIDIRECTIONAL='TRUE';
      INPUT_LOAD='(-0.01,0.01)';
      OUTPUT_LOAD='(1.0,-1.0)';
    'DDR2_DQS_DP'<14>:
      PIN_NUMBER='(0,0,0,0,V33,0,0,0,0,0,0,0,0,0,0,0,0,0,0,0,0,0,0,0,0,0,0,0,0,0)';
      BIDIRECTIONAL='TRUE';
      INPUT_LOAD='(-0.01,0.01)';
      OUTPUT_LOAD='(1.0,-1.0)';
    'DDR2_DQS_DP'<13>:
      PIN_NUMBER='(0,0,0,0,V39,0,0,0,0,0,0,0,0,0,0,0,0,0,0,0,0,0,0,0,0,0,0,0,0,0)';
      BIDIRECTIONAL='TRUE';
      INPUT_LOAD='(-0.01,0.01)';
      OUTPUT_LOAD='(1.0,-1.0)';
    'DDR2_DQS_DP'<12>:
      PIN_NUMBER='(0,0,0,0,AN66,0,0,0,0,0,0,0,0,0,0,0,0,0,0,0,0,0,0,0,0,0,0,0,0,0)';
      BIDIRECTIONAL='TRUE';
      INPUT_LOAD='(-0.01,0.01)';
      OUTPUT_LOAD='(1.0,-1.0)';
    'DDR2_DQS_DP'<11>:
      PIN_NUMBER='(0,0,0,0,V71,0,0,0,0,0,0,0,0,0,0,0,0,0,0,0,0,0,0,0,0,0,0,0,0,0)';
      BIDIRECTIONAL='TRUE';
      INPUT_LOAD='(-0.01,0.01)';
      OUTPUT_LOAD='(1.0,-1.0)';
    'DDR2_DQS_DP'<10>:
      PIN_NUMBER='(0,0,0,0,AC76,0,0,0,0,0,0,0,0,0,0,0,0,0,0,0,0,0,0,0,0,0,0,0,0,0)';
      BIDIRECTIONAL='TRUE';
      INPUT_LOAD='(-0.01,0.01)';
      OUTPUT_LOAD='(1.0,-1.0)';
    'DDR2_DQS_DP'<9>:
      PIN_NUMBER='(0,0,0,0,AN76,0,0,0,0,0,0,0,0,0,0,0,0,0,0,0,0,0,0,0,0,0,0,0,0,0)';
      BIDIRECTIONAL='TRUE';
      INPUT_LOAD='(-0.01,0.01)';
      OUTPUT_LOAD='(1.0,-1.0)';
    'DDR2_DQS_DP'<8>:
      PIN_NUMBER='(0,0,0,0,AY71,0,0,0,0,0,0,0,0,0,0,0,0,0,0,0,0,0,0,0,0,0,0,0,0,0)';
      BIDIRECTIONAL='TRUE';
      INPUT_LOAD='(-0.01,0.01)';
      OUTPUT_LOAD='(1.0,-1.0)';
    'DDR2_DQS_DP'<7>:
      PIN_NUMBER='(0,0,0,0,AG24,0,0,0,0,0,0,0,0,0,0,0,0,0,0,0,0,0,0,0,0,0,0,0,0,0)';
      BIDIRECTIONAL='TRUE';
      INPUT_LOAD='(-0.01,0.01)';
      OUTPUT_LOAD='(1.0,-1.0)';
    'DDR2_DQS_DP'<6>:
      PIN_NUMBER='(0,0,0,0,AG30,0,0,0,0,0,0,0,0,0,0,0,0,0,0,0,0,0,0,0,0,0,0,0,0,0)';
      BIDIRECTIONAL='TRUE';
      INPUT_LOAD='(-0.01,0.01)';
      OUTPUT_LOAD='(1.0,-1.0)';
    'DDR2_DQS_DP'<5>:
      PIN_NUMBER='(0,0,0,0,Y33,0,0,0,0,0,0,0,0,0,0,0,0,0,0,0,0,0,0,0,0,0,0,0,0,0)';
      BIDIRECTIONAL='TRUE';
      INPUT_LOAD='(-0.01,0.01)';
      OUTPUT_LOAD='(1.0,-1.0)';
    'DDR2_DQS_DP'<4>:
      PIN_NUMBER='(0,0,0,0,Y39,0,0,0,0,0,0,0,0,0,0,0,0,0,0,0,0,0,0,0,0,0,0,0,0,0)';
      BIDIRECTIONAL='TRUE';
      INPUT_LOAD='(-0.01,0.01)';
      OUTPUT_LOAD='(1.0,-1.0)';
    'DDR2_DQS_DP'<3>:
      PIN_NUMBER='(0,0,0,0,AR66,0,0,0,0,0,0,0,0,0,0,0,0,0,0,0,0,0,0,0,0,0,0,0,0,0)';
      BIDIRECTIONAL='TRUE';
      INPUT_LOAD='(-0.01,0.01)';
      OUTPUT_LOAD='(1.0,-1.0)';
    'DDR2_DQS_DP'<2>:
      PIN_NUMBER='(0,0,0,0,W70,0,0,0,0,0,0,0,0,0,0,0,0,0,0,0,0,0,0,0,0,0,0,0,0,0)';
      BIDIRECTIONAL='TRUE';
      INPUT_LOAD='(-0.01,0.01)';
      OUTPUT_LOAD='(1.0,-1.0)';
    'DDR2_DQS_DP'<1>:
      PIN_NUMBER='(0,0,0,0,AB75,0,0,0,0,0,0,0,0,0,0,0,0,0,0,0,0,0,0,0,0,0,0,0,0,0)';
      BIDIRECTIONAL='TRUE';
      INPUT_LOAD='(-0.01,0.01)';
      OUTPUT_LOAD='(1.0,-1.0)';
    'DDR2_DQS_DP'<0>:
      PIN_NUMBER='(0,0,0,0,AM75,0,0,0,0,0,0,0,0,0,0,0,0,0,0,0,0,0,0,0,0,0,0,0,0,0)';
      BIDIRECTIONAL='TRUE';
      INPUT_LOAD='(-0.01,0.01)';
      OUTPUT_LOAD='(1.0,-1.0)';
    'DDR2_ECC'<7>:
      PIN_NUMBER='(0,0,0,0,BA70,0,0,0,0,0,0,0,0,0,0,0,0,0,0,0,0,0,0,0,0,0,0,0,0,0)';
      BIDIRECTIONAL='TRUE';
      INPUT_LOAD='(-0.01,0.01)';
      OUTPUT_LOAD='(1.0,-1.0)';
    'DDR2_ECC'<6>:
      PIN_NUMBER='(0,0,0,0,AU70,0,0,0,0,0,0,0,0,0,0,0,0,0,0,0,0,0,0,0,0,0,0,0,0,0)';
      BIDIRECTIONAL='TRUE';
      INPUT_LOAD='(-0.01,0.01)';
      OUTPUT_LOAD='(1.0,-1.0)';
    'DDR2_ECC'<5>:
      PIN_NUMBER='(0,0,0,0,AY73,0,0,0,0,0,0,0,0,0,0,0,0,0,0,0,0,0,0,0,0,0,0,0,0,0)';
      BIDIRECTIONAL='TRUE';
      INPUT_LOAD='(-0.01,0.01)';
      OUTPUT_LOAD='(1.0,-1.0)';
    'DDR2_ECC'<4>:
      PIN_NUMBER='(0,0,0,0,AV73,0,0,0,0,0,0,0,0,0,0,0,0,0,0,0,0,0,0,0,0,0,0,0,0,0)';
      BIDIRECTIONAL='TRUE';
      INPUT_LOAD='(-0.01,0.01)';
      OUTPUT_LOAD='(1.0,-1.0)';
    'DDR2_ECC'<3>:
      PIN_NUMBER='(0,0,0,0,AY69,0,0,0,0,0,0,0,0,0,0,0,0,0,0,0,0,0,0,0,0,0,0,0,0,0)';
      BIDIRECTIONAL='TRUE';
      INPUT_LOAD='(-0.01,0.01)';
      OUTPUT_LOAD='(1.0,-1.0)';
    'DDR2_ECC'<2>:
      PIN_NUMBER='(0,0,0,0,AV69,0,0,0,0,0,0,0,0,0,0,0,0,0,0,0,0,0,0,0,0,0,0,0,0,0)';
      BIDIRECTIONAL='TRUE';
      INPUT_LOAD='(-0.01,0.01)';
      OUTPUT_LOAD='(1.0,-1.0)';
    'DDR2_ECC'<1>:
      PIN_NUMBER='(0,0,0,0,BA72,0,0,0,0,0,0,0,0,0,0,0,0,0,0,0,0,0,0,0,0,0,0,0,0,0)';
      BIDIRECTIONAL='TRUE';
      INPUT_LOAD='(-0.01,0.01)';
      OUTPUT_LOAD='(1.0,-1.0)';
    'DDR2_ECC'<0>:
      PIN_NUMBER='(0,0,0,0,AU72,0,0,0,0,0,0,0,0,0,0,0,0,0,0,0,0,0,0,0,0,0,0,0,0,0)';
      BIDIRECTIONAL='TRUE';
      INPUT_LOAD='(-0.01,0.01)';
      OUTPUT_LOAD='(1.0,-1.0)';
    'DDR2_MA'<17>:
      PIN_NUMBER='(0,0,0,0,AC46,0,0,0,0,0,0,0,0,0,0,0,0,0,0,0,0,0,0,0,0,0,0,0,0,0)';
      OUTPUT_LOAD='(1.0,-1.0)';
    'DDR2_MA'<16>:
      PIN_NUMBER='(0,0,0,0,AA52,0,0,0,0,0,0,0,0,0,0,0,0,0,0,0,0,0,0,0,0,0,0,0,0,0)';
      OUTPUT_LOAD='(1.0,-1.0)';
    'DDR2_MA'<15>:
      PIN_NUMBER='(0,0,0,0,AE54,0,0,0,0,0,0,0,0,0,0,0,0,0,0,0,0,0,0,0,0,0,0,0,0,0)';
      OUTPUT_LOAD='(1.0,-1.0)';
    'DDR2_MA'<14>:
      PIN_NUMBER='(0,0,0,0,W50,0,0,0,0,0,0,0,0,0,0,0,0,0,0,0,0,0,0,0,0,0,0,0,0,0)';
      OUTPUT_LOAD='(1.0,-1.0)';
    'DDR2_MA'<13>:
      PIN_NUMBER='(0,0,0,0,AD53,0,0,0,0,0,0,0,0,0,0,0,0,0,0,0,0,0,0,0,0,0,0,0,0,0)';
      OUTPUT_LOAD='(1.0,-1.0)';
    'DDR2_MA'<12>:
      PIN_NUMBER='(0,0,0,0,AG62,0,0,0,0,0,0,0,0,0,0,0,0,0,0,0,0,0,0,0,0,0,0,0,0,0)';
      OUTPUT_LOAD='(1.0,-1.0)';
    'DDR2_MA'<11>:
      PIN_NUMBER='(0,0,0,0,AG60,0,0,0,0,0,0,0,0,0,0,0,0,0,0,0,0,0,0,0,0,0,0,0,0,0)';
      OUTPUT_LOAD='(1.0,-1.0)';
    'DDR2_MA'<10>:
      PIN_NUMBER='(0,0,0,0,AD55,0,0,0,0,0,0,0,0,0,0,0,0,0,0,0,0,0,0,0,0,0,0,0,0,0)';
      OUTPUT_LOAD='(1.0,-1.0)';
    'DDR2_MA'<9>:
      PIN_NUMBER='(0,0,0,0,AG58,0,0,0,0,0,0,0,0,0,0,0,0,0,0,0,0,0,0,0,0,0,0,0,0,0)';
      OUTPUT_LOAD='(1.0,-1.0)';
    'DDR2_MA'<8>:
      PIN_NUMBER='(0,0,0,0,AD59,0,0,0,0,0,0,0,0,0,0,0,0,0,0,0,0,0,0,0,0,0,0,0,0,0)';
      OUTPUT_LOAD='(1.0,-1.0)';
    'DDR2_MA'<7>:
      PIN_NUMBER='(0,0,0,0,AE60,0,0,0,0,0,0,0,0,0,0,0,0,0,0,0,0,0,0,0,0,0,0,0,0,0)';
      OUTPUT_LOAD='(1.0,-1.0)';
    'DDR2_MA'<6>:
      PIN_NUMBER='(0,0,0,0,AB59,0,0,0,0,0,0,0,0,0,0,0,0,0,0,0,0,0,0,0,0,0,0,0,0,0)';
      OUTPUT_LOAD='(1.0,-1.0)';
    'DDR2_MA'<5>:
      PIN_NUMBER='(0,0,0,0,V59,0,0,0,0,0,0,0,0,0,0,0,0,0,0,0,0,0,0,0,0,0,0,0,0,0)';
      OUTPUT_LOAD='(1.0,-1.0)';
    'DDR2_MA'<4>:
      PIN_NUMBER='(0,0,0,0,AA58,0,0,0,0,0,0,0,0,0,0,0,0,0,0,0,0,0,0,0,0,0,0,0,0,0)';
      OUTPUT_LOAD='(1.0,-1.0)';
    'DDR2_MA'<3>:
      PIN_NUMBER='(0,0,0,0,W58,0,0,0,0,0,0,0,0,0,0,0,0,0,0,0,0,0,0,0,0,0,0,0,0,0)';
      OUTPUT_LOAD='(1.0,-1.0)';
    'DDR2_MA'<2>:
      PIN_NUMBER='(0,0,0,0,AD57,0,0,0,0,0,0,0,0,0,0,0,0,0,0,0,0,0,0,0,0,0,0,0,0,0)';
      OUTPUT_LOAD='(1.0,-1.0)';
    'DDR2_MA'<1>:
      PIN_NUMBER='(0,0,0,0,AE58,0,0,0,0,0,0,0,0,0,0,0,0,0,0,0,0,0,0,0,0,0,0,0,0,0)';
      OUTPUT_LOAD='(1.0,-1.0)';
    'DDR2_MA'<0>:
      PIN_NUMBER='(0,0,0,0,AB53,0,0,0,0,0,0,0,0,0,0,0,0,0,0,0,0,0,0,0,0,0,0,0,0,0)';
      OUTPUT_LOAD='(1.0,-1.0)';
    'DDR2_ODT'<3>:
      PIN_NUMBER='(0,0,0,0,AB47,0,0,0,0,0,0,0,0,0,0,0,0,0,0,0,0,0,0,0,0,0,0,0,0,0)';
      OUTPUT_LOAD='(1.0,-1.0)';
    'DDR2_ODT'<2>:
      PIN_NUMBER='(0,0,0,0,V49,0,0,0,0,0,0,0,0,0,0,0,0,0,0,0,0,0,0,0,0,0,0,0,0,0)';
      OUTPUT_LOAD='(1.0,-1.0)';
    'DDR2_ODT'<1>:
      PIN_NUMBER='(0,0,0,0,AA48,0,0,0,0,0,0,0,0,0,0,0,0,0,0,0,0,0,0,0,0,0,0,0,0,0)';
      OUTPUT_LOAD='(1.0,-1.0)';
    'DDR2_ODT'<0>:
      PIN_NUMBER='(0,0,0,0,AA50,0,0,0,0,0,0,0,0,0,0,0,0,0,0,0,0,0,0,0,0,0,0,0,0,0)';
      OUTPUT_LOAD='(1.0,-1.0)';
    'DDR2_PAR':
      PIN_NUMBER='(0,0,0,0,V53,0,0,0,0,0,0,0,0,0,0,0,0,0,0,0,0,0,0,0,0,0,0,0,0,0)';
      OUTPUT_LOAD='(1.0,-1.0)';
    'DDR345_DRAM_PWR_OK':
      PIN_NUMBER='(CR28,0,0,0,0,0,0,0,0,0,0,0,0,0,0,0,0,0,0,0,0,0,0,0,0,0,0,0,0,0)';
      INPUT_LOAD='(-0.01,0.01)';
    'DDR345_RCOMP'<2>:
      PIN_NUMBER='(DD49,0,0,0,0,0,0,0,0,0,0,0,0,0,0,0,0,0,0,0,0,0,0,0,0,0,0,0,0,0)';
      BIDIRECTIONAL='TRUE';
      INPUT_LOAD='(-0.01,0.01)';
      OUTPUT_LOAD='(1.0,-1.0)';
    'DDR345_RCOMP'<1>:
      PIN_NUMBER='(DD47,0,0,0,0,0,0,0,0,0,0,0,0,0,0,0,0,0,0,0,0,0,0,0,0,0,0,0,0,0)';
      BIDIRECTIONAL='TRUE';
      INPUT_LOAD='(-0.01,0.01)';
      OUTPUT_LOAD='(1.0,-1.0)';
    'DDR345_RCOMP'<0>:
      PIN_NUMBER='(DC48,0,0,0,0,0,0,0,0,0,0,0,0,0,0,0,0,0,0,0,0,0,0,0,0,0,0,0,0,0)';
      BIDIRECTIONAL='TRUE';
      INPUT_LOAD='(-0.01,0.01)';
      OUTPUT_LOAD='(1.0,-1.0)';
    'DDR345_RESET_N':
      PIN_NUMBER='(DV63,0,0,0,0,0,0,0,0,0,0,0,0,0,0,0,0,0,0,0,0,0,0,0,0,0,0,0,0,0)';
      OUTPUT_LOAD='(1.0,-1.0)';
    'DDR345_SPDSCL':
      PIN_NUMBER='(AE18,0,0,0,0,0,0,0,0,0,0,0,0,0,0,0,0,0,0,0,0,0,0,0,0,0,0,0,0,0)';
      BIDIRECTIONAL='TRUE';
      INPUT_LOAD='(-0.01,0.01)';
      OUTPUT_LOAD='(1.0,-1.0)';
    'DDR345_SPDSDA':
      PIN_NUMBER='(AD17,0,0,0,0,0,0,0,0,0,0,0,0,0,0,0,0,0,0,0,0,0,0,0,0,0,0,0,0,0)';
      BIDIRECTIONAL='TRUE';
      INPUT_LOAD='(-0.01,0.01)';
      OUTPUT_LOAD='(1.0,-1.0)';
    'DDR3_ACT_N':
      PIN_NUMBER='(0,0,0,0,0,DW60,0,0,0,0,0,0,0,0,0,0,0,0,0,0,0,0,0,0,0,0,0,0,0,0)';
      OUTPUT_LOAD='(1.0,-1.0)';
    'DDR3_ALERT_N':
      PIN_NUMBER='(0,0,0,0,0,ED63,0,0,0,0,0,0,0,0,0,0,0,0,0,0,0,0,0,0,0,0,0,0,0,0)';
      INPUT_LOAD='(-0.01,0.01)';
    'DDR3_BA'<1>:
      PIN_NUMBER='(0,0,0,0,0,EA54,0,0,0,0,0,0,0,0,0,0,0,0,0,0,0,0,0,0,0,0,0,0,0,0)';
      OUTPUT_LOAD='(1.0,-1.0)';
    'DDR3_BA'<0>:
      PIN_NUMBER='(0,0,0,0,0,EE52,0,0,0,0,0,0,0,0,0,0,0,0,0,0,0,0,0,0,0,0,0,0,0,0)';
      OUTPUT_LOAD='(1.0,-1.0)';
    'DDR3_BG'<1>:
      PIN_NUMBER='(0,0,0,0,0,DW62,0,0,0,0,0,0,0,0,0,0,0,0,0,0,0,0,0,0,0,0,0,0,0,0)';
      OUTPUT_LOAD='(1.0,-1.0)';
    'DDR3_BG'<0>:
      PIN_NUMBER='(0,0,0,0,0,ED61,0,0,0,0,0,0,0,0,0,0,0,0,0,0,0,0,0,0,0,0,0,0,0,0)';
      OUTPUT_LOAD='(1.0,-1.0)';
    'DDR3_CAVREF':
      PIN_NUMBER='(CP61,0,0,0,0,0,0,0,0,0,0,0,0,0,0,0,0,0,0,0,0,0,0,0,0,0,0,0,0,0)';
      OUTPUT_LOAD='(1.0,-1.0)';
    'DDR3_CID'<2>:
      PIN_NUMBER='(0,0,0,0,0,DV47,0,0,0,0,0,0,0,0,0,0,0,0,0,0,0,0,0,0,0,0,0,0,0,0)';
      OUTPUT_LOAD='(1.0,-1.0)';
    'DDR3_CKE'<3>:
      PIN_NUMBER='(0,0,0,0,0,EB63,0,0,0,0,0,0,0,0,0,0,0,0,0,0,0,0,0,0,0,0,0,0,0,0)';
      OUTPUT_LOAD='(1.0,-1.0)';
    'DDR3_CKE'<2>:
      PIN_NUMBER='(0,0,0,0,0,EA62,0,0,0,0,0,0,0,0,0,0,0,0,0,0,0,0,0,0,0,0,0,0,0,0)';
      OUTPUT_LOAD='(1.0,-1.0)';
    'DDR3_CKE'<1>:
      PIN_NUMBER='(0,0,0,0,0,EF63,0,0,0,0,0,0,0,0,0,0,0,0,0,0,0,0,0,0,0,0,0,0,0,0)';
      OUTPUT_LOAD='(1.0,-1.0)';
    'DDR3_CKE'<0>:
      PIN_NUMBER='(0,0,0,0,0,EE62,0,0,0,0,0,0,0,0,0,0,0,0,0,0,0,0,0,0,0,0,0,0,0,0)';
      OUTPUT_LOAD='(1.0,-1.0)';
    'DDR3_CLK_DN'<3>:
      PIN_NUMBER='(0,0,0,0,0,EF57,0,0,0,0,0,0,0,0,0,0,0,0,0,0,0,0,0,0,0,0,0,0,0,0)';
      OUTPUT_LOAD='(1.0,-1.0)';
    'DDR3_CLK_DN'<2>:
      PIN_NUMBER='(0,0,0,0,0,DW56,0,0,0,0,0,0,0,0,0,0,0,0,0,0,0,0,0,0,0,0,0,0,0,0)';
      OUTPUT_LOAD='(1.0,-1.0)';
    'DDR3_CLK_DN'<1>:
      PIN_NUMBER='(0,0,0,0,0,EF55,0,0,0,0,0,0,0,0,0,0,0,0,0,0,0,0,0,0,0,0,0,0,0,0)';
      OUTPUT_LOAD='(1.0,-1.0)';
    'DDR3_CLK_DN'<0>:
      PIN_NUMBER='(0,0,0,0,0,ED55,0,0,0,0,0,0,0,0,0,0,0,0,0,0,0,0,0,0,0,0,0,0,0,0)';
      OUTPUT_LOAD='(1.0,-1.0)';
    'DDR3_CLK_DP'<3>:
      PIN_NUMBER='(0,0,0,0,0,EE56,0,0,0,0,0,0,0,0,0,0,0,0,0,0,0,0,0,0,0,0,0,0,0,0)';
      OUTPUT_LOAD='(1.0,-1.0)';
    'DDR3_CLK_DP'<2>:
      PIN_NUMBER='(0,0,0,0,0,EA56,0,0,0,0,0,0,0,0,0,0,0,0,0,0,0,0,0,0,0,0,0,0,0,0)';
      OUTPUT_LOAD='(1.0,-1.0)';
    'DDR3_CLK_DP'<1>:
      PIN_NUMBER='(0,0,0,0,0,EE54,0,0,0,0,0,0,0,0,0,0,0,0,0,0,0,0,0,0,0,0,0,0,0,0)';
      OUTPUT_LOAD='(1.0,-1.0)';
    'DDR3_CLK_DP'<0>:
      PIN_NUMBER='(0,0,0,0,0,EB55,0,0,0,0,0,0,0,0,0,0,0,0,0,0,0,0,0,0,0,0,0,0,0,0)';
      OUTPUT_LOAD='(1.0,-1.0)';
    'DDR3_CS_N'<7>:
      PIN_NUMBER='(0,0,0,0,0,EB45,0,0,0,0,0,0,0,0,0,0,0,0,0,0,0,0,0,0,0,0,0,0,0,0)';
      OUTPUT_LOAD='(1.0,-1.0)';
    'DDR3_CS_N'<6>:
      PIN_NUMBER='(0,0,0,0,0,DV45,0,0,0,0,0,0,0,0,0,0,0,0,0,0,0,0,0,0,0,0,0,0,0,0)';
      OUTPUT_LOAD='(1.0,-1.0)';
    'DDR3_CS_N'<5>:
      PIN_NUMBER='(0,0,0,0,0,EB49,0,0,0,0,0,0,0,0,0,0,0,0,0,0,0,0,0,0,0,0,0,0,0,0)';
      OUTPUT_LOAD='(1.0,-1.0)';
    'DDR3_CS_N'<4>:
      PIN_NUMBER='(0,0,0,0,0,EB51,0,0,0,0,0,0,0,0,0,0,0,0,0,0,0,0,0,0,0,0,0,0,0,0)';
      OUTPUT_LOAD='(1.0,-1.0)';
    'DDR3_CS_N'<3>:
      PIN_NUMBER='(0,0,0,0,0,EB47,0,0,0,0,0,0,0,0,0,0,0,0,0,0,0,0,0,0,0,0,0,0,0,0)';
      OUTPUT_LOAD='(1.0,-1.0)';
    'DDR3_CS_N'<2>:
      PIN_NUMBER='(0,0,0,0,0,ED47,0,0,0,0,0,0,0,0,0,0,0,0,0,0,0,0,0,0,0,0,0,0,0,0)';
      OUTPUT_LOAD='(1.0,-1.0)';
    'DDR3_CS_N'<1>:
      PIN_NUMBER='(0,0,0,0,0,ED49,0,0,0,0,0,0,0,0,0,0,0,0,0,0,0,0,0,0,0,0,0,0,0,0)';
      OUTPUT_LOAD='(1.0,-1.0)';
    'DDR3_CS_N'<0>:
      PIN_NUMBER='(0,0,0,0,0,EF51,0,0,0,0,0,0,0,0,0,0,0,0,0,0,0,0,0,0,0,0,0,0,0,0)';
      OUTPUT_LOAD='(1.0,-1.0)';
    'DDR3_DQ'<63>:
      PIN_NUMBER='(0,0,0,0,0,DW22,0,0,0,0,0,0,0,0,0,0,0,0,0,0,0,0,0,0,0,0,0,0,0,0)';
      BIDIRECTIONAL='TRUE';
      INPUT_LOAD='(-0.01,0.01)';
      OUTPUT_LOAD='(1.0,-1.0)';
    'DDR3_DQ'<62>:
      PIN_NUMBER='(0,0,0,0,0,EC22,0,0,0,0,0,0,0,0,0,0,0,0,0,0,0,0,0,0,0,0,0,0,0,0)';
      BIDIRECTIONAL='TRUE';
      INPUT_LOAD='(-0.01,0.01)';
      OUTPUT_LOAD='(1.0,-1.0)';
    'DDR3_DQ'<61>:
      PIN_NUMBER='(0,0,0,0,0,DT25,0,0,0,0,0,0,0,0,0,0,0,0,0,0,0,0,0,0,0,0,0,0,0,0)';
      BIDIRECTIONAL='TRUE';
      INPUT_LOAD='(-0.01,0.01)';
      OUTPUT_LOAD='(1.0,-1.0)';
    'DDR3_DQ'<60>:
      PIN_NUMBER='(0,0,0,0,0,DP25,0,0,0,0,0,0,0,0,0,0,0,0,0,0,0,0,0,0,0,0,0,0,0,0)';
      BIDIRECTIONAL='TRUE';
      INPUT_LOAD='(-0.01,0.01)';
      OUTPUT_LOAD='(1.0,-1.0)';
    'DDR3_DQ'<59>:
      PIN_NUMBER='(0,0,0,0,0,EB21,0,0,0,0,0,0,0,0,0,0,0,0,0,0,0,0,0,0,0,0,0,0,0,0)';
      BIDIRECTIONAL='TRUE';
      INPUT_LOAD='(-0.01,0.01)';
      OUTPUT_LOAD='(1.0,-1.0)';
    'DDR3_DQ'<58>:
      PIN_NUMBER='(0,0,0,0,0,DY21,0,0,0,0,0,0,0,0,0,0,0,0,0,0,0,0,0,0,0,0,0,0,0,0)';
      BIDIRECTIONAL='TRUE';
      INPUT_LOAD='(-0.01,0.01)';
      OUTPUT_LOAD='(1.0,-1.0)';
    'DDR3_DQ'<57>:
      PIN_NUMBER='(0,0,0,0,0,DU24,0,0,0,0,0,0,0,0,0,0,0,0,0,0,0,0,0,0,0,0,0,0,0,0)';
      BIDIRECTIONAL='TRUE';
      INPUT_LOAD='(-0.01,0.01)';
      OUTPUT_LOAD='(1.0,-1.0)';
    'DDR3_DQ'<56>:
      PIN_NUMBER='(0,0,0,0,0,DN24,0,0,0,0,0,0,0,0,0,0,0,0,0,0,0,0,0,0,0,0,0,0,0,0)';
      BIDIRECTIONAL='TRUE';
      INPUT_LOAD='(-0.01,0.01)';
      OUTPUT_LOAD='(1.0,-1.0)';
    'DDR3_DQ'<55>:
      PIN_NUMBER='(0,0,0,0,0,DU28,0,0,0,0,0,0,0,0,0,0,0,0,0,0,0,0,0,0,0,0,0,0,0,0)';
      BIDIRECTIONAL='TRUE';
      INPUT_LOAD='(-0.01,0.01)';
      OUTPUT_LOAD='(1.0,-1.0)';
    'DDR3_DQ'<54>:
      PIN_NUMBER='(0,0,0,0,0,DN28,0,0,0,0,0,0,0,0,0,0,0,0,0,0,0,0,0,0,0,0,0,0,0,0)';
      BIDIRECTIONAL='TRUE';
      INPUT_LOAD='(-0.01,0.01)';
      OUTPUT_LOAD='(1.0,-1.0)';
    'DDR3_DQ'<53>:
      PIN_NUMBER='(0,0,0,0,0,DT31,0,0,0,0,0,0,0,0,0,0,0,0,0,0,0,0,0,0,0,0,0,0,0,0)';
      BIDIRECTIONAL='TRUE';
      INPUT_LOAD='(-0.01,0.01)';
      OUTPUT_LOAD='(1.0,-1.0)';
    'DDR3_DQ'<52>:
      PIN_NUMBER='(0,0,0,0,0,DP31,0,0,0,0,0,0,0,0,0,0,0,0,0,0,0,0,0,0,0,0,0,0,0,0)';
      BIDIRECTIONAL='TRUE';
      INPUT_LOAD='(-0.01,0.01)';
      OUTPUT_LOAD='(1.0,-1.0)';
    'DDR3_DQ'<51>:
      PIN_NUMBER='(0,0,0,0,0,DT27,0,0,0,0,0,0,0,0,0,0,0,0,0,0,0,0,0,0,0,0,0,0,0,0)';
      BIDIRECTIONAL='TRUE';
      INPUT_LOAD='(-0.01,0.01)';
      OUTPUT_LOAD='(1.0,-1.0)';
    'DDR3_DQ'<50>:
      PIN_NUMBER='(0,0,0,0,0,DP27,0,0,0,0,0,0,0,0,0,0,0,0,0,0,0,0,0,0,0,0,0,0,0,0)';
      BIDIRECTIONAL='TRUE';
      INPUT_LOAD='(-0.01,0.01)';
      OUTPUT_LOAD='(1.0,-1.0)';
    'DDR3_DQ'<49>:
      PIN_NUMBER='(0,0,0,0,0,DU30,0,0,0,0,0,0,0,0,0,0,0,0,0,0,0,0,0,0,0,0,0,0,0,0)';
      BIDIRECTIONAL='TRUE';
      INPUT_LOAD='(-0.01,0.01)';
      OUTPUT_LOAD='(1.0,-1.0)';
    'DDR3_DQ'<48>:
      PIN_NUMBER='(0,0,0,0,0,DN30,0,0,0,0,0,0,0,0,0,0,0,0,0,0,0,0,0,0,0,0,0,0,0,0)';
      BIDIRECTIONAL='TRUE';
      INPUT_LOAD='(-0.01,0.01)';
      OUTPUT_LOAD='(1.0,-1.0)';
    'DDR3_DQ'<47>:
      PIN_NUMBER='(0,0,0,0,0,DU34,0,0,0,0,0,0,0,0,0,0,0,0,0,0,0,0,0,0,0,0,0,0,0,0)';
      BIDIRECTIONAL='TRUE';
      INPUT_LOAD='(-0.01,0.01)';
      OUTPUT_LOAD='(1.0,-1.0)';
    'DDR3_DQ'<46>:
      PIN_NUMBER='(0,0,0,0,0,DN34,0,0,0,0,0,0,0,0,0,0,0,0,0,0,0,0,0,0,0,0,0,0,0,0)';
      BIDIRECTIONAL='TRUE';
      INPUT_LOAD='(-0.01,0.01)';
      OUTPUT_LOAD='(1.0,-1.0)';
    'DDR3_DQ'<45>:
      PIN_NUMBER='(0,0,0,0,0,DT37,0,0,0,0,0,0,0,0,0,0,0,0,0,0,0,0,0,0,0,0,0,0,0,0)';
      BIDIRECTIONAL='TRUE';
      INPUT_LOAD='(-0.01,0.01)';
      OUTPUT_LOAD='(1.0,-1.0)';
    'DDR3_DQ'<44>:
      PIN_NUMBER='(0,0,0,0,0,DP37,0,0,0,0,0,0,0,0,0,0,0,0,0,0,0,0,0,0,0,0,0,0,0,0)';
      BIDIRECTIONAL='TRUE';
      INPUT_LOAD='(-0.01,0.01)';
      OUTPUT_LOAD='(1.0,-1.0)';
    'DDR3_DQ'<43>:
      PIN_NUMBER='(0,0,0,0,0,DT33,0,0,0,0,0,0,0,0,0,0,0,0,0,0,0,0,0,0,0,0,0,0,0,0)';
      BIDIRECTIONAL='TRUE';
      INPUT_LOAD='(-0.01,0.01)';
      OUTPUT_LOAD='(1.0,-1.0)';
    'DDR3_DQ'<42>:
      PIN_NUMBER='(0,0,0,0,0,DP33,0,0,0,0,0,0,0,0,0,0,0,0,0,0,0,0,0,0,0,0,0,0,0,0)';
      BIDIRECTIONAL='TRUE';
      INPUT_LOAD='(-0.01,0.01)';
      OUTPUT_LOAD='(1.0,-1.0)';
    'DDR3_DQ'<41>:
      PIN_NUMBER='(0,0,0,0,0,DU36,0,0,0,0,0,0,0,0,0,0,0,0,0,0,0,0,0,0,0,0,0,0,0,0)';
      BIDIRECTIONAL='TRUE';
      INPUT_LOAD='(-0.01,0.01)';
      OUTPUT_LOAD='(1.0,-1.0)';
    'DDR3_DQ'<40>:
      PIN_NUMBER='(0,0,0,0,0,DN36,0,0,0,0,0,0,0,0,0,0,0,0,0,0,0,0,0,0,0,0,0,0,0,0)';
      BIDIRECTIONAL='TRUE';
      INPUT_LOAD='(-0.01,0.01)';
      OUTPUT_LOAD='(1.0,-1.0)';
    'DDR3_DQ'<39>:
      PIN_NUMBER='(0,0,0,0,0,ED37,0,0,0,0,0,0,0,0,0,0,0,0,0,0,0,0,0,0,0,0,0,0,0,0)';
      BIDIRECTIONAL='TRUE';
      INPUT_LOAD='(-0.01,0.01)';
      OUTPUT_LOAD='(1.0,-1.0)';
    'DDR3_DQ'<38>:
      PIN_NUMBER='(0,0,0,0,0,DY37,0,0,0,0,0,0,0,0,0,0,0,0,0,0,0,0,0,0,0,0,0,0,0,0)';
      BIDIRECTIONAL='TRUE';
      INPUT_LOAD='(-0.01,0.01)';
      OUTPUT_LOAD='(1.0,-1.0)';
    'DDR3_DQ'<37>:
      PIN_NUMBER='(0,0,0,0,0,EA40,0,0,0,0,0,0,0,0,0,0,0,0,0,0,0,0,0,0,0,0,0,0,0,0)';
      BIDIRECTIONAL='TRUE';
      INPUT_LOAD='(-0.01,0.01)';
      OUTPUT_LOAD='(1.0,-1.0)';
    'DDR3_DQ'<36>:
      PIN_NUMBER='(0,0,0,0,0,DY39,0,0,0,0,0,0,0,0,0,0,0,0,0,0,0,0,0,0,0,0,0,0,0,0)';
      BIDIRECTIONAL='TRUE';
      INPUT_LOAD='(-0.01,0.01)';
      OUTPUT_LOAD='(1.0,-1.0)';
    'DDR3_DQ'<35>:
      PIN_NUMBER='(0,0,0,0,0,EC36,0,0,0,0,0,0,0,0,0,0,0,0,0,0,0,0,0,0,0,0,0,0,0,0)';
      BIDIRECTIONAL='TRUE';
      INPUT_LOAD='(-0.01,0.01)';
      OUTPUT_LOAD='(1.0,-1.0)';
    'DDR3_DQ'<34>:
      PIN_NUMBER='(0,0,0,0,0,EA36,0,0,0,0,0,0,0,0,0,0,0,0,0,0,0,0,0,0,0,0,0,0,0,0)';
      BIDIRECTIONAL='TRUE';
      INPUT_LOAD='(-0.01,0.01)';
      OUTPUT_LOAD='(1.0,-1.0)';
    'DDR3_DQ'<33>:
      PIN_NUMBER='(0,0,0,0,0,ED39,0,0,0,0,0,0,0,0,0,0,0,0,0,0,0,0,0,0,0,0,0,0,0,0)';
      BIDIRECTIONAL='TRUE';
      INPUT_LOAD='(-0.01,0.01)';
      OUTPUT_LOAD='(1.0,-1.0)';
    'DDR3_DQ'<32>:
      PIN_NUMBER='(0,0,0,0,0,EC40,0,0,0,0,0,0,0,0,0,0,0,0,0,0,0,0,0,0,0,0,0,0,0,0)';
      BIDIRECTIONAL='TRUE';
      INPUT_LOAD='(-0.01,0.01)';
      OUTPUT_LOAD='(1.0,-1.0)';
    'DDR3_DQ'<31>:
      PIN_NUMBER='(0,0,0,0,0,DU74,0,0,0,0,0,0,0,0,0,0,0,0,0,0,0,0,0,0,0,0,0,0,0,0)';
      BIDIRECTIONAL='TRUE';
      INPUT_LOAD='(-0.01,0.01)';
      OUTPUT_LOAD='(1.0,-1.0)';
    'DDR3_DQ'<30>:
      PIN_NUMBER='(0,0,0,0,0,DN74,0,0,0,0,0,0,0,0,0,0,0,0,0,0,0,0,0,0,0,0,0,0,0,0)';
      BIDIRECTIONAL='TRUE';
      INPUT_LOAD='(-0.01,0.01)';
      OUTPUT_LOAD='(1.0,-1.0)';
    'DDR3_DQ'<29>:
      PIN_NUMBER='(0,0,0,0,0,DT77,0,0,0,0,0,0,0,0,0,0,0,0,0,0,0,0,0,0,0,0,0,0,0,0)';
      BIDIRECTIONAL='TRUE';
      INPUT_LOAD='(-0.01,0.01)';
      OUTPUT_LOAD='(1.0,-1.0)';
    'DDR3_DQ'<28>:
      PIN_NUMBER='(0,0,0,0,0,DP77,0,0,0,0,0,0,0,0,0,0,0,0,0,0,0,0,0,0,0,0,0,0,0,0)';
      BIDIRECTIONAL='TRUE';
      INPUT_LOAD='(-0.01,0.01)';
      OUTPUT_LOAD='(1.0,-1.0)';
    'DDR3_DQ'<27>:
      PIN_NUMBER='(0,0,0,0,0,DT73,0,0,0,0,0,0,0,0,0,0,0,0,0,0,0,0,0,0,0,0,0,0,0,0)';
      BIDIRECTIONAL='TRUE';
      INPUT_LOAD='(-0.01,0.01)';
      OUTPUT_LOAD='(1.0,-1.0)';
    'DDR3_DQ'<26>:
      PIN_NUMBER='(0,0,0,0,0,DP73,0,0,0,0,0,0,0,0,0,0,0,0,0,0,0,0,0,0,0,0,0,0,0,0)';
      BIDIRECTIONAL='TRUE';
      INPUT_LOAD='(-0.01,0.01)';
      OUTPUT_LOAD='(1.0,-1.0)';
    'DDR3_DQ'<25>:
      PIN_NUMBER='(0,0,0,0,0,DU76,0,0,0,0,0,0,0,0,0,0,0,0,0,0,0,0,0,0,0,0,0,0,0,0)';
      BIDIRECTIONAL='TRUE';
      INPUT_LOAD='(-0.01,0.01)';
      OUTPUT_LOAD='(1.0,-1.0)';
    'DDR3_DQ'<24>:
      PIN_NUMBER='(0,0,0,0,0,DN76,0,0,0,0,0,0,0,0,0,0,0,0,0,0,0,0,0,0,0,0,0,0,0,0)';
      BIDIRECTIONAL='TRUE';
      INPUT_LOAD='(-0.01,0.01)';
      OUTPUT_LOAD='(1.0,-1.0)';
    'DDR3_DQ'<23>:
      PIN_NUMBER='(0,0,0,0,0,DN82,0,0,0,0,0,0,0,0,0,0,0,0,0,0,0,0,0,0,0,0,0,0,0,0)';
      BIDIRECTIONAL='TRUE';
      INPUT_LOAD='(-0.01,0.01)';
      OUTPUT_LOAD='(1.0,-1.0)';
    'DDR3_DQ'<22>:
      PIN_NUMBER='(0,0,0,0,0,DR80,0,0,0,0,0,0,0,0,0,0,0,0,0,0,0,0,0,0,0,0,0,0,0,0)';
      BIDIRECTIONAL='TRUE';
      INPUT_LOAD='(-0.01,0.01)';
      OUTPUT_LOAD='(1.0,-1.0)';
    'DDR3_DQ'<21>:
      PIN_NUMBER='(0,0,0,0,0,DJ80,0,0,0,0,0,0,0,0,0,0,0,0,0,0,0,0,0,0,0,0,0,0,0,0)';
      BIDIRECTIONAL='TRUE';
      INPUT_LOAD='(-0.01,0.01)';
      OUTPUT_LOAD='(1.0,-1.0)';
    'DDR3_DQ'<20>:
      PIN_NUMBER='(0,0,0,0,0,DK79,0,0,0,0,0,0,0,0,0,0,0,0,0,0,0,0,0,0,0,0,0,0,0,0)';
      BIDIRECTIONAL='TRUE';
      INPUT_LOAD='(-0.01,0.01)';
      OUTPUT_LOAD='(1.0,-1.0)';
    'DDR3_DQ'<19>:
      PIN_NUMBER='(0,0,0,0,0,DR82,0,0,0,0,0,0,0,0,0,0,0,0,0,0,0,0,0,0,0,0,0,0,0,0)';
      BIDIRECTIONAL='TRUE';
      INPUT_LOAD='(-0.01,0.01)';
      OUTPUT_LOAD='(1.0,-1.0)';
    'DDR3_DQ'<18>:
      PIN_NUMBER='(0,0,0,0,0,DT81,0,0,0,0,0,0,0,0,0,0,0,0,0,0,0,0,0,0,0,0,0,0,0,0)';
      BIDIRECTIONAL='TRUE';
      INPUT_LOAD='(-0.01,0.01)';
      OUTPUT_LOAD='(1.0,-1.0)';
    'DDR3_DQ'<17>:
      PIN_NUMBER='(0,0,0,0,0,DK81,0,0,0,0,0,0,0,0,0,0,0,0,0,0,0,0,0,0,0,0,0,0,0,0)';
      BIDIRECTIONAL='TRUE';
      INPUT_LOAD='(-0.01,0.01)';
      OUTPUT_LOAD='(1.0,-1.0)';
    'DDR3_DQ'<16>:
      PIN_NUMBER='(0,0,0,0,0,DM79,0,0,0,0,0,0,0,0,0,0,0,0,0,0,0,0,0,0,0,0,0,0,0,0)';
      BIDIRECTIONAL='TRUE';
      INPUT_LOAD='(-0.01,0.01)';
      OUTPUT_LOAD='(1.0,-1.0)';
    'DDR3_DQ'<15>:
      PIN_NUMBER='(0,0,0,0,0,DV85,0,0,0,0,0,0,0,0,0,0,0,0,0,0,0,0,0,0,0,0,0,0,0,0)';
      BIDIRECTIONAL='TRUE';
      INPUT_LOAD='(-0.01,0.01)';
      OUTPUT_LOAD='(1.0,-1.0)';
    'DDR3_DQ'<14>:
      PIN_NUMBER='(0,0,0,0,0,DR84,0,0,0,0,0,0,0,0,0,0,0,0,0,0,0,0,0,0,0,0,0,0,0,0)';
      BIDIRECTIONAL='TRUE';
      INPUT_LOAD='(-0.01,0.01)';
      OUTPUT_LOAD='(1.0,-1.0)';
    'DDR3_DQ'<13>:
      PIN_NUMBER='(0,0,0,0,0,DE84,0,0,0,0,0,0,0,0,0,0,0,0,0,0,0,0,0,0,0,0,0,0,0,0)';
      BIDIRECTIONAL='TRUE';
      INPUT_LOAD='(-0.01,0.01)';
      OUTPUT_LOAD='(1.0,-1.0)';
    'DDR3_DQ'<12>:
      PIN_NUMBER='(0,0,0,0,0,DD85,0,0,0,0,0,0,0,0,0,0,0,0,0,0,0,0,0,0,0,0,0,0,0,0)';
      BIDIRECTIONAL='TRUE';
      INPUT_LOAD='(-0.01,0.01)';
      OUTPUT_LOAD='(1.0,-1.0)';
    'DDR3_DQ'<11>:
      PIN_NUMBER='(0,0,0,0,0,DY83,0,0,0,0,0,0,0,0,0,0,0,0,0,0,0,0,0,0,0,0,0,0,0,0)';
      BIDIRECTIONAL='TRUE';
      INPUT_LOAD='(-0.01,0.01)';
      OUTPUT_LOAD='(1.0,-1.0)';
    'DDR3_DQ'<10>:
      PIN_NUMBER='(0,0,0,0,0,DV83,0,0,0,0,0,0,0,0,0,0,0,0,0,0,0,0,0,0,0,0,0,0,0,0)';
      BIDIRECTIONAL='TRUE';
      INPUT_LOAD='(-0.01,0.01)';
      OUTPUT_LOAD='(1.0,-1.0)';
    'DDR3_DQ'<9>:
      PIN_NUMBER='(0,0,0,0,0,DH85,0,0,0,0,0,0,0,0,0,0,0,0,0,0,0,0,0,0,0,0,0,0,0,0)';
      BIDIRECTIONAL='TRUE';
      INPUT_LOAD='(-0.01,0.01)';
      OUTPUT_LOAD='(1.0,-1.0)';
    'DDR3_DQ'<8>:
      PIN_NUMBER='(0,0,0,0,0,DG84,0,0,0,0,0,0,0,0,0,0,0,0,0,0,0,0,0,0,0,0,0,0,0,0)';
      BIDIRECTIONAL='TRUE';
      INPUT_LOAD='(-0.01,0.01)';
      OUTPUT_LOAD='(1.0,-1.0)';
    'DDR3_DQ'<7>:
      PIN_NUMBER='(0,0,0,0,0,CW84,0,0,0,0,0,0,0,0,0,0,0,0,0,0,0,0,0,0,0,0,0,0,0,0)';
      BIDIRECTIONAL='TRUE';
      INPUT_LOAD='(-0.01,0.01)';
      OUTPUT_LOAD='(1.0,-1.0)';
    'DDR3_DQ'<6>:
      PIN_NUMBER='(0,0,0,0,0,CW86,0,0,0,0,0,0,0,0,0,0,0,0,0,0,0,0,0,0,0,0,0,0,0,0)';
      BIDIRECTIONAL='TRUE';
      INPUT_LOAD='(-0.01,0.01)';
      OUTPUT_LOAD='(1.0,-1.0)';
    'DDR3_DQ'<5>:
      PIN_NUMBER='(0,0,0,0,0,CL86,0,0,0,0,0,0,0,0,0,0,0,0,0,0,0,0,0,0,0,0,0,0,0,0)';
      BIDIRECTIONAL='TRUE';
      INPUT_LOAD='(-0.01,0.01)';
      OUTPUT_LOAD='(1.0,-1.0)';
    'DDR3_DQ'<4>:
      PIN_NUMBER='(0,0,0,0,0,CL84,0,0,0,0,0,0,0,0,0,0,0,0,0,0,0,0,0,0,0,0,0,0,0,0)';
      BIDIRECTIONAL='TRUE';
      INPUT_LOAD='(-0.01,0.01)';
      OUTPUT_LOAD='(1.0,-1.0)';
    'DDR3_DQ'<3>:
      PIN_NUMBER='(0,0,0,0,0,DA84,0,0,0,0,0,0,0,0,0,0,0,0,0,0,0,0,0,0,0,0,0,0,0,0)';
      BIDIRECTIONAL='TRUE';
      INPUT_LOAD='(-0.01,0.01)';
      OUTPUT_LOAD='(1.0,-1.0)';
    'DDR3_DQ'<2>:
      PIN_NUMBER='(0,0,0,0,0,DA86,0,0,0,0,0,0,0,0,0,0,0,0,0,0,0,0,0,0,0,0,0,0,0,0)';
      BIDIRECTIONAL='TRUE';
      INPUT_LOAD='(-0.01,0.01)';
      OUTPUT_LOAD='(1.0,-1.0)';
    'DDR3_DQ'<1>:
      PIN_NUMBER='(0,0,0,0,0,CN86,0,0,0,0,0,0,0,0,0,0,0,0,0,0,0,0,0,0,0,0,0,0,0,0)';
      BIDIRECTIONAL='TRUE';
      INPUT_LOAD='(-0.01,0.01)';
      OUTPUT_LOAD='(1.0,-1.0)';
    'DDR3_DQ'<0>:
      PIN_NUMBER='(0,0,0,0,0,CN84,0,0,0,0,0,0,0,0,0,0,0,0,0,0,0,0,0,0,0,0,0,0,0,0)';
      BIDIRECTIONAL='TRUE';
      INPUT_LOAD='(-0.01,0.01)';
      OUTPUT_LOAD='(1.0,-1.0)';
    'DDR3_DQS_DN'<17>:
      PIN_NUMBER='(0,0,0,0,0,DB67,0,0,0,0,0,0,0,0,0,0,0,0,0,0,0,0,0,0,0,0,0,0,0,0)';
      BIDIRECTIONAL='TRUE';
      INPUT_LOAD='(-0.01,0.01)';
      OUTPUT_LOAD='(1.0,-1.0)';
    'DDR3_DQS_DN'<16>:
      PIN_NUMBER='(0,0,0,0,0,DM23,0,0,0,0,0,0,0,0,0,0,0,0,0,0,0,0,0,0,0,0,0,0,0,0)';
      BIDIRECTIONAL='TRUE';
      INPUT_LOAD='(-0.01,0.01)';
      OUTPUT_LOAD='(1.0,-1.0)';
    'DDR3_DQS_DN'<15>:
      PIN_NUMBER='(0,0,0,0,0,DM29,0,0,0,0,0,0,0,0,0,0,0,0,0,0,0,0,0,0,0,0,0,0,0,0)';
      BIDIRECTIONAL='TRUE';
      INPUT_LOAD='(-0.01,0.01)';
      OUTPUT_LOAD='(1.0,-1.0)';
    'DDR3_DQS_DN'<14>:
      PIN_NUMBER='(0,0,0,0,0,DP35,0,0,0,0,0,0,0,0,0,0,0,0,0,0,0,0,0,0,0,0,0,0,0,0)';
      BIDIRECTIONAL='TRUE';
      INPUT_LOAD='(-0.01,0.01)';
      OUTPUT_LOAD='(1.0,-1.0)';
    'DDR3_DQS_DN'<13>:
      PIN_NUMBER='(0,0,0,0,0,EA38,0,0,0,0,0,0,0,0,0,0,0,0,0,0,0,0,0,0,0,0,0,0,0,0)';
      BIDIRECTIONAL='TRUE';
      INPUT_LOAD='(-0.01,0.01)';
      OUTPUT_LOAD='(1.0,-1.0)';
    'DDR3_DQS_DN'<12>:
      PIN_NUMBER='(0,0,0,0,0,DP75,0,0,0,0,0,0,0,0,0,0,0,0,0,0,0,0,0,0,0,0,0,0,0,0)';
      BIDIRECTIONAL='TRUE';
      INPUT_LOAD='(-0.01,0.01)';
      OUTPUT_LOAD='(1.0,-1.0)';
    'DDR3_DQS_DN'<11>:
      PIN_NUMBER='(0,0,0,0,0,DN80,0,0,0,0,0,0,0,0,0,0,0,0,0,0,0,0,0,0,0,0,0,0,0,0)';
      BIDIRECTIONAL='TRUE';
      INPUT_LOAD='(-0.01,0.01)';
      OUTPUT_LOAD='(1.0,-1.0)';
    'DDR3_DQS_DN'<10>:
      PIN_NUMBER='(0,0,0,0,0,DM85,0,0,0,0,0,0,0,0,0,0,0,0,0,0,0,0,0,0,0,0,0,0,0,0)';
      BIDIRECTIONAL='TRUE';
      INPUT_LOAD='(-0.01,0.01)';
      OUTPUT_LOAD='(1.0,-1.0)';
    'DDR3_DQS_DN'<9>:
      PIN_NUMBER='(0,0,0,0,0,CR84,0,0,0,0,0,0,0,0,0,0,0,0,0,0,0,0,0,0,0,0,0,0,0,0)';
      BIDIRECTIONAL='TRUE';
      INPUT_LOAD='(-0.01,0.01)';
      OUTPUT_LOAD='(1.0,-1.0)';
    'DDR3_DQS_DN'<8>:
      PIN_NUMBER='(0,0,0,0,0,DF67,0,0,0,0,0,0,0,0,0,0,0,0,0,0,0,0,0,0,0,0,0,0,0,0)';
      BIDIRECTIONAL='TRUE';
      INPUT_LOAD='(-0.01,0.01)';
      OUTPUT_LOAD='(1.0,-1.0)';
    'DDR3_DQS_DN'<7>:
      PIN_NUMBER='(0,0,0,0,0,DV23,0,0,0,0,0,0,0,0,0,0,0,0,0,0,0,0,0,0,0,0,0,0,0,0)';
      BIDIRECTIONAL='TRUE';
      INPUT_LOAD='(-0.01,0.01)';
      OUTPUT_LOAD='(1.0,-1.0)';
    'DDR3_DQS_DN'<6>:
      PIN_NUMBER='(0,0,0,0,0,DV29,0,0,0,0,0,0,0,0,0,0,0,0,0,0,0,0,0,0,0,0,0,0,0,0)';
      BIDIRECTIONAL='TRUE';
      INPUT_LOAD='(-0.01,0.01)';
      OUTPUT_LOAD='(1.0,-1.0)';
    'DDR3_DQS_DN'<5>:
      PIN_NUMBER='(0,0,0,0,0,DV35,0,0,0,0,0,0,0,0,0,0,0,0,0,0,0,0,0,0,0,0,0,0,0,0)';
      BIDIRECTIONAL='TRUE';
      INPUT_LOAD='(-0.01,0.01)';
      OUTPUT_LOAD='(1.0,-1.0)';
    'DDR3_DQS_DN'<4>:
      PIN_NUMBER='(0,0,0,0,0,EE38,0,0,0,0,0,0,0,0,0,0,0,0,0,0,0,0,0,0,0,0,0,0,0,0)';
      BIDIRECTIONAL='TRUE';
      INPUT_LOAD='(-0.01,0.01)';
      OUTPUT_LOAD='(1.0,-1.0)';
    'DDR3_DQS_DN'<3>:
      PIN_NUMBER='(0,0,0,0,0,DV75,0,0,0,0,0,0,0,0,0,0,0,0,0,0,0,0,0,0,0,0,0,0,0,0)';
      BIDIRECTIONAL='TRUE';
      INPUT_LOAD='(-0.01,0.01)';
      OUTPUT_LOAD='(1.0,-1.0)';
    'DDR3_DQS_DN'<2>:
      PIN_NUMBER='(0,0,0,0,0,DL82,0,0,0,0,0,0,0,0,0,0,0,0,0,0,0,0,0,0,0,0,0,0,0,0)';
      BIDIRECTIONAL='TRUE';
      INPUT_LOAD='(-0.01,0.01)';
      OUTPUT_LOAD='(1.0,-1.0)';
    'DDR3_DQS_DN'<1>:
      PIN_NUMBER='(0,0,0,0,0,DN84,0,0,0,0,0,0,0,0,0,0,0,0,0,0,0,0,0,0,0,0,0,0,0,0)';
      BIDIRECTIONAL='TRUE';
      INPUT_LOAD='(-0.01,0.01)';
      OUTPUT_LOAD='(1.0,-1.0)';
    'DDR3_DQS_DN'<0>:
      PIN_NUMBER='(0,0,0,0,0,CU84,0,0,0,0,0,0,0,0,0,0,0,0,0,0,0,0,0,0,0,0,0,0,0,0)';
      BIDIRECTIONAL='TRUE';
      INPUT_LOAD='(-0.01,0.01)';
      OUTPUT_LOAD='(1.0,-1.0)';
    'DDR3_DQS_DP'<17>:
      PIN_NUMBER='(0,0,0,0,0,CY67,0,0,0,0,0,0,0,0,0,0,0,0,0,0,0,0,0,0,0,0,0,0,0,0)';
      BIDIRECTIONAL='TRUE';
      INPUT_LOAD='(-0.01,0.01)';
      OUTPUT_LOAD='(1.0,-1.0)';
    'DDR3_DQS_DP'<16>:
      PIN_NUMBER='(0,0,0,0,0,DP23,0,0,0,0,0,0,0,0,0,0,0,0,0,0,0,0,0,0,0,0,0,0,0,0)';
      BIDIRECTIONAL='TRUE';
      INPUT_LOAD='(-0.01,0.01)';
      OUTPUT_LOAD='(1.0,-1.0)';
    'DDR3_DQS_DP'<15>:
      PIN_NUMBER='(0,0,0,0,0,DP29,0,0,0,0,0,0,0,0,0,0,0,0,0,0,0,0,0,0,0,0,0,0,0,0)';
      BIDIRECTIONAL='TRUE';
      INPUT_LOAD='(-0.01,0.01)';
      OUTPUT_LOAD='(1.0,-1.0)';
    'DDR3_DQS_DP'<14>:
      PIN_NUMBER='(0,0,0,0,0,DM35,0,0,0,0,0,0,0,0,0,0,0,0,0,0,0,0,0,0,0,0,0,0,0,0)';
      BIDIRECTIONAL='TRUE';
      INPUT_LOAD='(-0.01,0.01)';
      OUTPUT_LOAD='(1.0,-1.0)';
    'DDR3_DQS_DP'<13>:
      PIN_NUMBER='(0,0,0,0,0,DW38,0,0,0,0,0,0,0,0,0,0,0,0,0,0,0,0,0,0,0,0,0,0,0,0)';
      BIDIRECTIONAL='TRUE';
      INPUT_LOAD='(-0.01,0.01)';
      OUTPUT_LOAD='(1.0,-1.0)';
    'DDR3_DQS_DP'<12>:
      PIN_NUMBER='(0,0,0,0,0,DM75,0,0,0,0,0,0,0,0,0,0,0,0,0,0,0,0,0,0,0,0,0,0,0,0)';
      BIDIRECTIONAL='TRUE';
      INPUT_LOAD='(-0.01,0.01)';
      OUTPUT_LOAD='(1.0,-1.0)';
    'DDR3_DQS_DP'<11>:
      PIN_NUMBER='(0,0,0,0,0,DP79,0,0,0,0,0,0,0,0,0,0,0,0,0,0,0,0,0,0,0,0,0,0,0,0)';
      BIDIRECTIONAL='TRUE';
      INPUT_LOAD='(-0.01,0.01)';
      OUTPUT_LOAD='(1.0,-1.0)';
    'DDR3_DQS_DP'<10>:
      PIN_NUMBER='(0,0,0,0,0,DL84,0,0,0,0,0,0,0,0,0,0,0,0,0,0,0,0,0,0,0,0,0,0,0,0)';
      BIDIRECTIONAL='TRUE';
      INPUT_LOAD='(-0.01,0.01)';
      OUTPUT_LOAD='(1.0,-1.0)';
    'DDR3_DQS_DP'<9>:
      PIN_NUMBER='(0,0,0,0,0,CP85,0,0,0,0,0,0,0,0,0,0,0,0,0,0,0,0,0,0,0,0,0,0,0,0)';
      BIDIRECTIONAL='TRUE';
      INPUT_LOAD='(-0.01,0.01)';
      OUTPUT_LOAD='(1.0,-1.0)';
    'DDR3_DQS_DP'<8>:
      PIN_NUMBER='(0,0,0,0,0,DD67,0,0,0,0,0,0,0,0,0,0,0,0,0,0,0,0,0,0,0,0,0,0,0,0)';
      BIDIRECTIONAL='TRUE';
      INPUT_LOAD='(-0.01,0.01)';
      OUTPUT_LOAD='(1.0,-1.0)';
    'DDR3_DQS_DP'<7>:
      PIN_NUMBER='(0,0,0,0,0,DT23,0,0,0,0,0,0,0,0,0,0,0,0,0,0,0,0,0,0,0,0,0,0,0,0)';
      BIDIRECTIONAL='TRUE';
      INPUT_LOAD='(-0.01,0.01)';
      OUTPUT_LOAD='(1.0,-1.0)';
    'DDR3_DQS_DP'<6>:
      PIN_NUMBER='(0,0,0,0,0,DT29,0,0,0,0,0,0,0,0,0,0,0,0,0,0,0,0,0,0,0,0,0,0,0,0)';
      BIDIRECTIONAL='TRUE';
      INPUT_LOAD='(-0.01,0.01)';
      OUTPUT_LOAD='(1.0,-1.0)';
    'DDR3_DQS_DP'<5>:
      PIN_NUMBER='(0,0,0,0,0,DT35,0,0,0,0,0,0,0,0,0,0,0,0,0,0,0,0,0,0,0,0,0,0,0,0)';
      BIDIRECTIONAL='TRUE';
      INPUT_LOAD='(-0.01,0.01)';
      OUTPUT_LOAD='(1.0,-1.0)';
    'DDR3_DQS_DP'<4>:
      PIN_NUMBER='(0,0,0,0,0,EC38,0,0,0,0,0,0,0,0,0,0,0,0,0,0,0,0,0,0,0,0,0,0,0,0)';
      BIDIRECTIONAL='TRUE';
      INPUT_LOAD='(-0.01,0.01)';
      OUTPUT_LOAD='(1.0,-1.0)';
    'DDR3_DQS_DP'<3>:
      PIN_NUMBER='(0,0,0,0,0,DT75,0,0,0,0,0,0,0,0,0,0,0,0,0,0,0,0,0,0,0,0,0,0,0,0)';
      BIDIRECTIONAL='TRUE';
      INPUT_LOAD='(-0.01,0.01)';
      OUTPUT_LOAD='(1.0,-1.0)';
    'DDR3_DQS_DP'<2>:
      PIN_NUMBER='(0,0,0,0,0,DM81,0,0,0,0,0,0,0,0,0,0,0,0,0,0,0,0,0,0,0,0,0,0,0,0)';
      BIDIRECTIONAL='TRUE';
      INPUT_LOAD='(-0.01,0.01)';
      OUTPUT_LOAD='(1.0,-1.0)';
    'DDR3_DQS_DP'<1>:
      PIN_NUMBER='(0,0,0,0,0,DP85,0,0,0,0,0,0,0,0,0,0,0,0,0,0,0,0,0,0,0,0,0,0,0,0)';
      BIDIRECTIONAL='TRUE';
      INPUT_LOAD='(-0.01,0.01)';
      OUTPUT_LOAD='(1.0,-1.0)';
    'DDR3_DQS_DP'<0>:
      PIN_NUMBER='(0,0,0,0,0,CV85,0,0,0,0,0,0,0,0,0,0,0,0,0,0,0,0,0,0,0,0,0,0,0,0)';
      BIDIRECTIONAL='TRUE';
      INPUT_LOAD='(-0.01,0.01)';
      OUTPUT_LOAD='(1.0,-1.0)';
    'DDR3_ECC'<7>:
      PIN_NUMBER='(0,0,0,0,0,DE66,0,0,0,0,0,0,0,0,0,0,0,0,0,0,0,0,0,0,0,0,0,0,0,0)';
      BIDIRECTIONAL='TRUE';
      INPUT_LOAD='(-0.01,0.01)';
      OUTPUT_LOAD='(1.0,-1.0)';
    'DDR3_ECC'<6>:
      PIN_NUMBER='(0,0,0,0,0,DA66,0,0,0,0,0,0,0,0,0,0,0,0,0,0,0,0,0,0,0,0,0,0,0,0)';
      BIDIRECTIONAL='TRUE';
      INPUT_LOAD='(-0.01,0.01)';
      OUTPUT_LOAD='(1.0,-1.0)';
    'DDR3_ECC'<5>:
      PIN_NUMBER='(0,0,0,0,0,DD69,0,0,0,0,0,0,0,0,0,0,0,0,0,0,0,0,0,0,0,0,0,0,0,0)';
      BIDIRECTIONAL='TRUE';
      INPUT_LOAD='(-0.01,0.01)';
      OUTPUT_LOAD='(1.0,-1.0)';
    'DDR3_ECC'<4>:
      PIN_NUMBER='(0,0,0,0,0,DB69,0,0,0,0,0,0,0,0,0,0,0,0,0,0,0,0,0,0,0,0,0,0,0,0)';
      BIDIRECTIONAL='TRUE';
      INPUT_LOAD='(-0.01,0.01)';
      OUTPUT_LOAD='(1.0,-1.0)';
    'DDR3_ECC'<3>:
      PIN_NUMBER='(0,0,0,0,0,DD65,0,0,0,0,0,0,0,0,0,0,0,0,0,0,0,0,0,0,0,0,0,0,0,0)';
      BIDIRECTIONAL='TRUE';
      INPUT_LOAD='(-0.01,0.01)';
      OUTPUT_LOAD='(1.0,-1.0)';
    'DDR3_ECC'<2>:
      PIN_NUMBER='(0,0,0,0,0,DB65,0,0,0,0,0,0,0,0,0,0,0,0,0,0,0,0,0,0,0,0,0,0,0,0)';
      BIDIRECTIONAL='TRUE';
      INPUT_LOAD='(-0.01,0.01)';
      OUTPUT_LOAD='(1.0,-1.0)';
    'DDR3_ECC'<1>:
      PIN_NUMBER='(0,0,0,0,0,DE68,0,0,0,0,0,0,0,0,0,0,0,0,0,0,0,0,0,0,0,0,0,0,0,0)';
      BIDIRECTIONAL='TRUE';
      INPUT_LOAD='(-0.01,0.01)';
      OUTPUT_LOAD='(1.0,-1.0)';
    'DDR3_ECC'<0>:
      PIN_NUMBER='(0,0,0,0,0,DA68,0,0,0,0,0,0,0,0,0,0,0,0,0,0,0,0,0,0,0,0,0,0,0,0)';
      BIDIRECTIONAL='TRUE';
      INPUT_LOAD='(-0.01,0.01)';
      OUTPUT_LOAD='(1.0,-1.0)';
    'DDR3_MA'<17>:
      PIN_NUMBER='(0,0,0,0,0,EA46,0,0,0,0,0,0,0,0,0,0,0,0,0,0,0,0,0,0,0,0,0,0,0,0)';
      OUTPUT_LOAD='(1.0,-1.0)';
    'DDR3_MA'<16>:
      PIN_NUMBER='(0,0,0,0,0,EA52,0,0,0,0,0,0,0,0,0,0,0,0,0,0,0,0,0,0,0,0,0,0,0,0)';
      OUTPUT_LOAD='(1.0,-1.0)';
    'DDR3_MA'<15>:
      PIN_NUMBER='(0,0,0,0,0,DV49,0,0,0,0,0,0,0,0,0,0,0,0,0,0,0,0,0,0,0,0,0,0,0,0)';
      OUTPUT_LOAD='(1.0,-1.0)';
    'DDR3_MA'<14>:
      PIN_NUMBER='(0,0,0,0,0,ED51,0,0,0,0,0,0,0,0,0,0,0,0,0,0,0,0,0,0,0,0,0,0,0,0)';
      OUTPUT_LOAD='(1.0,-1.0)';
    'DDR3_MA'<13>:
      PIN_NUMBER='(0,0,0,0,0,DW48,0,0,0,0,0,0,0,0,0,0,0,0,0,0,0,0,0,0,0,0,0,0,0,0)';
      OUTPUT_LOAD='(1.0,-1.0)';
    'DDR3_MA'<12>:
      PIN_NUMBER='(0,0,0,0,0,DT63,0,0,0,0,0,0,0,0,0,0,0,0,0,0,0,0,0,0,0,0,0,0,0,0)';
      OUTPUT_LOAD='(1.0,-1.0)';
    'DDR3_MA'<11>:
      PIN_NUMBER='(0,0,0,0,0,EB61,0,0,0,0,0,0,0,0,0,0,0,0,0,0,0,0,0,0,0,0,0,0,0,0)';
      OUTPUT_LOAD='(1.0,-1.0)';
    'DDR3_MA'<10>:
      PIN_NUMBER='(0,0,0,0,0,DW54,0,0,0,0,0,0,0,0,0,0,0,0,0,0,0,0,0,0,0,0,0,0,0,0)';
      OUTPUT_LOAD='(1.0,-1.0)';
    'DDR3_MA'<9>:
      PIN_NUMBER='(0,0,0,0,0,EF61,0,0,0,0,0,0,0,0,0,0,0,0,0,0,0,0,0,0,0,0,0,0,0,0)';
      OUTPUT_LOAD='(1.0,-1.0)';
    'DDR3_MA'<8>:
      PIN_NUMBER='(0,0,0,0,0,EB59,0,0,0,0,0,0,0,0,0,0,0,0,0,0,0,0,0,0,0,0,0,0,0,0)';
      OUTPUT_LOAD='(1.0,-1.0)';
    'DDR3_MA'<7>:
      PIN_NUMBER='(0,0,0,0,0,EA60,0,0,0,0,0,0,0,0,0,0,0,0,0,0,0,0,0,0,0,0,0,0,0,0)';
      OUTPUT_LOAD='(1.0,-1.0)';
    'DDR3_MA'<6>:
      PIN_NUMBER='(0,0,0,0,0,EE60,0,0,0,0,0,0,0,0,0,0,0,0,0,0,0,0,0,0,0,0,0,0,0,0)';
      OUTPUT_LOAD='(1.0,-1.0)';
    'DDR3_MA'<5>:
      PIN_NUMBER='(0,0,0,0,0,EA58,0,0,0,0,0,0,0,0,0,0,0,0,0,0,0,0,0,0,0,0,0,0,0,0)';
      OUTPUT_LOAD='(1.0,-1.0)';
    'DDR3_MA'<4>:
      PIN_NUMBER='(0,0,0,0,0,ED59,0,0,0,0,0,0,0,0,0,0,0,0,0,0,0,0,0,0,0,0,0,0,0,0)';
      OUTPUT_LOAD='(1.0,-1.0)';
    'DDR3_MA'<3>:
      PIN_NUMBER='(0,0,0,0,0,EB57,0,0,0,0,0,0,0,0,0,0,0,0,0,0,0,0,0,0,0,0,0,0,0,0)';
      OUTPUT_LOAD='(1.0,-1.0)';
    'DDR3_MA'<2>:
      PIN_NUMBER='(0,0,0,0,0,EE58,0,0,0,0,0,0,0,0,0,0,0,0,0,0,0,0,0,0,0,0,0,0,0,0)';
      OUTPUT_LOAD='(1.0,-1.0)';
    'DDR3_MA'<1>:
      PIN_NUMBER='(0,0,0,0,0,ED57,0,0,0,0,0,0,0,0,0,0,0,0,0,0,0,0,0,0,0,0,0,0,0,0)';
      OUTPUT_LOAD='(1.0,-1.0)';
    'DDR3_MA'<0>:
      PIN_NUMBER='(0,0,0,0,0,EB53,0,0,0,0,0,0,0,0,0,0,0,0,0,0,0,0,0,0,0,0,0,0,0,0)';
      OUTPUT_LOAD='(1.0,-1.0)';
    'DDR3_ODT'<3>:
      PIN_NUMBER='(0,0,0,0,0,EA48,0,0,0,0,0,0,0,0,0,0,0,0,0,0,0,0,0,0,0,0,0,0,0,0)';
      OUTPUT_LOAD='(1.0,-1.0)';
    'DDR3_ODT'<2>:
      PIN_NUMBER='(0,0,0,0,0,EA50,0,0,0,0,0,0,0,0,0,0,0,0,0,0,0,0,0,0,0,0,0,0,0,0)';
      OUTPUT_LOAD='(1.0,-1.0)';
    'DDR3_ODT'<1>:
      PIN_NUMBER='(0,0,0,0,0,EE48,0,0,0,0,0,0,0,0,0,0,0,0,0,0,0,0,0,0,0,0,0,0,0,0)';
      OUTPUT_LOAD='(1.0,-1.0)';
    'DDR3_ODT'<0>:
      PIN_NUMBER='(0,0,0,0,0,EE50,0,0,0,0,0,0,0,0,0,0,0,0,0,0,0,0,0,0,0,0,0,0,0,0)';
      OUTPUT_LOAD='(1.0,-1.0)';
    'DDR3_PAR':
      PIN_NUMBER='(0,0,0,0,0,ED53,0,0,0,0,0,0,0,0,0,0,0,0,0,0,0,0,0,0,0,0,0,0,0,0)';
      OUTPUT_LOAD='(1.0,-1.0)';
    'DDR4_ACT_N':
      PIN_NUMBER='(0,0,0,0,0,0,DR62,0,0,0,0,0,0,0,0,0,0,0,0,0,0,0,0,0,0,0,0,0,0,0)';
      OUTPUT_LOAD='(1.0,-1.0)';
    'DDR4_ALERT_N':
      PIN_NUMBER='(0,0,0,0,0,0,DT61,0,0,0,0,0,0,0,0,0,0,0,0,0,0,0,0,0,0,0,0,0,0,0)';
      INPUT_LOAD='(-0.01,0.01)';
    'DDR4_BA'<1>:
      PIN_NUMBER='(0,0,0,0,0,0,DV55,0,0,0,0,0,0,0,0,0,0,0,0,0,0,0,0,0,0,0,0,0,0,0)';
      OUTPUT_LOAD='(1.0,-1.0)';
    'DDR4_BA'<0>:
      PIN_NUMBER='(0,0,0,0,0,0,DM53,0,0,0,0,0,0,0,0,0,0,0,0,0,0,0,0,0,0,0,0,0,0,0)';
      OUTPUT_LOAD='(1.0,-1.0)';
    'DDR4_BG'<1>:
      PIN_NUMBER='(0,0,0,0,0,0,DM61,0,0,0,0,0,0,0,0,0,0,0,0,0,0,0,0,0,0,0,0,0,0,0)';
      OUTPUT_LOAD='(1.0,-1.0)';
    'DDR4_BG'<0>:
      PIN_NUMBER='(0,0,0,0,0,0,DJ62,0,0,0,0,0,0,0,0,0,0,0,0,0,0,0,0,0,0,0,0,0,0,0)';
      OUTPUT_LOAD='(1.0,-1.0)';
    'DDR4_CAVREF':
      PIN_NUMBER='(CT61,0,0,0,0,0,0,0,0,0,0,0,0,0,0,0,0,0,0,0,0,0,0,0,0,0,0,0,0,0)';
      OUTPUT_LOAD='(1.0,-1.0)';
    'DDR4_CID'<2>:
      PIN_NUMBER='(0,0,0,0,0,0,DT47,0,0,0,0,0,0,0,0,0,0,0,0,0,0,0,0,0,0,0,0,0,0,0)';
      OUTPUT_LOAD='(1.0,-1.0)';
    'DDR4_CKE'<3>:
      PIN_NUMBER='(0,0,0,0,0,0,DR64,0,0,0,0,0,0,0,0,0,0,0,0,0,0,0,0,0,0,0,0,0,0,0)';
      OUTPUT_LOAD='(1.0,-1.0)';
    'DDR4_CKE'<2>:
      PIN_NUMBER='(0,0,0,0,0,0,DL64,0,0,0,0,0,0,0,0,0,0,0,0,0,0,0,0,0,0,0,0,0,0,0)';
      OUTPUT_LOAD='(1.0,-1.0)';
    'DDR4_CKE'<1>:
      PIN_NUMBER='(0,0,0,0,0,0,DN64,0,0,0,0,0,0,0,0,0,0,0,0,0,0,0,0,0,0,0,0,0,0,0)';
      OUTPUT_LOAD='(1.0,-1.0)';
    'DDR4_CKE'<0>:
      PIN_NUMBER='(0,0,0,0,0,0,DM63,0,0,0,0,0,0,0,0,0,0,0,0,0,0,0,0,0,0,0,0,0,0,0)';
      OUTPUT_LOAD='(1.0,-1.0)';
    'DDR4_CLK_DN'<3>:
      PIN_NUMBER='(0,0,0,0,0,0,DT57,0,0,0,0,0,0,0,0,0,0,0,0,0,0,0,0,0,0,0,0,0,0,0)';
      OUTPUT_LOAD='(1.0,-1.0)';
    'DDR4_CLK_DN'<2>:
      PIN_NUMBER='(0,0,0,0,0,0,DM57,0,0,0,0,0,0,0,0,0,0,0,0,0,0,0,0,0,0,0,0,0,0,0)';
      OUTPUT_LOAD='(1.0,-1.0)';
    'DDR4_CLK_DN'<1>:
      PIN_NUMBER='(0,0,0,0,0,0,DR54,0,0,0,0,0,0,0,0,0,0,0,0,0,0,0,0,0,0,0,0,0,0,0)';
      OUTPUT_LOAD='(1.0,-1.0)';
    'DDR4_CLK_DN'<0>:
      PIN_NUMBER='(0,0,0,0,0,0,DM55,0,0,0,0,0,0,0,0,0,0,0,0,0,0,0,0,0,0,0,0,0,0,0)';
      OUTPUT_LOAD='(1.0,-1.0)';
    'DDR4_CLK_DP'<3>:
      PIN_NUMBER='(0,0,0,0,0,0,DR56,0,0,0,0,0,0,0,0,0,0,0,0,0,0,0,0,0,0,0,0,0,0,0)';
      OUTPUT_LOAD='(1.0,-1.0)';
    'DDR4_CLK_DP'<2>:
      PIN_NUMBER='(0,0,0,0,0,0,DN56,0,0,0,0,0,0,0,0,0,0,0,0,0,0,0,0,0,0,0,0,0,0,0)';
      OUTPUT_LOAD='(1.0,-1.0)';
    'DDR4_CLK_DP'<1>:
      PIN_NUMBER='(0,0,0,0,0,0,DT53,0,0,0,0,0,0,0,0,0,0,0,0,0,0,0,0,0,0,0,0,0,0,0)';
      OUTPUT_LOAD='(1.0,-1.0)';
    'DDR4_CLK_DP'<0>:
      PIN_NUMBER='(0,0,0,0,0,0,DN54,0,0,0,0,0,0,0,0,0,0,0,0,0,0,0,0,0,0,0,0,0,0,0)';
      OUTPUT_LOAD='(1.0,-1.0)';
    'DDR4_CS_N'<7>:
      PIN_NUMBER='(0,0,0,0,0,0,DN46,0,0,0,0,0,0,0,0,0,0,0,0,0,0,0,0,0,0,0,0,0,0,0)';
      OUTPUT_LOAD='(1.0,-1.0)';
    'DDR4_CS_N'<6>:
      PIN_NUMBER='(0,0,0,0,0,0,DT45,0,0,0,0,0,0,0,0,0,0,0,0,0,0,0,0,0,0,0,0,0,0,0)';
      OUTPUT_LOAD='(1.0,-1.0)';
    'DDR4_CS_N'<5>:
      PIN_NUMBER='(0,0,0,0,0,0,DM49,0,0,0,0,0,0,0,0,0,0,0,0,0,0,0,0,0,0,0,0,0,0,0)';
      OUTPUT_LOAD='(1.0,-1.0)';
    'DDR4_CS_N'<4>:
      PIN_NUMBER='(0,0,0,0,0,0,DW50,0,0,0,0,0,0,0,0,0,0,0,0,0,0,0,0,0,0,0,0,0,0,0)';
      OUTPUT_LOAD='(1.0,-1.0)';
    'DDR4_CS_N'<3>:
      PIN_NUMBER='(0,0,0,0,0,0,DK47,0,0,0,0,0,0,0,0,0,0,0,0,0,0,0,0,0,0,0,0,0,0,0)';
      OUTPUT_LOAD='(1.0,-1.0)';
    'DDR4_CS_N'<2>:
      PIN_NUMBER='(0,0,0,0,0,0,DR46,0,0,0,0,0,0,0,0,0,0,0,0,0,0,0,0,0,0,0,0,0,0,0)';
      OUTPUT_LOAD='(1.0,-1.0)';
    'DDR4_CS_N'<1>:
      PIN_NUMBER='(0,0,0,0,0,0,DN50,0,0,0,0,0,0,0,0,0,0,0,0,0,0,0,0,0,0,0,0,0,0,0)';
      OUTPUT_LOAD='(1.0,-1.0)';
    'DDR4_CS_N'<0>:
      PIN_NUMBER='(0,0,0,0,0,0,DV51,0,0,0,0,0,0,0,0,0,0,0,0,0,0,0,0,0,0,0,0,0,0,0)';
      OUTPUT_LOAD='(1.0,-1.0)';
    'DDR4_DQ'<63>:
      PIN_NUMBER='(0,0,0,0,0,0,DK25,0,0,0,0,0,0,0,0,0,0,0,0,0,0,0,0,0,0,0,0,0,0,0)';
      BIDIRECTIONAL='TRUE';
      INPUT_LOAD='(-0.01,0.01)';
      OUTPUT_LOAD='(1.0,-1.0)';
    'DDR4_DQ'<62>:
      PIN_NUMBER='(0,0,0,0,0,0,DF25,0,0,0,0,0,0,0,0,0,0,0,0,0,0,0,0,0,0,0,0,0,0,0)';
      BIDIRECTIONAL='TRUE';
      INPUT_LOAD='(-0.01,0.01)';
      OUTPUT_LOAD='(1.0,-1.0)';
    'DDR4_DQ'<61>:
      PIN_NUMBER='(0,0,0,0,0,0,DJ28,0,0,0,0,0,0,0,0,0,0,0,0,0,0,0,0,0,0,0,0,0,0,0)';
      BIDIRECTIONAL='TRUE';
      INPUT_LOAD='(-0.01,0.01)';
      OUTPUT_LOAD='(1.0,-1.0)';
    'DDR4_DQ'<60>:
      PIN_NUMBER='(0,0,0,0,0,0,DG28,0,0,0,0,0,0,0,0,0,0,0,0,0,0,0,0,0,0,0,0,0,0,0)';
      BIDIRECTIONAL='TRUE';
      INPUT_LOAD='(-0.01,0.01)';
      OUTPUT_LOAD='(1.0,-1.0)';
    'DDR4_DQ'<59>:
      PIN_NUMBER='(0,0,0,0,0,0,DJ24,0,0,0,0,0,0,0,0,0,0,0,0,0,0,0,0,0,0,0,0,0,0,0)';
      BIDIRECTIONAL='TRUE';
      INPUT_LOAD='(-0.01,0.01)';
      OUTPUT_LOAD='(1.0,-1.0)';
    'DDR4_DQ'<58>:
      PIN_NUMBER='(0,0,0,0,0,0,DD25,0,0,0,0,0,0,0,0,0,0,0,0,0,0,0,0,0,0,0,0,0,0,0)';
      BIDIRECTIONAL='TRUE';
      INPUT_LOAD='(-0.01,0.01)';
      OUTPUT_LOAD='(1.0,-1.0)';
    'DDR4_DQ'<57>:
      PIN_NUMBER='(0,0,0,0,0,0,DK27,0,0,0,0,0,0,0,0,0,0,0,0,0,0,0,0,0,0,0,0,0,0,0)';
      BIDIRECTIONAL='TRUE';
      INPUT_LOAD='(-0.01,0.01)';
      OUTPUT_LOAD='(1.0,-1.0)';
    'DDR4_DQ'<56>:
      PIN_NUMBER='(0,0,0,0,0,0,DF27,0,0,0,0,0,0,0,0,0,0,0,0,0,0,0,0,0,0,0,0,0,0,0)';
      BIDIRECTIONAL='TRUE';
      INPUT_LOAD='(-0.01,0.01)';
      OUTPUT_LOAD='(1.0,-1.0)';
    'DDR4_DQ'<55>:
      PIN_NUMBER='(0,0,0,0,0,0,ED25,0,0,0,0,0,0,0,0,0,0,0,0,0,0,0,0,0,0,0,0,0,0,0)';
      BIDIRECTIONAL='TRUE';
      INPUT_LOAD='(-0.01,0.01)';
      OUTPUT_LOAD='(1.0,-1.0)';
    'DDR4_DQ'<54>:
      PIN_NUMBER='(0,0,0,0,0,0,DY25,0,0,0,0,0,0,0,0,0,0,0,0,0,0,0,0,0,0,0,0,0,0,0)';
      BIDIRECTIONAL='TRUE';
      INPUT_LOAD='(-0.01,0.01)';
      OUTPUT_LOAD='(1.0,-1.0)';
    'DDR4_DQ'<53>:
      PIN_NUMBER='(0,0,0,0,0,0,EA28,0,0,0,0,0,0,0,0,0,0,0,0,0,0,0,0,0,0,0,0,0,0,0)';
      BIDIRECTIONAL='TRUE';
      INPUT_LOAD='(-0.01,0.01)';
      OUTPUT_LOAD='(1.0,-1.0)';
    'DDR4_DQ'<52>:
      PIN_NUMBER='(0,0,0,0,0,0,DY27,0,0,0,0,0,0,0,0,0,0,0,0,0,0,0,0,0,0,0,0,0,0,0)';
      BIDIRECTIONAL='TRUE';
      INPUT_LOAD='(-0.01,0.01)';
      OUTPUT_LOAD='(1.0,-1.0)';
    'DDR4_DQ'<51>:
      PIN_NUMBER='(0,0,0,0,0,0,EC24,0,0,0,0,0,0,0,0,0,0,0,0,0,0,0,0,0,0,0,0,0,0,0)';
      BIDIRECTIONAL='TRUE';
      INPUT_LOAD='(-0.01,0.01)';
      OUTPUT_LOAD='(1.0,-1.0)';
    'DDR4_DQ'<50>:
      PIN_NUMBER='(0,0,0,0,0,0,EA24,0,0,0,0,0,0,0,0,0,0,0,0,0,0,0,0,0,0,0,0,0,0,0)';
      BIDIRECTIONAL='TRUE';
      INPUT_LOAD='(-0.01,0.01)';
      OUTPUT_LOAD='(1.0,-1.0)';
    'DDR4_DQ'<49>:
      PIN_NUMBER='(0,0,0,0,0,0,ED27,0,0,0,0,0,0,0,0,0,0,0,0,0,0,0,0,0,0,0,0,0,0,0)';
      BIDIRECTIONAL='TRUE';
      INPUT_LOAD='(-0.01,0.01)';
      OUTPUT_LOAD='(1.0,-1.0)';
    'DDR4_DQ'<48>:
      PIN_NUMBER='(0,0,0,0,0,0,EC28,0,0,0,0,0,0,0,0,0,0,0,0,0,0,0,0,0,0,0,0,0,0,0)';
      BIDIRECTIONAL='TRUE';
      INPUT_LOAD='(-0.01,0.01)';
      OUTPUT_LOAD='(1.0,-1.0)';
    'DDR4_DQ'<47>:
      PIN_NUMBER='(0,0,0,0,0,0,ED31,0,0,0,0,0,0,0,0,0,0,0,0,0,0,0,0,0,0,0,0,0,0,0)';
      BIDIRECTIONAL='TRUE';
      INPUT_LOAD='(-0.01,0.01)';
      OUTPUT_LOAD='(1.0,-1.0)';
    'DDR4_DQ'<46>:
      PIN_NUMBER='(0,0,0,0,0,0,DY31,0,0,0,0,0,0,0,0,0,0,0,0,0,0,0,0,0,0,0,0,0,0,0)';
      BIDIRECTIONAL='TRUE';
      INPUT_LOAD='(-0.01,0.01)';
      OUTPUT_LOAD='(1.0,-1.0)';
    'DDR4_DQ'<45>:
      PIN_NUMBER='(0,0,0,0,0,0,EA34,0,0,0,0,0,0,0,0,0,0,0,0,0,0,0,0,0,0,0,0,0,0,0)';
      BIDIRECTIONAL='TRUE';
      INPUT_LOAD='(-0.01,0.01)';
      OUTPUT_LOAD='(1.0,-1.0)';
    'DDR4_DQ'<44>:
      PIN_NUMBER='(0,0,0,0,0,0,DY33,0,0,0,0,0,0,0,0,0,0,0,0,0,0,0,0,0,0,0,0,0,0,0)';
      BIDIRECTIONAL='TRUE';
      INPUT_LOAD='(-0.01,0.01)';
      OUTPUT_LOAD='(1.0,-1.0)';
    'DDR4_DQ'<43>:
      PIN_NUMBER='(0,0,0,0,0,0,EC30,0,0,0,0,0,0,0,0,0,0,0,0,0,0,0,0,0,0,0,0,0,0,0)';
      BIDIRECTIONAL='TRUE';
      INPUT_LOAD='(-0.01,0.01)';
      OUTPUT_LOAD='(1.0,-1.0)';
    'DDR4_DQ'<42>:
      PIN_NUMBER='(0,0,0,0,0,0,EA30,0,0,0,0,0,0,0,0,0,0,0,0,0,0,0,0,0,0,0,0,0,0,0)';
      BIDIRECTIONAL='TRUE';
      INPUT_LOAD='(-0.01,0.01)';
      OUTPUT_LOAD='(1.0,-1.0)';
    'DDR4_DQ'<41>:
      PIN_NUMBER='(0,0,0,0,0,0,ED33,0,0,0,0,0,0,0,0,0,0,0,0,0,0,0,0,0,0,0,0,0,0,0)';
      BIDIRECTIONAL='TRUE';
      INPUT_LOAD='(-0.01,0.01)';
      OUTPUT_LOAD='(1.0,-1.0)';
    'DDR4_DQ'<40>:
      PIN_NUMBER='(0,0,0,0,0,0,EC34,0,0,0,0,0,0,0,0,0,0,0,0,0,0,0,0,0,0,0,0,0,0,0)';
      BIDIRECTIONAL='TRUE';
      INPUT_LOAD='(-0.01,0.01)';
      OUTPUT_LOAD='(1.0,-1.0)';
    'DDR4_DQ'<39>:
      PIN_NUMBER='(0,0,0,0,0,0,DU40,0,0,0,0,0,0,0,0,0,0,0,0,0,0,0,0,0,0,0,0,0,0,0)';
      BIDIRECTIONAL='TRUE';
      INPUT_LOAD='(-0.01,0.01)';
      OUTPUT_LOAD='(1.0,-1.0)';
    'DDR4_DQ'<38>:
      PIN_NUMBER='(0,0,0,0,0,0,DN40,0,0,0,0,0,0,0,0,0,0,0,0,0,0,0,0,0,0,0,0,0,0,0)';
      BIDIRECTIONAL='TRUE';
      INPUT_LOAD='(-0.01,0.01)';
      OUTPUT_LOAD='(1.0,-1.0)';
    'DDR4_DQ'<37>:
      PIN_NUMBER='(0,0,0,0,0,0,DN42,0,0,0,0,0,0,0,0,0,0,0,0,0,0,0,0,0,0,0,0,0,0,0)';
      BIDIRECTIONAL='TRUE';
      INPUT_LOAD='(-0.01,0.01)';
      OUTPUT_LOAD='(1.0,-1.0)';
    'DDR4_DQ'<36>:
      PIN_NUMBER='(0,0,0,0,0,0,DL42,0,0,0,0,0,0,0,0,0,0,0,0,0,0,0,0,0,0,0,0,0,0,0)';
      BIDIRECTIONAL='TRUE';
      INPUT_LOAD='(-0.01,0.01)';
      OUTPUT_LOAD='(1.0,-1.0)';
    'DDR4_DQ'<35>:
      PIN_NUMBER='(0,0,0,0,0,0,DT39,0,0,0,0,0,0,0,0,0,0,0,0,0,0,0,0,0,0,0,0,0,0,0)';
      BIDIRECTIONAL='TRUE';
      INPUT_LOAD='(-0.01,0.01)';
      OUTPUT_LOAD='(1.0,-1.0)';
    'DDR4_DQ'<34>:
      PIN_NUMBER='(0,0,0,0,0,0,DP39,0,0,0,0,0,0,0,0,0,0,0,0,0,0,0,0,0,0,0,0,0,0,0)';
      BIDIRECTIONAL='TRUE';
      INPUT_LOAD='(-0.01,0.01)';
      OUTPUT_LOAD='(1.0,-1.0)';
    'DDR4_DQ'<33>:
      PIN_NUMBER='(0,0,0,0,0,0,DW42,0,0,0,0,0,0,0,0,0,0,0,0,0,0,0,0,0,0,0,0,0,0,0)';
      BIDIRECTIONAL='TRUE';
      INPUT_LOAD='(-0.01,0.01)';
      OUTPUT_LOAD='(1.0,-1.0)';
    'DDR4_DQ'<32>:
      PIN_NUMBER='(0,0,0,0,0,0,DU42,0,0,0,0,0,0,0,0,0,0,0,0,0,0,0,0,0,0,0,0,0,0,0)';
      BIDIRECTIONAL='TRUE';
      INPUT_LOAD='(-0.01,0.01)';
      OUTPUT_LOAD='(1.0,-1.0)';
    'DDR4_DQ'<31>:
      PIN_NUMBER='(0,0,0,0,0,0,EE72,0,0,0,0,0,0,0,0,0,0,0,0,0,0,0,0,0,0,0,0,0,0,0)';
      BIDIRECTIONAL='TRUE';
      INPUT_LOAD='(-0.01,0.01)';
      OUTPUT_LOAD='(1.0,-1.0)';
    'DDR4_DQ'<30>:
      PIN_NUMBER='(0,0,0,0,0,0,EA72,0,0,0,0,0,0,0,0,0,0,0,0,0,0,0,0,0,0,0,0,0,0,0)';
      BIDIRECTIONAL='TRUE';
      INPUT_LOAD='(-0.01,0.01)';
      OUTPUT_LOAD='(1.0,-1.0)';
    'DDR4_DQ'<29>:
      PIN_NUMBER='(0,0,0,0,0,0,EB75,0,0,0,0,0,0,0,0,0,0,0,0,0,0,0,0,0,0,0,0,0,0,0)';
      BIDIRECTIONAL='TRUE';
      INPUT_LOAD='(-0.01,0.01)';
      OUTPUT_LOAD='(1.0,-1.0)';
    'DDR4_DQ'<28>:
      PIN_NUMBER='(0,0,0,0,0,0,EA74,0,0,0,0,0,0,0,0,0,0,0,0,0,0,0,0,0,0,0,0,0,0,0)';
      BIDIRECTIONAL='TRUE';
      INPUT_LOAD='(-0.01,0.01)';
      OUTPUT_LOAD='(1.0,-1.0)';
    'DDR4_DQ'<27>:
      PIN_NUMBER='(0,0,0,0,0,0,ED71,0,0,0,0,0,0,0,0,0,0,0,0,0,0,0,0,0,0,0,0,0,0,0)';
      BIDIRECTIONAL='TRUE';
      INPUT_LOAD='(-0.01,0.01)';
      OUTPUT_LOAD='(1.0,-1.0)';
    'DDR4_DQ'<26>:
      PIN_NUMBER='(0,0,0,0,0,0,EB71,0,0,0,0,0,0,0,0,0,0,0,0,0,0,0,0,0,0,0,0,0,0,0)';
      BIDIRECTIONAL='TRUE';
      INPUT_LOAD='(-0.01,0.01)';
      OUTPUT_LOAD='(1.0,-1.0)';
    'DDR4_DQ'<25>:
      PIN_NUMBER='(0,0,0,0,0,0,EE74,0,0,0,0,0,0,0,0,0,0,0,0,0,0,0,0,0,0,0,0,0,0,0)';
      BIDIRECTIONAL='TRUE';
      INPUT_LOAD='(-0.01,0.01)';
      OUTPUT_LOAD='(1.0,-1.0)';
    'DDR4_DQ'<24>:
      PIN_NUMBER='(0,0,0,0,0,0,ED75,0,0,0,0,0,0,0,0,0,0,0,0,0,0,0,0,0,0,0,0,0,0,0)';
      BIDIRECTIONAL='TRUE';
      INPUT_LOAD='(-0.01,0.01)';
      OUTPUT_LOAD='(1.0,-1.0)';
    'DDR4_DQ'<23>:
      PIN_NUMBER='(0,0,0,0,0,0,EC78,0,0,0,0,0,0,0,0,0,0,0,0,0,0,0,0,0,0,0,0,0,0,0)';
      BIDIRECTIONAL='TRUE';
      INPUT_LOAD='(-0.01,0.01)';
      OUTPUT_LOAD='(1.0,-1.0)';
    'DDR4_DQ'<22>:
      PIN_NUMBER='(0,0,0,0,0,0,DW78,0,0,0,0,0,0,0,0,0,0,0,0,0,0,0,0,0,0,0,0,0,0,0)';
      BIDIRECTIONAL='TRUE';
      INPUT_LOAD='(-0.01,0.01)';
      OUTPUT_LOAD='(1.0,-1.0)';
    'DDR4_DQ'<21>:
      PIN_NUMBER='(0,0,0,0,0,0,EB81,0,0,0,0,0,0,0,0,0,0,0,0,0,0,0,0,0,0,0,0,0,0,0)';
      BIDIRECTIONAL='TRUE';
      INPUT_LOAD='(-0.01,0.01)';
      OUTPUT_LOAD='(1.0,-1.0)';
    'DDR4_DQ'<20>:
      PIN_NUMBER='(0,0,0,0,0,0,DY81,0,0,0,0,0,0,0,0,0,0,0,0,0,0,0,0,0,0,0,0,0,0,0)';
      BIDIRECTIONAL='TRUE';
      INPUT_LOAD='(-0.01,0.01)';
      OUTPUT_LOAD='(1.0,-1.0)';
    'DDR4_DQ'<19>:
      PIN_NUMBER='(0,0,0,0,0,0,EB77,0,0,0,0,0,0,0,0,0,0,0,0,0,0,0,0,0,0,0,0,0,0,0)';
      BIDIRECTIONAL='TRUE';
      INPUT_LOAD='(-0.01,0.01)';
      OUTPUT_LOAD='(1.0,-1.0)';
    'DDR4_DQ'<18>:
      PIN_NUMBER='(0,0,0,0,0,0,DY77,0,0,0,0,0,0,0,0,0,0,0,0,0,0,0,0,0,0,0,0,0,0,0)';
      BIDIRECTIONAL='TRUE';
      INPUT_LOAD='(-0.01,0.01)';
      OUTPUT_LOAD='(1.0,-1.0)';
    'DDR4_DQ'<17>:
      PIN_NUMBER='(0,0,0,0,0,0,EC80,0,0,0,0,0,0,0,0,0,0,0,0,0,0,0,0,0,0,0,0,0,0,0)';
      BIDIRECTIONAL='TRUE';
      INPUT_LOAD='(-0.01,0.01)';
      OUTPUT_LOAD='(1.0,-1.0)';
    'DDR4_DQ'<16>:
      PIN_NUMBER='(0,0,0,0,0,0,DW80,0,0,0,0,0,0,0,0,0,0,0,0,0,0,0,0,0,0,0,0,0,0,0)';
      BIDIRECTIONAL='TRUE';
      INPUT_LOAD='(-0.01,0.01)';
      OUTPUT_LOAD='(1.0,-1.0)';
    'DDR4_DQ'<15>:
      PIN_NUMBER='(0,0,0,0,0,0,DE82,0,0,0,0,0,0,0,0,0,0,0,0,0,0,0,0,0,0,0,0,0,0,0)';
      BIDIRECTIONAL='TRUE';
      INPUT_LOAD='(-0.01,0.01)';
      OUTPUT_LOAD='(1.0,-1.0)';
    'DDR4_DQ'<14>:
      PIN_NUMBER='(0,0,0,0,0,0,DC82,0,0,0,0,0,0,0,0,0,0,0,0,0,0,0,0,0,0,0,0,0,0,0)';
      BIDIRECTIONAL='TRUE';
      INPUT_LOAD='(-0.01,0.01)';
      OUTPUT_LOAD='(1.0,-1.0)';
    'DDR4_DQ'<13>:
      PIN_NUMBER='(0,0,0,0,0,0,CW80,0,0,0,0,0,0,0,0,0,0,0,0,0,0,0,0,0,0,0,0,0,0,0)';
      BIDIRECTIONAL='TRUE';
      INPUT_LOAD='(-0.01,0.01)';
      OUTPUT_LOAD='(1.0,-1.0)';
    'DDR4_DQ'<12>:
      PIN_NUMBER='(0,0,0,0,0,0,CY79,0,0,0,0,0,0,0,0,0,0,0,0,0,0,0,0,0,0,0,0,0,0,0)';
      BIDIRECTIONAL='TRUE';
      INPUT_LOAD='(-0.01,0.01)';
      OUTPUT_LOAD='(1.0,-1.0)';
    'DDR4_DQ'<11>:
      PIN_NUMBER='(0,0,0,0,0,0,DF81,0,0,0,0,0,0,0,0,0,0,0,0,0,0,0,0,0,0,0,0,0,0,0)';
      BIDIRECTIONAL='TRUE';
      INPUT_LOAD='(-0.01,0.01)';
      OUTPUT_LOAD='(1.0,-1.0)';
    'DDR4_DQ'<10>:
      PIN_NUMBER='(0,0,0,0,0,0,DE80,0,0,0,0,0,0,0,0,0,0,0,0,0,0,0,0,0,0,0,0,0,0,0)';
      BIDIRECTIONAL='TRUE';
      INPUT_LOAD='(-0.01,0.01)';
      OUTPUT_LOAD='(1.0,-1.0)';
    'DDR4_DQ'<9>:
      PIN_NUMBER='(0,0,0,0,0,0,CY81,0,0,0,0,0,0,0,0,0,0,0,0,0,0,0,0,0,0,0,0,0,0,0)';
      BIDIRECTIONAL='TRUE';
      INPUT_LOAD='(-0.01,0.01)';
      OUTPUT_LOAD='(1.0,-1.0)';
    'DDR4_DQ'<8>:
      PIN_NUMBER='(0,0,0,0,0,0,DB79,0,0,0,0,0,0,0,0,0,0,0,0,0,0,0,0,0,0,0,0,0,0,0)';
      BIDIRECTIONAL='TRUE';
      INPUT_LOAD='(-0.01,0.01)';
      OUTPUT_LOAD='(1.0,-1.0)';
    'DDR4_DQ'<7>:
      PIN_NUMBER='(0,0,0,0,0,0,CN82,0,0,0,0,0,0,0,0,0,0,0,0,0,0,0,0,0,0,0,0,0,0,0)';
      BIDIRECTIONAL='TRUE';
      INPUT_LOAD='(-0.01,0.01)';
      OUTPUT_LOAD='(1.0,-1.0)';
    'DDR4_DQ'<6>:
      PIN_NUMBER='(0,0,0,0,0,0,CR80,0,0,0,0,0,0,0,0,0,0,0,0,0,0,0,0,0,0,0,0,0,0,0)';
      BIDIRECTIONAL='TRUE';
      INPUT_LOAD='(-0.01,0.01)';
      OUTPUT_LOAD='(1.0,-1.0)';
    'DDR4_DQ'<5>:
      PIN_NUMBER='(0,0,0,0,0,0,CJ80,0,0,0,0,0,0,0,0,0,0,0,0,0,0,0,0,0,0,0,0,0,0,0)';
      BIDIRECTIONAL='TRUE';
      INPUT_LOAD='(-0.01,0.01)';
      OUTPUT_LOAD='(1.0,-1.0)';
    'DDR4_DQ'<4>:
      PIN_NUMBER='(0,0,0,0,0,0,CK79,0,0,0,0,0,0,0,0,0,0,0,0,0,0,0,0,0,0,0,0,0,0,0)';
      BIDIRECTIONAL='TRUE';
      INPUT_LOAD='(-0.01,0.01)';
      OUTPUT_LOAD='(1.0,-1.0)';
    'DDR4_DQ'<3>:
      PIN_NUMBER='(0,0,0,0,0,0,CR82,0,0,0,0,0,0,0,0,0,0,0,0,0,0,0,0,0,0,0,0,0,0,0)';
      BIDIRECTIONAL='TRUE';
      INPUT_LOAD='(-0.01,0.01)';
      OUTPUT_LOAD='(1.0,-1.0)';
    'DDR4_DQ'<2>:
      PIN_NUMBER='(0,0,0,0,0,0,CT81,0,0,0,0,0,0,0,0,0,0,0,0,0,0,0,0,0,0,0,0,0,0,0)';
      BIDIRECTIONAL='TRUE';
      INPUT_LOAD='(-0.01,0.01)';
      OUTPUT_LOAD='(1.0,-1.0)';
    'DDR4_DQ'<1>:
      PIN_NUMBER='(0,0,0,0,0,0,CK81,0,0,0,0,0,0,0,0,0,0,0,0,0,0,0,0,0,0,0,0,0,0,0)';
      BIDIRECTIONAL='TRUE';
      INPUT_LOAD='(-0.01,0.01)';
      OUTPUT_LOAD='(1.0,-1.0)';
    'DDR4_DQ'<0>:
      PIN_NUMBER='(0,0,0,0,0,0,CM79,0,0,0,0,0,0,0,0,0,0,0,0,0,0,0,0,0,0,0,0,0,0,0)';
      BIDIRECTIONAL='TRUE';
      INPUT_LOAD='(-0.01,0.01)';
      OUTPUT_LOAD='(1.0,-1.0)';
    'DDR4_DQS_DN'<17>:
      PIN_NUMBER='(0,0,0,0,0,0,DV67,0,0,0,0,0,0,0,0,0,0,0,0,0,0,0,0,0,0,0,0,0,0,0)';
      BIDIRECTIONAL='TRUE';
      INPUT_LOAD='(-0.01,0.01)';
      OUTPUT_LOAD='(1.0,-1.0)';
    'DDR4_DQS_DN'<16>:
      PIN_NUMBER='(0,0,0,0,0,0,DG26,0,0,0,0,0,0,0,0,0,0,0,0,0,0,0,0,0,0,0,0,0,0,0)';
      BIDIRECTIONAL='TRUE';
      INPUT_LOAD='(-0.01,0.01)';
      OUTPUT_LOAD='(1.0,-1.0)';
    'DDR4_DQS_DN'<15>:
      PIN_NUMBER='(0,0,0,0,0,0,EA26,0,0,0,0,0,0,0,0,0,0,0,0,0,0,0,0,0,0,0,0,0,0,0)';
      BIDIRECTIONAL='TRUE';
      INPUT_LOAD='(-0.01,0.01)';
      OUTPUT_LOAD='(1.0,-1.0)';
    'DDR4_DQS_DN'<14>:
      PIN_NUMBER='(0,0,0,0,0,0,EA32,0,0,0,0,0,0,0,0,0,0,0,0,0,0,0,0,0,0,0,0,0,0,0)';
      BIDIRECTIONAL='TRUE';
      INPUT_LOAD='(-0.01,0.01)';
      OUTPUT_LOAD='(1.0,-1.0)';
    'DDR4_DQS_DN'<13>:
      PIN_NUMBER='(0,0,0,0,0,0,DP41,0,0,0,0,0,0,0,0,0,0,0,0,0,0,0,0,0,0,0,0,0,0,0)';
      BIDIRECTIONAL='TRUE';
      INPUT_LOAD='(-0.01,0.01)';
      OUTPUT_LOAD='(1.0,-1.0)';
    'DDR4_DQS_DN'<12>:
      PIN_NUMBER='(0,0,0,0,0,0,EB73,0,0,0,0,0,0,0,0,0,0,0,0,0,0,0,0,0,0,0,0,0,0,0)';
      BIDIRECTIONAL='TRUE';
      INPUT_LOAD='(-0.01,0.01)';
      OUTPUT_LOAD='(1.0,-1.0)';
    'DDR4_DQS_DN'<11>:
      PIN_NUMBER='(0,0,0,0,0,0,DY79,0,0,0,0,0,0,0,0,0,0,0,0,0,0,0,0,0,0,0,0,0,0,0)';
      BIDIRECTIONAL='TRUE';
      INPUT_LOAD='(-0.01,0.01)';
      OUTPUT_LOAD='(1.0,-1.0)';
    'DDR4_DQS_DN'<10>:
      PIN_NUMBER='(0,0,0,0,0,0,DC80,0,0,0,0,0,0,0,0,0,0,0,0,0,0,0,0,0,0,0,0,0,0,0)';
      BIDIRECTIONAL='TRUE';
      INPUT_LOAD='(-0.01,0.01)';
      OUTPUT_LOAD='(1.0,-1.0)';
    'DDR4_DQS_DN'<9>:
      PIN_NUMBER='(0,0,0,0,0,0,CN80,0,0,0,0,0,0,0,0,0,0,0,0,0,0,0,0,0,0,0,0,0,0,0)';
      BIDIRECTIONAL='TRUE';
      INPUT_LOAD='(-0.01,0.01)';
      OUTPUT_LOAD='(1.0,-1.0)';
    'DDR4_DQS_DN'<8>:
      PIN_NUMBER='(0,0,0,0,0,0,EB67,0,0,0,0,0,0,0,0,0,0,0,0,0,0,0,0,0,0,0,0,0,0,0)';
      BIDIRECTIONAL='TRUE';
      INPUT_LOAD='(-0.01,0.01)';
      OUTPUT_LOAD='(1.0,-1.0)';
    'DDR4_DQS_DN'<7>:
      PIN_NUMBER='(0,0,0,0,0,0,DL26,0,0,0,0,0,0,0,0,0,0,0,0,0,0,0,0,0,0,0,0,0,0,0)';
      BIDIRECTIONAL='TRUE';
      INPUT_LOAD='(-0.01,0.01)';
      OUTPUT_LOAD='(1.0,-1.0)';
    'DDR4_DQS_DN'<6>:
      PIN_NUMBER='(0,0,0,0,0,0,EE26,0,0,0,0,0,0,0,0,0,0,0,0,0,0,0,0,0,0,0,0,0,0,0)';
      BIDIRECTIONAL='TRUE';
      INPUT_LOAD='(-0.01,0.01)';
      OUTPUT_LOAD='(1.0,-1.0)';
    'DDR4_DQS_DN'<5>:
      PIN_NUMBER='(0,0,0,0,0,0,EE32,0,0,0,0,0,0,0,0,0,0,0,0,0,0,0,0,0,0,0,0,0,0,0)';
      BIDIRECTIONAL='TRUE';
      INPUT_LOAD='(-0.01,0.01)';
      OUTPUT_LOAD='(1.0,-1.0)';
    'DDR4_DQS_DN'<4>:
      PIN_NUMBER='(0,0,0,0,0,0,DV41,0,0,0,0,0,0,0,0,0,0,0,0,0,0,0,0,0,0,0,0,0,0,0)';
      BIDIRECTIONAL='TRUE';
      INPUT_LOAD='(-0.01,0.01)';
      OUTPUT_LOAD='(1.0,-1.0)';
    'DDR4_DQS_DN'<3>:
      PIN_NUMBER='(0,0,0,0,0,0,EF73,0,0,0,0,0,0,0,0,0,0,0,0,0,0,0,0,0,0,0,0,0,0,0)';
      BIDIRECTIONAL='TRUE';
      INPUT_LOAD='(-0.01,0.01)';
      OUTPUT_LOAD='(1.0,-1.0)';
    'DDR4_DQS_DN'<2>:
      PIN_NUMBER='(0,0,0,0,0,0,ED79,0,0,0,0,0,0,0,0,0,0,0,0,0,0,0,0,0,0,0,0,0,0,0)';
      BIDIRECTIONAL='TRUE';
      INPUT_LOAD='(-0.01,0.01)';
      OUTPUT_LOAD='(1.0,-1.0)';
    'DDR4_DQS_DN'<1>:
      PIN_NUMBER='(0,0,0,0,0,0,DA82,0,0,0,0,0,0,0,0,0,0,0,0,0,0,0,0,0,0,0,0,0,0,0)';
      BIDIRECTIONAL='TRUE';
      INPUT_LOAD='(-0.01,0.01)';
      OUTPUT_LOAD='(1.0,-1.0)';
    'DDR4_DQS_DN'<0>:
      PIN_NUMBER='(0,0,0,0,0,0,CL82,0,0,0,0,0,0,0,0,0,0,0,0,0,0,0,0,0,0,0,0,0,0,0)';
      BIDIRECTIONAL='TRUE';
      INPUT_LOAD='(-0.01,0.01)';
      OUTPUT_LOAD='(1.0,-1.0)';
    'DDR4_DQS_DP'<17>:
      PIN_NUMBER='(0,0,0,0,0,0,DT67,0,0,0,0,0,0,0,0,0,0,0,0,0,0,0,0,0,0,0,0,0,0,0)';
      BIDIRECTIONAL='TRUE';
      INPUT_LOAD='(-0.01,0.01)';
      OUTPUT_LOAD='(1.0,-1.0)';
    'DDR4_DQS_DP'<16>:
      PIN_NUMBER='(0,0,0,0,0,0,DE26,0,0,0,0,0,0,0,0,0,0,0,0,0,0,0,0,0,0,0,0,0,0,0)';
      BIDIRECTIONAL='TRUE';
      INPUT_LOAD='(-0.01,0.01)';
      OUTPUT_LOAD='(1.0,-1.0)';
    'DDR4_DQS_DP'<15>:
      PIN_NUMBER='(0,0,0,0,0,0,DW26,0,0,0,0,0,0,0,0,0,0,0,0,0,0,0,0,0,0,0,0,0,0,0)';
      BIDIRECTIONAL='TRUE';
      INPUT_LOAD='(-0.01,0.01)';
      OUTPUT_LOAD='(1.0,-1.0)';
    'DDR4_DQS_DP'<14>:
      PIN_NUMBER='(0,0,0,0,0,0,DW32,0,0,0,0,0,0,0,0,0,0,0,0,0,0,0,0,0,0,0,0,0,0,0)';
      BIDIRECTIONAL='TRUE';
      INPUT_LOAD='(-0.01,0.01)';
      OUTPUT_LOAD='(1.0,-1.0)';
    'DDR4_DQS_DP'<13>:
      PIN_NUMBER='(0,0,0,0,0,0,DM41,0,0,0,0,0,0,0,0,0,0,0,0,0,0,0,0,0,0,0,0,0,0,0)';
      BIDIRECTIONAL='TRUE';
      INPUT_LOAD='(-0.01,0.01)';
      OUTPUT_LOAD='(1.0,-1.0)';
    'DDR4_DQS_DP'<12>:
      PIN_NUMBER='(0,0,0,0,0,0,DY73,0,0,0,0,0,0,0,0,0,0,0,0,0,0,0,0,0,0,0,0,0,0,0)';
      BIDIRECTIONAL='TRUE';
      INPUT_LOAD='(-0.01,0.01)';
      OUTPUT_LOAD='(1.0,-1.0)';
    'DDR4_DQS_DP'<11>:
      PIN_NUMBER='(0,0,0,0,0,0,DV79,0,0,0,0,0,0,0,0,0,0,0,0,0,0,0,0,0,0,0,0,0,0,0)';
      BIDIRECTIONAL='TRUE';
      INPUT_LOAD='(-0.01,0.01)';
      OUTPUT_LOAD='(1.0,-1.0)';
    'DDR4_DQS_DP'<10>:
      PIN_NUMBER='(0,0,0,0,0,0,DD79,0,0,0,0,0,0,0,0,0,0,0,0,0,0,0,0,0,0,0,0,0,0,0)';
      BIDIRECTIONAL='TRUE';
      INPUT_LOAD='(-0.01,0.01)';
      OUTPUT_LOAD='(1.0,-1.0)';
    'DDR4_DQS_DP'<9>:
      PIN_NUMBER='(0,0,0,0,0,0,CP79,0,0,0,0,0,0,0,0,0,0,0,0,0,0,0,0,0,0,0,0,0,0,0)';
      BIDIRECTIONAL='TRUE';
      INPUT_LOAD='(-0.01,0.01)';
      OUTPUT_LOAD='(1.0,-1.0)';
    'DDR4_DQS_DP'<8>:
      PIN_NUMBER='(0,0,0,0,0,0,DY67,0,0,0,0,0,0,0,0,0,0,0,0,0,0,0,0,0,0,0,0,0,0,0)';
      BIDIRECTIONAL='TRUE';
      INPUT_LOAD='(-0.01,0.01)';
      OUTPUT_LOAD='(1.0,-1.0)';
    'DDR4_DQS_DP'<7>:
      PIN_NUMBER='(0,0,0,0,0,0,DJ26,0,0,0,0,0,0,0,0,0,0,0,0,0,0,0,0,0,0,0,0,0,0,0)';
      BIDIRECTIONAL='TRUE';
      INPUT_LOAD='(-0.01,0.01)';
      OUTPUT_LOAD='(1.0,-1.0)';
    'DDR4_DQS_DP'<6>:
      PIN_NUMBER='(0,0,0,0,0,0,EC26,0,0,0,0,0,0,0,0,0,0,0,0,0,0,0,0,0,0,0,0,0,0,0)';
      BIDIRECTIONAL='TRUE';
      INPUT_LOAD='(-0.01,0.01)';
      OUTPUT_LOAD='(1.0,-1.0)';
    'DDR4_DQS_DP'<5>:
      PIN_NUMBER='(0,0,0,0,0,0,EC32,0,0,0,0,0,0,0,0,0,0,0,0,0,0,0,0,0,0,0,0,0,0,0)';
      BIDIRECTIONAL='TRUE';
      INPUT_LOAD='(-0.01,0.01)';
      OUTPUT_LOAD='(1.0,-1.0)';
    'DDR4_DQS_DP'<4>:
      PIN_NUMBER='(0,0,0,0,0,0,DT41,0,0,0,0,0,0,0,0,0,0,0,0,0,0,0,0,0,0,0,0,0,0,0)';
      BIDIRECTIONAL='TRUE';
      INPUT_LOAD='(-0.01,0.01)';
      OUTPUT_LOAD='(1.0,-1.0)';
    'DDR4_DQS_DP'<3>:
      PIN_NUMBER='(0,0,0,0,0,0,ED73,0,0,0,0,0,0,0,0,0,0,0,0,0,0,0,0,0,0,0,0,0,0,0)';
      BIDIRECTIONAL='TRUE';
      INPUT_LOAD='(-0.01,0.01)';
      OUTPUT_LOAD='(1.0,-1.0)';
    'DDR4_DQS_DP'<2>:
      PIN_NUMBER='(0,0,0,0,0,0,EB79,0,0,0,0,0,0,0,0,0,0,0,0,0,0,0,0,0,0,0,0,0,0,0)';
      BIDIRECTIONAL='TRUE';
      INPUT_LOAD='(-0.01,0.01)';
      OUTPUT_LOAD='(1.0,-1.0)';
    'DDR4_DQS_DP'<1>:
      PIN_NUMBER='(0,0,0,0,0,0,DB81,0,0,0,0,0,0,0,0,0,0,0,0,0,0,0,0,0,0,0,0,0,0,0)';
      BIDIRECTIONAL='TRUE';
      INPUT_LOAD='(-0.01,0.01)';
      OUTPUT_LOAD='(1.0,-1.0)';
    'DDR4_DQS_DP'<0>:
      PIN_NUMBER='(0,0,0,0,0,0,CM81,0,0,0,0,0,0,0,0,0,0,0,0,0,0,0,0,0,0,0,0,0,0,0)';
      BIDIRECTIONAL='TRUE';
      INPUT_LOAD='(-0.01,0.01)';
      OUTPUT_LOAD='(1.0,-1.0)';
    'DDR4_ECC'<7>:
      PIN_NUMBER='(0,0,0,0,0,0,EA66,0,0,0,0,0,0,0,0,0,0,0,0,0,0,0,0,0,0,0,0,0,0,0)';
      BIDIRECTIONAL='TRUE';
      INPUT_LOAD='(-0.01,0.01)';
      OUTPUT_LOAD='(1.0,-1.0)';
    'DDR4_ECC'<6>:
      PIN_NUMBER='(0,0,0,0,0,0,DU66,0,0,0,0,0,0,0,0,0,0,0,0,0,0,0,0,0,0,0,0,0,0,0)';
      BIDIRECTIONAL='TRUE';
      INPUT_LOAD='(-0.01,0.01)';
      OUTPUT_LOAD='(1.0,-1.0)';
    'DDR4_ECC'<5>:
      PIN_NUMBER='(0,0,0,0,0,0,DV69,0,0,0,0,0,0,0,0,0,0,0,0,0,0,0,0,0,0,0,0,0,0,0)';
      BIDIRECTIONAL='TRUE';
      INPUT_LOAD='(-0.01,0.01)';
      OUTPUT_LOAD='(1.0,-1.0)';
    'DDR4_ECC'<4>:
      PIN_NUMBER='(0,0,0,0,0,0,DU68,0,0,0,0,0,0,0,0,0,0,0,0,0,0,0,0,0,0,0,0,0,0,0)';
      BIDIRECTIONAL='TRUE';
      INPUT_LOAD='(-0.01,0.01)';
      OUTPUT_LOAD='(1.0,-1.0)';
    'DDR4_ECC'<3>:
      PIN_NUMBER='(0,0,0,0,0,0,DY65,0,0,0,0,0,0,0,0,0,0,0,0,0,0,0,0,0,0,0,0,0,0,0)';
      BIDIRECTIONAL='TRUE';
      INPUT_LOAD='(-0.01,0.01)';
      OUTPUT_LOAD='(1.0,-1.0)';
    'DDR4_ECC'<2>:
      PIN_NUMBER='(0,0,0,0,0,0,DV65,0,0,0,0,0,0,0,0,0,0,0,0,0,0,0,0,0,0,0,0,0,0,0)';
      BIDIRECTIONAL='TRUE';
      INPUT_LOAD='(-0.01,0.01)';
      OUTPUT_LOAD='(1.0,-1.0)';
    'DDR4_ECC'<1>:
      PIN_NUMBER='(0,0,0,0,0,0,EA68,0,0,0,0,0,0,0,0,0,0,0,0,0,0,0,0,0,0,0,0,0,0,0)';
      BIDIRECTIONAL='TRUE';
      INPUT_LOAD='(-0.01,0.01)';
      OUTPUT_LOAD='(1.0,-1.0)';
    'DDR4_ECC'<0>:
      PIN_NUMBER='(0,0,0,0,0,0,DY69,0,0,0,0,0,0,0,0,0,0,0,0,0,0,0,0,0,0,0,0,0,0,0)';
      BIDIRECTIONAL='TRUE';
      INPUT_LOAD='(-0.01,0.01)';
      OUTPUT_LOAD='(1.0,-1.0)';
    'DDR4_MA'<17>:
      PIN_NUMBER='(0,0,0,0,0,0,DR48,0,0,0,0,0,0,0,0,0,0,0,0,0,0,0,0,0,0,0,0,0,0,0)';
      OUTPUT_LOAD='(1.0,-1.0)';
    'DDR4_MA'<16>:
      PIN_NUMBER='(0,0,0,0,0,0,DN52,0,0,0,0,0,0,0,0,0,0,0,0,0,0,0,0,0,0,0,0,0,0,0)';
      OUTPUT_LOAD='(1.0,-1.0)';
    'DDR4_MA'<15>:
      PIN_NUMBER='(0,0,0,0,0,0,DR52,0,0,0,0,0,0,0,0,0,0,0,0,0,0,0,0,0,0,0,0,0,0,0)';
      OUTPUT_LOAD='(1.0,-1.0)';
    'DDR4_MA'<14>:
      PIN_NUMBER='(0,0,0,0,0,0,DM51,0,0,0,0,0,0,0,0,0,0,0,0,0,0,0,0,0,0,0,0,0,0,0)';
      OUTPUT_LOAD='(1.0,-1.0)';
    'DDR4_MA'<13>:
      PIN_NUMBER='(0,0,0,0,0,0,DT51,0,0,0,0,0,0,0,0,0,0,0,0,0,0,0,0,0,0,0,0,0,0,0)';
      OUTPUT_LOAD='(1.0,-1.0)';
    'DDR4_MA'<12>:
      PIN_NUMBER='(0,0,0,0,0,0,DN60,0,0,0,0,0,0,0,0,0,0,0,0,0,0,0,0,0,0,0,0,0,0,0)';
      OUTPUT_LOAD='(1.0,-1.0)';
    'DDR4_MA'<11>:
      PIN_NUMBER='(0,0,0,0,0,0,DR60,0,0,0,0,0,0,0,0,0,0,0,0,0,0,0,0,0,0,0,0,0,0,0)';
      OUTPUT_LOAD='(1.0,-1.0)';
    'DDR4_MA'<10>:
      PIN_NUMBER='(0,0,0,0,0,0,DT55,0,0,0,0,0,0,0,0,0,0,0,0,0,0,0,0,0,0,0,0,0,0,0)';
      OUTPUT_LOAD='(1.0,-1.0)';
    'DDR4_MA'<9>:
      PIN_NUMBER='(0,0,0,0,0,0,DV59,0,0,0,0,0,0,0,0,0,0,0,0,0,0,0,0,0,0,0,0,0,0,0)';
      OUTPUT_LOAD='(1.0,-1.0)';
    'DDR4_MA'<8>:
      PIN_NUMBER='(0,0,0,0,0,0,DJ60,0,0,0,0,0,0,0,0,0,0,0,0,0,0,0,0,0,0,0,0,0,0,0)';
      OUTPUT_LOAD='(1.0,-1.0)';
    'DDR4_MA'<7>:
      PIN_NUMBER='(0,0,0,0,0,0,DK61,0,0,0,0,0,0,0,0,0,0,0,0,0,0,0,0,0,0,0,0,0,0,0)';
      OUTPUT_LOAD='(1.0,-1.0)';
    'DDR4_MA'<6>:
      PIN_NUMBER='(0,0,0,0,0,0,DM59,0,0,0,0,0,0,0,0,0,0,0,0,0,0,0,0,0,0,0,0,0,0,0)';
      OUTPUT_LOAD='(1.0,-1.0)';
    'DDR4_MA'<5>:
      PIN_NUMBER='(0,0,0,0,0,0,DN58,0,0,0,0,0,0,0,0,0,0,0,0,0,0,0,0,0,0,0,0,0,0,0)';
      OUTPUT_LOAD='(1.0,-1.0)';
    'DDR4_MA'<4>:
      PIN_NUMBER='(0,0,0,0,0,0,DT59,0,0,0,0,0,0,0,0,0,0,0,0,0,0,0,0,0,0,0,0,0,0,0)';
      OUTPUT_LOAD='(1.0,-1.0)';
    'DDR4_MA'<3>:
      PIN_NUMBER='(0,0,0,0,0,0,DR58,0,0,0,0,0,0,0,0,0,0,0,0,0,0,0,0,0,0,0,0,0,0,0)';
      OUTPUT_LOAD='(1.0,-1.0)';
    'DDR4_MA'<2>:
      PIN_NUMBER='(0,0,0,0,0,0,DV57,0,0,0,0,0,0,0,0,0,0,0,0,0,0,0,0,0,0,0,0,0,0,0)';
      OUTPUT_LOAD='(1.0,-1.0)';
    'DDR4_MA'<1>:
      PIN_NUMBER='(0,0,0,0,0,0,DW58,0,0,0,0,0,0,0,0,0,0,0,0,0,0,0,0,0,0,0,0,0,0,0)';
      OUTPUT_LOAD='(1.0,-1.0)';
    'DDR4_MA'<0>:
      PIN_NUMBER='(0,0,0,0,0,0,DW52,0,0,0,0,0,0,0,0,0,0,0,0,0,0,0,0,0,0,0,0,0,0,0)';
      OUTPUT_LOAD='(1.0,-1.0)';
    'DDR4_ODT'<3>:
      PIN_NUMBER='(0,0,0,0,0,0,DM47,0,0,0,0,0,0,0,0,0,0,0,0,0,0,0,0,0,0,0,0,0,0,0)';
      OUTPUT_LOAD='(1.0,-1.0)';
    'DDR4_ODT'<2>:
      PIN_NUMBER='(0,0,0,0,0,0,DT49,0,0,0,0,0,0,0,0,0,0,0,0,0,0,0,0,0,0,0,0,0,0,0)';
      OUTPUT_LOAD='(1.0,-1.0)';
    'DDR4_ODT'<1>:
      PIN_NUMBER='(0,0,0,0,0,0,DN48,0,0,0,0,0,0,0,0,0,0,0,0,0,0,0,0,0,0,0,0,0,0,0)';
      OUTPUT_LOAD='(1.0,-1.0)';
    'DDR4_ODT'<0>:
      PIN_NUMBER='(0,0,0,0,0,0,DR50,0,0,0,0,0,0,0,0,0,0,0,0,0,0,0,0,0,0,0,0,0,0,0)';
      OUTPUT_LOAD='(1.0,-1.0)';
    'DDR4_PAR':
      PIN_NUMBER='(0,0,0,0,0,0,DV53,0,0,0,0,0,0,0,0,0,0,0,0,0,0,0,0,0,0,0,0,0,0,0)';
      OUTPUT_LOAD='(1.0,-1.0)';
    'DDR5_ACT_N':
      PIN_NUMBER='(0,0,0,0,0,0,0,DC62,0,0,0,0,0,0,0,0,0,0,0,0,0,0,0,0,0,0,0,0,0,0)';
      OUTPUT_LOAD='(1.0,-1.0)';
    'DDR5_ALERT_N':
      PIN_NUMBER='(0,0,0,0,0,0,0,DD61,0,0,0,0,0,0,0,0,0,0,0,0,0,0,0,0,0,0,0,0,0,0)';
      INPUT_LOAD='(-0.01,0.01)';
    'DDR5_BA'<1>:
      PIN_NUMBER='(0,0,0,0,0,0,0,DC56,0,0,0,0,0,0,0,0,0,0,0,0,0,0,0,0,0,0,0,0,0,0)';
      OUTPUT_LOAD='(1.0,-1.0)';
    'DDR5_BA'<0>:
      PIN_NUMBER='(0,0,0,0,0,0,0,DJ52,0,0,0,0,0,0,0,0,0,0,0,0,0,0,0,0,0,0,0,0,0,0)';
      OUTPUT_LOAD='(1.0,-1.0)';
    'DDR5_BG'<1>:
      PIN_NUMBER='(0,0,0,0,0,0,0,DF61,0,0,0,0,0,0,0,0,0,0,0,0,0,0,0,0,0,0,0,0,0,0)';
      OUTPUT_LOAD='(1.0,-1.0)';
    'DDR5_BG'<0>:
      PIN_NUMBER='(0,0,0,0,0,0,0,DA62,0,0,0,0,0,0,0,0,0,0,0,0,0,0,0,0,0,0,0,0,0,0)';
      OUTPUT_LOAD='(1.0,-1.0)';
    'DDR5_CAVREF':
      PIN_NUMBER='(CV61,0,0,0,0,0,0,0,0,0,0,0,0,0,0,0,0,0,0,0,0,0,0,0,0,0,0,0,0,0)';
      OUTPUT_LOAD='(1.0,-1.0)';
    'DDR5_CID'<2>:
      PIN_NUMBER='(0,0,0,0,0,0,0,DF45,0,0,0,0,0,0,0,0,0,0,0,0,0,0,0,0,0,0,0,0,0,0)';
      OUTPUT_LOAD='(1.0,-1.0)';
    'DDR5_CKE'<3>:
      PIN_NUMBER='(0,0,0,0,0,0,0,DF63,0,0,0,0,0,0,0,0,0,0,0,0,0,0,0,0,0,0,0,0,0,0)';
      OUTPUT_LOAD='(1.0,-1.0)';
    'DDR5_CKE'<2>:
      PIN_NUMBER='(0,0,0,0,0,0,0,DK63,0,0,0,0,0,0,0,0,0,0,0,0,0,0,0,0,0,0,0,0,0,0)';
      OUTPUT_LOAD='(1.0,-1.0)';
    'DDR5_CKE'<1>:
      PIN_NUMBER='(0,0,0,0,0,0,0,DD63,0,0,0,0,0,0,0,0,0,0,0,0,0,0,0,0,0,0,0,0,0,0)';
      OUTPUT_LOAD='(1.0,-1.0)';
    'DDR5_CKE'<0>:
      PIN_NUMBER='(0,0,0,0,0,0,0,DG62,0,0,0,0,0,0,0,0,0,0,0,0,0,0,0,0,0,0,0,0,0,0)';
      OUTPUT_LOAD='(1.0,-1.0)';
    'DDR5_CLK_DN'<3>:
      PIN_NUMBER='(0,0,0,0,0,0,0,DF57,0,0,0,0,0,0,0,0,0,0,0,0,0,0,0,0,0,0,0,0,0,0)';
      OUTPUT_LOAD='(1.0,-1.0)';
    'DDR5_CLK_DN'<2>:
      PIN_NUMBER='(0,0,0,0,0,0,0,DK57,0,0,0,0,0,0,0,0,0,0,0,0,0,0,0,0,0,0,0,0,0,0)';
      OUTPUT_LOAD='(1.0,-1.0)';
    'DDR5_CLK_DN'<1>:
      PIN_NUMBER='(0,0,0,0,0,0,0,DF55,0,0,0,0,0,0,0,0,0,0,0,0,0,0,0,0,0,0,0,0,0,0)';
      OUTPUT_LOAD='(1.0,-1.0)';
    'DDR5_CLK_DN'<0>:
      PIN_NUMBER='(0,0,0,0,0,0,0,DK55,0,0,0,0,0,0,0,0,0,0,0,0,0,0,0,0,0,0,0,0,0,0)';
      OUTPUT_LOAD='(1.0,-1.0)';
    'DDR5_CLK_DP'<3>:
      PIN_NUMBER='(0,0,0,0,0,0,0,DG56,0,0,0,0,0,0,0,0,0,0,0,0,0,0,0,0,0,0,0,0,0,0)';
      OUTPUT_LOAD='(1.0,-1.0)';
    'DDR5_CLK_DP'<2>:
      PIN_NUMBER='(0,0,0,0,0,0,0,DJ56,0,0,0,0,0,0,0,0,0,0,0,0,0,0,0,0,0,0,0,0,0,0)';
      OUTPUT_LOAD='(1.0,-1.0)';
    'DDR5_CLK_DP'<1>:
      PIN_NUMBER='(0,0,0,0,0,0,0,DG54,0,0,0,0,0,0,0,0,0,0,0,0,0,0,0,0,0,0,0,0,0,0)';
      OUTPUT_LOAD='(1.0,-1.0)';
    'DDR5_CLK_DP'<0>:
      PIN_NUMBER='(0,0,0,0,0,0,0,DJ54,0,0,0,0,0,0,0,0,0,0,0,0,0,0,0,0,0,0,0,0,0,0)';
      OUTPUT_LOAD='(1.0,-1.0)';
    'DDR5_CS_N'<7>:
      PIN_NUMBER='(0,0,0,0,0,0,0,DK45,0,0,0,0,0,0,0,0,0,0,0,0,0,0,0,0,0,0,0,0,0,0)';
      OUTPUT_LOAD='(1.0,-1.0)';
    'DDR5_CS_N'<6>:
      PIN_NUMBER='(0,0,0,0,0,0,0,DM45,0,0,0,0,0,0,0,0,0,0,0,0,0,0,0,0,0,0,0,0,0,0)';
      OUTPUT_LOAD='(1.0,-1.0)';
    'DDR5_CS_N'<5>:
      PIN_NUMBER='(0,0,0,0,0,0,0,DJ48,0,0,0,0,0,0,0,0,0,0,0,0,0,0,0,0,0,0,0,0,0,0)';
      OUTPUT_LOAD='(1.0,-1.0)';
    'DDR5_CS_N'<4>:
      PIN_NUMBER='(0,0,0,0,0,0,0,DF51,0,0,0,0,0,0,0,0,0,0,0,0,0,0,0,0,0,0,0,0,0,0)';
      OUTPUT_LOAD='(1.0,-1.0)';
    'DDR5_CS_N'<3>:
      PIN_NUMBER='(0,0,0,0,0,0,0,DG46,0,0,0,0,0,0,0,0,0,0,0,0,0,0,0,0,0,0,0,0,0,0)';
      OUTPUT_LOAD='(1.0,-1.0)';
    'DDR5_CS_N'<2>:
      PIN_NUMBER='(0,0,0,0,0,0,0,DJ46,0,0,0,0,0,0,0,0,0,0,0,0,0,0,0,0,0,0,0,0,0,0)';
      OUTPUT_LOAD='(1.0,-1.0)';
    'DDR5_CS_N'<1>:
      PIN_NUMBER='(0,0,0,0,0,0,0,DF49,0,0,0,0,0,0,0,0,0,0,0,0,0,0,0,0,0,0,0,0,0,0)';
      OUTPUT_LOAD='(1.0,-1.0)';
    'DDR5_CS_N'<0>:
      PIN_NUMBER='(0,0,0,0,0,0,0,DK51,0,0,0,0,0,0,0,0,0,0,0,0,0,0,0,0,0,0,0,0,0,0)';
      OUTPUT_LOAD='(1.0,-1.0)';
    'DDR5_DQ'<63>:
      PIN_NUMBER='(0,0,0,0,0,0,0,DC28,0,0,0,0,0,0,0,0,0,0,0,0,0,0,0,0,0,0,0,0,0,0)';
      BIDIRECTIONAL='TRUE';
      INPUT_LOAD='(-0.01,0.01)';
      OUTPUT_LOAD='(1.0,-1.0)';
    'DDR5_DQ'<62>:
      PIN_NUMBER='(0,0,0,0,0,0,0,CW28,0,0,0,0,0,0,0,0,0,0,0,0,0,0,0,0,0,0,0,0,0,0)';
      BIDIRECTIONAL='TRUE';
      INPUT_LOAD='(-0.01,0.01)';
      OUTPUT_LOAD='(1.0,-1.0)';
    'DDR5_DQ'<61>:
      PIN_NUMBER='(0,0,0,0,0,0,0,DB31,0,0,0,0,0,0,0,0,0,0,0,0,0,0,0,0,0,0,0,0,0,0)';
      BIDIRECTIONAL='TRUE';
      INPUT_LOAD='(-0.01,0.01)';
      OUTPUT_LOAD='(1.0,-1.0)';
    'DDR5_DQ'<60>:
      PIN_NUMBER='(0,0,0,0,0,0,0,CY31,0,0,0,0,0,0,0,0,0,0,0,0,0,0,0,0,0,0,0,0,0,0)';
      BIDIRECTIONAL='TRUE';
      INPUT_LOAD='(-0.01,0.01)';
      OUTPUT_LOAD='(1.0,-1.0)';
    'DDR5_DQ'<59>:
      PIN_NUMBER='(0,0,0,0,0,0,0,DB27,0,0,0,0,0,0,0,0,0,0,0,0,0,0,0,0,0,0,0,0,0,0)';
      BIDIRECTIONAL='TRUE';
      INPUT_LOAD='(-0.01,0.01)';
      OUTPUT_LOAD='(1.0,-1.0)';
    'DDR5_DQ'<58>:
      PIN_NUMBER='(0,0,0,0,0,0,0,CY27,0,0,0,0,0,0,0,0,0,0,0,0,0,0,0,0,0,0,0,0,0,0)';
      BIDIRECTIONAL='TRUE';
      INPUT_LOAD='(-0.01,0.01)';
      OUTPUT_LOAD='(1.0,-1.0)';
    'DDR5_DQ'<57>:
      PIN_NUMBER='(0,0,0,0,0,0,0,DC30,0,0,0,0,0,0,0,0,0,0,0,0,0,0,0,0,0,0,0,0,0,0)';
      BIDIRECTIONAL='TRUE';
      INPUT_LOAD='(-0.01,0.01)';
      OUTPUT_LOAD='(1.0,-1.0)';
    'DDR5_DQ'<56>:
      PIN_NUMBER='(0,0,0,0,0,0,0,CW30,0,0,0,0,0,0,0,0,0,0,0,0,0,0,0,0,0,0,0,0,0,0)';
      BIDIRECTIONAL='TRUE';
      INPUT_LOAD='(-0.01,0.01)';
      OUTPUT_LOAD='(1.0,-1.0)';
    'DDR5_DQ'<55>:
      PIN_NUMBER='(0,0,0,0,0,0,0,DC34,0,0,0,0,0,0,0,0,0,0,0,0,0,0,0,0,0,0,0,0,0,0)';
      BIDIRECTIONAL='TRUE';
      INPUT_LOAD='(-0.01,0.01)';
      OUTPUT_LOAD='(1.0,-1.0)';
    'DDR5_DQ'<54>:
      PIN_NUMBER='(0,0,0,0,0,0,0,CW34,0,0,0,0,0,0,0,0,0,0,0,0,0,0,0,0,0,0,0,0,0,0)';
      BIDIRECTIONAL='TRUE';
      INPUT_LOAD='(-0.01,0.01)';
      OUTPUT_LOAD='(1.0,-1.0)';
    'DDR5_DQ'<53>:
      PIN_NUMBER='(0,0,0,0,0,0,0,DB37,0,0,0,0,0,0,0,0,0,0,0,0,0,0,0,0,0,0,0,0,0,0)';
      BIDIRECTIONAL='TRUE';
      INPUT_LOAD='(-0.01,0.01)';
      OUTPUT_LOAD='(1.0,-1.0)';
    'DDR5_DQ'<52>:
      PIN_NUMBER='(0,0,0,0,0,0,0,CY37,0,0,0,0,0,0,0,0,0,0,0,0,0,0,0,0,0,0,0,0,0,0)';
      BIDIRECTIONAL='TRUE';
      INPUT_LOAD='(-0.01,0.01)';
      OUTPUT_LOAD='(1.0,-1.0)';
    'DDR5_DQ'<51>:
      PIN_NUMBER='(0,0,0,0,0,0,0,DB33,0,0,0,0,0,0,0,0,0,0,0,0,0,0,0,0,0,0,0,0,0,0)';
      BIDIRECTIONAL='TRUE';
      INPUT_LOAD='(-0.01,0.01)';
      OUTPUT_LOAD='(1.0,-1.0)';
    'DDR5_DQ'<50>:
      PIN_NUMBER='(0,0,0,0,0,0,0,CY33,0,0,0,0,0,0,0,0,0,0,0,0,0,0,0,0,0,0,0,0,0,0)';
      BIDIRECTIONAL='TRUE';
      INPUT_LOAD='(-0.01,0.01)';
      OUTPUT_LOAD='(1.0,-1.0)';
    'DDR5_DQ'<49>:
      PIN_NUMBER='(0,0,0,0,0,0,0,DC36,0,0,0,0,0,0,0,0,0,0,0,0,0,0,0,0,0,0,0,0,0,0)';
      BIDIRECTIONAL='TRUE';
      INPUT_LOAD='(-0.01,0.01)';
      OUTPUT_LOAD='(1.0,-1.0)';
    'DDR5_DQ'<48>:
      PIN_NUMBER='(0,0,0,0,0,0,0,CW36,0,0,0,0,0,0,0,0,0,0,0,0,0,0,0,0,0,0,0,0,0,0)';
      BIDIRECTIONAL='TRUE';
      INPUT_LOAD='(-0.01,0.01)';
      OUTPUT_LOAD='(1.0,-1.0)';
    'DDR5_DQ'<47>:
      PIN_NUMBER='(0,0,0,0,0,0,0,DK31,0,0,0,0,0,0,0,0,0,0,0,0,0,0,0,0,0,0,0,0,0,0)';
      BIDIRECTIONAL='TRUE';
      INPUT_LOAD='(-0.01,0.01)';
      OUTPUT_LOAD='(1.0,-1.0)';
    'DDR5_DQ'<46>:
      PIN_NUMBER='(0,0,0,0,0,0,0,DF31,0,0,0,0,0,0,0,0,0,0,0,0,0,0,0,0,0,0,0,0,0,0)';
      BIDIRECTIONAL='TRUE';
      INPUT_LOAD='(-0.01,0.01)';
      OUTPUT_LOAD='(1.0,-1.0)';
    'DDR5_DQ'<45>:
      PIN_NUMBER='(0,0,0,0,0,0,0,DJ34,0,0,0,0,0,0,0,0,0,0,0,0,0,0,0,0,0,0,0,0,0,0)';
      BIDIRECTIONAL='TRUE';
      INPUT_LOAD='(-0.01,0.01)';
      OUTPUT_LOAD='(1.0,-1.0)';
    'DDR5_DQ'<44>:
      PIN_NUMBER='(0,0,0,0,0,0,0,DG34,0,0,0,0,0,0,0,0,0,0,0,0,0,0,0,0,0,0,0,0,0,0)';
      BIDIRECTIONAL='TRUE';
      INPUT_LOAD='(-0.01,0.01)';
      OUTPUT_LOAD='(1.0,-1.0)';
    'DDR5_DQ'<43>:
      PIN_NUMBER='(0,0,0,0,0,0,0,DJ30,0,0,0,0,0,0,0,0,0,0,0,0,0,0,0,0,0,0,0,0,0,0)';
      BIDIRECTIONAL='TRUE';
      INPUT_LOAD='(-0.01,0.01)';
      OUTPUT_LOAD='(1.0,-1.0)';
    'DDR5_DQ'<42>:
      PIN_NUMBER='(0,0,0,0,0,0,0,DG30,0,0,0,0,0,0,0,0,0,0,0,0,0,0,0,0,0,0,0,0,0,0)';
      BIDIRECTIONAL='TRUE';
      INPUT_LOAD='(-0.01,0.01)';
      OUTPUT_LOAD='(1.0,-1.0)';
    'DDR5_DQ'<41>:
      PIN_NUMBER='(0,0,0,0,0,0,0,DK33,0,0,0,0,0,0,0,0,0,0,0,0,0,0,0,0,0,0,0,0,0,0)';
      BIDIRECTIONAL='TRUE';
      INPUT_LOAD='(-0.01,0.01)';
      OUTPUT_LOAD='(1.0,-1.0)';
    'DDR5_DQ'<40>:
      PIN_NUMBER='(0,0,0,0,0,0,0,DF33,0,0,0,0,0,0,0,0,0,0,0,0,0,0,0,0,0,0,0,0,0,0)';
      BIDIRECTIONAL='TRUE';
      INPUT_LOAD='(-0.01,0.01)';
      OUTPUT_LOAD='(1.0,-1.0)';
    'DDR5_DQ'<39>:
      PIN_NUMBER='(0,0,0,0,0,0,0,DH39,0,0,0,0,0,0,0,0,0,0,0,0,0,0,0,0,0,0,0,0,0,0)';
      BIDIRECTIONAL='TRUE';
      INPUT_LOAD='(-0.01,0.01)';
      OUTPUT_LOAD='(1.0,-1.0)';
    'DDR5_DQ'<38>:
      PIN_NUMBER='(0,0,0,0,0,0,0,DD39,0,0,0,0,0,0,0,0,0,0,0,0,0,0,0,0,0,0,0,0,0,0)';
      BIDIRECTIONAL='TRUE';
      INPUT_LOAD='(-0.01,0.01)';
      OUTPUT_LOAD='(1.0,-1.0)';
    'DDR5_DQ'<37>:
      PIN_NUMBER='(0,0,0,0,0,0,0,DE42,0,0,0,0,0,0,0,0,0,0,0,0,0,0,0,0,0,0,0,0,0,0)';
      BIDIRECTIONAL='TRUE';
      INPUT_LOAD='(-0.01,0.01)';
      OUTPUT_LOAD='(1.0,-1.0)';
    'DDR5_DQ'<36>:
      PIN_NUMBER='(0,0,0,0,0,0,0,DA42,0,0,0,0,0,0,0,0,0,0,0,0,0,0,0,0,0,0,0,0,0,0)';
      BIDIRECTIONAL='TRUE';
      INPUT_LOAD='(-0.01,0.01)';
      OUTPUT_LOAD='(1.0,-1.0)';
    'DDR5_DQ'<35>:
      PIN_NUMBER='(0,0,0,0,0,0,0,DG38,0,0,0,0,0,0,0,0,0,0,0,0,0,0,0,0,0,0,0,0,0,0)';
      BIDIRECTIONAL='TRUE';
      INPUT_LOAD='(-0.01,0.01)';
      OUTPUT_LOAD='(1.0,-1.0)';
    'DDR5_DQ'<34>:
      PIN_NUMBER='(0,0,0,0,0,0,0,DE38,0,0,0,0,0,0,0,0,0,0,0,0,0,0,0,0,0,0,0,0,0,0)';
      BIDIRECTIONAL='TRUE';
      INPUT_LOAD='(-0.01,0.01)';
      OUTPUT_LOAD='(1.0,-1.0)';
    'DDR5_DQ'<33>:
      PIN_NUMBER='(0,0,0,0,0,0,0,DG42,0,0,0,0,0,0,0,0,0,0,0,0,0,0,0,0,0,0,0,0,0,0)';
      BIDIRECTIONAL='TRUE';
      INPUT_LOAD='(-0.01,0.01)';
      OUTPUT_LOAD='(1.0,-1.0)';
    'DDR5_DQ'<32>:
      PIN_NUMBER='(0,0,0,0,0,0,0,DD41,0,0,0,0,0,0,0,0,0,0,0,0,0,0,0,0,0,0,0,0,0,0)';
      BIDIRECTIONAL='TRUE';
      INPUT_LOAD='(-0.01,0.01)';
      OUTPUT_LOAD='(1.0,-1.0)';
    'DDR5_DQ'<31>:
      PIN_NUMBER='(0,0,0,0,0,0,0,CU64,0,0,0,0,0,0,0,0,0,0,0,0,0,0,0,0,0,0,0,0,0,0)';
      BIDIRECTIONAL='TRUE';
      INPUT_LOAD='(-0.01,0.01)';
      OUTPUT_LOAD='(1.0,-1.0)';
    'DDR5_DQ'<30>:
      PIN_NUMBER='(0,0,0,0,0,0,0,CN64,0,0,0,0,0,0,0,0,0,0,0,0,0,0,0,0,0,0,0,0,0,0)';
      BIDIRECTIONAL='TRUE';
      INPUT_LOAD='(-0.01,0.01)';
      OUTPUT_LOAD='(1.0,-1.0)';
    'DDR5_DQ'<29>:
      PIN_NUMBER='(0,0,0,0,0,0,0,CT67,0,0,0,0,0,0,0,0,0,0,0,0,0,0,0,0,0,0,0,0,0,0)';
      BIDIRECTIONAL='TRUE';
      INPUT_LOAD='(-0.01,0.01)';
      OUTPUT_LOAD='(1.0,-1.0)';
    'DDR5_DQ'<28>:
      PIN_NUMBER='(0,0,0,0,0,0,0,CP67,0,0,0,0,0,0,0,0,0,0,0,0,0,0,0,0,0,0,0,0,0,0)';
      BIDIRECTIONAL='TRUE';
      INPUT_LOAD='(-0.01,0.01)';
      OUTPUT_LOAD='(1.0,-1.0)';
    'DDR5_DQ'<27>:
      PIN_NUMBER='(0,0,0,0,0,0,0,CT63,0,0,0,0,0,0,0,0,0,0,0,0,0,0,0,0,0,0,0,0,0,0)';
      BIDIRECTIONAL='TRUE';
      INPUT_LOAD='(-0.01,0.01)';
      OUTPUT_LOAD='(1.0,-1.0)';
    'DDR5_DQ'<26>:
      PIN_NUMBER='(0,0,0,0,0,0,0,CP63,0,0,0,0,0,0,0,0,0,0,0,0,0,0,0,0,0,0,0,0,0,0)';
      BIDIRECTIONAL='TRUE';
      INPUT_LOAD='(-0.01,0.01)';
      OUTPUT_LOAD='(1.0,-1.0)';
    'DDR5_DQ'<25>:
      PIN_NUMBER='(0,0,0,0,0,0,0,CU66,0,0,0,0,0,0,0,0,0,0,0,0,0,0,0,0,0,0,0,0,0,0)';
      BIDIRECTIONAL='TRUE';
      INPUT_LOAD='(-0.01,0.01)';
      OUTPUT_LOAD='(1.0,-1.0)';
    'DDR5_DQ'<24>:
      PIN_NUMBER='(0,0,0,0,0,0,0,CN66,0,0,0,0,0,0,0,0,0,0,0,0,0,0,0,0,0,0,0,0,0,0)';
      BIDIRECTIONAL='TRUE';
      INPUT_LOAD='(-0.01,0.01)';
      OUTPUT_LOAD='(1.0,-1.0)';
    'DDR5_DQ'<23>:
      PIN_NUMBER='(0,0,0,0,0,0,0,DM71,0,0,0,0,0,0,0,0,0,0,0,0,0,0,0,0,0,0,0,0,0,0)';
      BIDIRECTIONAL='TRUE';
      INPUT_LOAD='(-0.01,0.01)';
      OUTPUT_LOAD='(1.0,-1.0)';
    'DDR5_DQ'<22>:
      PIN_NUMBER='(0,0,0,0,0,0,0,DK69,0,0,0,0,0,0,0,0,0,0,0,0,0,0,0,0,0,0,0,0,0,0)';
      BIDIRECTIONAL='TRUE';
      INPUT_LOAD='(-0.01,0.01)';
      OUTPUT_LOAD='(1.0,-1.0)';
    'DDR5_DQ'<21>:
      PIN_NUMBER='(0,0,0,0,0,0,0,DG72,0,0,0,0,0,0,0,0,0,0,0,0,0,0,0,0,0,0,0,0,0,0)';
      BIDIRECTIONAL='TRUE';
      INPUT_LOAD='(-0.01,0.01)';
      OUTPUT_LOAD='(1.0,-1.0)';
    'DDR5_DQ'<20>:
      PIN_NUMBER='(0,0,0,0,0,0,0,DF71,0,0,0,0,0,0,0,0,0,0,0,0,0,0,0,0,0,0,0,0,0,0)';
      BIDIRECTIONAL='TRUE';
      INPUT_LOAD='(-0.01,0.01)';
      OUTPUT_LOAD='(1.0,-1.0)';
    'DDR5_DQ'<19>:
      PIN_NUMBER='(0,0,0,0,0,0,0,DN70,0,0,0,0,0,0,0,0,0,0,0,0,0,0,0,0,0,0,0,0,0,0)';
      BIDIRECTIONAL='TRUE';
      INPUT_LOAD='(-0.01,0.01)';
      OUTPUT_LOAD='(1.0,-1.0)';
    'DDR5_DQ'<18>:
      PIN_NUMBER='(0,0,0,0,0,0,0,DM69,0,0,0,0,0,0,0,0,0,0,0,0,0,0,0,0,0,0,0,0,0,0)';
      BIDIRECTIONAL='TRUE';
      INPUT_LOAD='(-0.01,0.01)';
      OUTPUT_LOAD='(1.0,-1.0)';
    'DDR5_DQ'<17>:
      PIN_NUMBER='(0,0,0,0,0,0,0,DJ72,0,0,0,0,0,0,0,0,0,0,0,0,0,0,0,0,0,0,0,0,0,0)';
      BIDIRECTIONAL='TRUE';
      INPUT_LOAD='(-0.01,0.01)';
      OUTPUT_LOAD='(1.0,-1.0)';
    'DDR5_DQ'<16>:
      PIN_NUMBER='(0,0,0,0,0,0,0,DG70,0,0,0,0,0,0,0,0,0,0,0,0,0,0,0,0,0,0,0,0,0,0)';
      BIDIRECTIONAL='TRUE';
      INPUT_LOAD='(-0.01,0.01)';
      OUTPUT_LOAD='(1.0,-1.0)';
    'DDR5_DQ'<15>:
      PIN_NUMBER='(0,0,0,0,0,0,0,DH77,0,0,0,0,0,0,0,0,0,0,0,0,0,0,0,0,0,0,0,0,0,0)';
      BIDIRECTIONAL='TRUE';
      INPUT_LOAD='(-0.01,0.01)';
      OUTPUT_LOAD='(1.0,-1.0)';
    'DDR5_DQ'<14>:
      PIN_NUMBER='(0,0,0,0,0,0,0,DF77,0,0,0,0,0,0,0,0,0,0,0,0,0,0,0,0,0,0,0,0,0,0)';
      BIDIRECTIONAL='TRUE';
      INPUT_LOAD='(-0.01,0.01)';
      OUTPUT_LOAD='(1.0,-1.0)';
    'DDR5_DQ'<13>:
      PIN_NUMBER='(0,0,0,0,0,0,0,DB75,0,0,0,0,0,0,0,0,0,0,0,0,0,0,0,0,0,0,0,0,0,0)';
      BIDIRECTIONAL='TRUE';
      INPUT_LOAD='(-0.01,0.01)';
      OUTPUT_LOAD='(1.0,-1.0)';
    'DDR5_DQ'<12>:
      PIN_NUMBER='(0,0,0,0,0,0,0,DC74,0,0,0,0,0,0,0,0,0,0,0,0,0,0,0,0,0,0,0,0,0,0)';
      BIDIRECTIONAL='TRUE';
      INPUT_LOAD='(-0.01,0.01)';
      OUTPUT_LOAD='(1.0,-1.0)';
    'DDR5_DQ'<11>:
      PIN_NUMBER='(0,0,0,0,0,0,0,DJ76,0,0,0,0,0,0,0,0,0,0,0,0,0,0,0,0,0,0,0,0,0,0)';
      BIDIRECTIONAL='TRUE';
      INPUT_LOAD='(-0.01,0.01)';
      OUTPUT_LOAD='(1.0,-1.0)';
    'DDR5_DQ'<10>:
      PIN_NUMBER='(0,0,0,0,0,0,0,DH75,0,0,0,0,0,0,0,0,0,0,0,0,0,0,0,0,0,0,0,0,0,0)';
      BIDIRECTIONAL='TRUE';
      INPUT_LOAD='(-0.01,0.01)';
      OUTPUT_LOAD='(1.0,-1.0)';
    'DDR5_DQ'<9>:
      PIN_NUMBER='(0,0,0,0,0,0,0,DC76,0,0,0,0,0,0,0,0,0,0,0,0,0,0,0,0,0,0,0,0,0,0)';
      BIDIRECTIONAL='TRUE';
      INPUT_LOAD='(-0.01,0.01)';
      OUTPUT_LOAD='(1.0,-1.0)';
    'DDR5_DQ'<8>:
      PIN_NUMBER='(0,0,0,0,0,0,0,DE74,0,0,0,0,0,0,0,0,0,0,0,0,0,0,0,0,0,0,0,0,0,0)';
      BIDIRECTIONAL='TRUE';
      INPUT_LOAD='(-0.01,0.01)';
      OUTPUT_LOAD='(1.0,-1.0)';
    'DDR5_DQ'<7>:
      PIN_NUMBER='(0,0,0,0,0,0,0,CT77,0,0,0,0,0,0,0,0,0,0,0,0,0,0,0,0,0,0,0,0,0,0)';
      BIDIRECTIONAL='TRUE';
      INPUT_LOAD='(-0.01,0.01)';
      OUTPUT_LOAD='(1.0,-1.0)';
    'DDR5_DQ'<6>:
      PIN_NUMBER='(0,0,0,0,0,0,0,CV75,0,0,0,0,0,0,0,0,0,0,0,0,0,0,0,0,0,0,0,0,0,0)';
      BIDIRECTIONAL='TRUE';
      INPUT_LOAD='(-0.01,0.01)';
      OUTPUT_LOAD='(1.0,-1.0)';
    'DDR5_DQ'<5>:
      PIN_NUMBER='(0,0,0,0,0,0,0,CM75,0,0,0,0,0,0,0,0,0,0,0,0,0,0,0,0,0,0,0,0,0,0)';
      BIDIRECTIONAL='TRUE';
      INPUT_LOAD='(-0.01,0.01)';
      OUTPUT_LOAD='(1.0,-1.0)';
    'DDR5_DQ'<4>:
      PIN_NUMBER='(0,0,0,0,0,0,0,CN74,0,0,0,0,0,0,0,0,0,0,0,0,0,0,0,0,0,0,0,0,0,0)';
      BIDIRECTIONAL='TRUE';
      INPUT_LOAD='(-0.01,0.01)';
      OUTPUT_LOAD='(1.0,-1.0)';
    'DDR5_DQ'<3>:
      PIN_NUMBER='(0,0,0,0,0,0,0,CV77,0,0,0,0,0,0,0,0,0,0,0,0,0,0,0,0,0,0,0,0,0,0)';
      BIDIRECTIONAL='TRUE';
      INPUT_LOAD='(-0.01,0.01)';
      OUTPUT_LOAD='(1.0,-1.0)';
    'DDR5_DQ'<2>:
      PIN_NUMBER='(0,0,0,0,0,0,0,CW76,0,0,0,0,0,0,0,0,0,0,0,0,0,0,0,0,0,0,0,0,0,0)';
      BIDIRECTIONAL='TRUE';
      INPUT_LOAD='(-0.01,0.01)';
      OUTPUT_LOAD='(1.0,-1.0)';
    'DDR5_DQ'<1>:
      PIN_NUMBER='(0,0,0,0,0,0,0,CN76,0,0,0,0,0,0,0,0,0,0,0,0,0,0,0,0,0,0,0,0,0,0)';
      BIDIRECTIONAL='TRUE';
      INPUT_LOAD='(-0.01,0.01)';
      OUTPUT_LOAD='(1.0,-1.0)';
    'DDR5_DQ'<0>:
      PIN_NUMBER='(0,0,0,0,0,0,0,CR74,0,0,0,0,0,0,0,0,0,0,0,0,0,0,0,0,0,0,0,0,0,0)';
      BIDIRECTIONAL='TRUE';
      INPUT_LOAD='(-0.01,0.01)';
      OUTPUT_LOAD='(1.0,-1.0)';
    'DDR5_DQS_DN'<17>:
      PIN_NUMBER='(0,0,0,0,0,0,0,CJ70,0,0,0,0,0,0,0,0,0,0,0,0,0,0,0,0,0,0,0,0,0,0)';
      BIDIRECTIONAL='TRUE';
      INPUT_LOAD='(-0.01,0.01)';
      OUTPUT_LOAD='(1.0,-1.0)';
    'DDR5_DQS_DN'<16>:
      PIN_NUMBER='(0,0,0,0,0,0,0,CY29,0,0,0,0,0,0,0,0,0,0,0,0,0,0,0,0,0,0,0,0,0,0)';
      BIDIRECTIONAL='TRUE';
      INPUT_LOAD='(-0.01,0.01)';
      OUTPUT_LOAD='(1.0,-1.0)';
    'DDR5_DQS_DN'<15>:
      PIN_NUMBER='(0,0,0,0,0,0,0,CY35,0,0,0,0,0,0,0,0,0,0,0,0,0,0,0,0,0,0,0,0,0,0)';
      BIDIRECTIONAL='TRUE';
      INPUT_LOAD='(-0.01,0.01)';
      OUTPUT_LOAD='(1.0,-1.0)';
    'DDR5_DQS_DN'<14>:
      PIN_NUMBER='(0,0,0,0,0,0,0,DG32,0,0,0,0,0,0,0,0,0,0,0,0,0,0,0,0,0,0,0,0,0,0)';
      BIDIRECTIONAL='TRUE';
      INPUT_LOAD='(-0.01,0.01)';
      OUTPUT_LOAD='(1.0,-1.0)';
    'DDR5_DQS_DN'<13>:
      PIN_NUMBER='(0,0,0,0,0,0,0,DE40,0,0,0,0,0,0,0,0,0,0,0,0,0,0,0,0,0,0,0,0,0,0)';
      BIDIRECTIONAL='TRUE';
      INPUT_LOAD='(-0.01,0.01)';
      OUTPUT_LOAD='(1.0,-1.0)';
    'DDR5_DQS_DN'<12>:
      PIN_NUMBER='(0,0,0,0,0,0,0,CP65,0,0,0,0,0,0,0,0,0,0,0,0,0,0,0,0,0,0,0,0,0,0)';
      BIDIRECTIONAL='TRUE';
      INPUT_LOAD='(-0.01,0.01)';
      OUTPUT_LOAD='(1.0,-1.0)';
    'DDR5_DQS_DN'<11>:
      PIN_NUMBER='(0,0,0,0,0,0,0,DJ70,0,0,0,0,0,0,0,0,0,0,0,0,0,0,0,0,0,0,0,0,0,0)';
      BIDIRECTIONAL='TRUE';
      INPUT_LOAD='(-0.01,0.01)';
      OUTPUT_LOAD='(1.0,-1.0)';
    'DDR5_DQS_DN'<10>:
      PIN_NUMBER='(0,0,0,0,0,0,0,DF75,0,0,0,0,0,0,0,0,0,0,0,0,0,0,0,0,0,0,0,0,0,0)';
      BIDIRECTIONAL='TRUE';
      INPUT_LOAD='(-0.01,0.01)';
      OUTPUT_LOAD='(1.0,-1.0)';
    'DDR5_DQS_DN'<9>:
      PIN_NUMBER='(0,0,0,0,0,0,0,CT75,0,0,0,0,0,0,0,0,0,0,0,0,0,0,0,0,0,0,0,0,0,0)';
      BIDIRECTIONAL='TRUE';
      INPUT_LOAD='(-0.01,0.01)';
      OUTPUT_LOAD='(1.0,-1.0)';
    'DDR5_DQS_DN'<8>:
      PIN_NUMBER='(0,0,0,0,0,0,0,CN70,0,0,0,0,0,0,0,0,0,0,0,0,0,0,0,0,0,0,0,0,0,0)';
      BIDIRECTIONAL='TRUE';
      INPUT_LOAD='(-0.01,0.01)';
      OUTPUT_LOAD='(1.0,-1.0)';
    'DDR5_DQS_DN'<7>:
      PIN_NUMBER='(0,0,0,0,0,0,0,DD29,0,0,0,0,0,0,0,0,0,0,0,0,0,0,0,0,0,0,0,0,0,0)';
      BIDIRECTIONAL='TRUE';
      INPUT_LOAD='(-0.01,0.01)';
      OUTPUT_LOAD='(1.0,-1.0)';
    'DDR5_DQS_DN'<6>:
      PIN_NUMBER='(0,0,0,0,0,0,0,DD35,0,0,0,0,0,0,0,0,0,0,0,0,0,0,0,0,0,0,0,0,0,0)';
      BIDIRECTIONAL='TRUE';
      INPUT_LOAD='(-0.01,0.01)';
      OUTPUT_LOAD='(1.0,-1.0)';
    'DDR5_DQS_DN'<5>:
      PIN_NUMBER='(0,0,0,0,0,0,0,DL32,0,0,0,0,0,0,0,0,0,0,0,0,0,0,0,0,0,0,0,0,0,0)';
      BIDIRECTIONAL='TRUE';
      INPUT_LOAD='(-0.01,0.01)';
      OUTPUT_LOAD='(1.0,-1.0)';
    'DDR5_DQS_DN'<4>:
      PIN_NUMBER='(0,0,0,0,0,0,0,DG40,0,0,0,0,0,0,0,0,0,0,0,0,0,0,0,0,0,0,0,0,0,0)';
      BIDIRECTIONAL='TRUE';
      INPUT_LOAD='(-0.01,0.01)';
      OUTPUT_LOAD='(1.0,-1.0)';
    'DDR5_DQS_DN'<3>:
      PIN_NUMBER='(0,0,0,0,0,0,0,CV65,0,0,0,0,0,0,0,0,0,0,0,0,0,0,0,0,0,0,0,0,0,0)';
      BIDIRECTIONAL='TRUE';
      INPUT_LOAD='(-0.01,0.01)';
      OUTPUT_LOAD='(1.0,-1.0)';
    'DDR5_DQS_DN'<2>:
      PIN_NUMBER='(0,0,0,0,0,0,0,DL72,0,0,0,0,0,0,0,0,0,0,0,0,0,0,0,0,0,0,0,0,0,0)';
      BIDIRECTIONAL='TRUE';
      INPUT_LOAD='(-0.01,0.01)';
      OUTPUT_LOAD='(1.0,-1.0)';
    'DDR5_DQS_DN'<1>:
      PIN_NUMBER='(0,0,0,0,0,0,0,DD77,0,0,0,0,0,0,0,0,0,0,0,0,0,0,0,0,0,0,0,0,0,0)';
      BIDIRECTIONAL='TRUE';
      INPUT_LOAD='(-0.01,0.01)';
      OUTPUT_LOAD='(1.0,-1.0)';
    'DDR5_DQS_DN'<0>:
      PIN_NUMBER='(0,0,0,0,0,0,0,CP77,0,0,0,0,0,0,0,0,0,0,0,0,0,0,0,0,0,0,0,0,0,0)';
      BIDIRECTIONAL='TRUE';
      INPUT_LOAD='(-0.01,0.01)';
      OUTPUT_LOAD='(1.0,-1.0)';
    'DDR5_DQS_DP'<17>:
      PIN_NUMBER='(0,0,0,0,0,0,0,CG70,0,0,0,0,0,0,0,0,0,0,0,0,0,0,0,0,0,0,0,0,0,0)';
      BIDIRECTIONAL='TRUE';
      INPUT_LOAD='(-0.01,0.01)';
      OUTPUT_LOAD='(1.0,-1.0)';
    'DDR5_DQS_DP'<16>:
      PIN_NUMBER='(0,0,0,0,0,0,0,CV29,0,0,0,0,0,0,0,0,0,0,0,0,0,0,0,0,0,0,0,0,0,0)';
      BIDIRECTIONAL='TRUE';
      INPUT_LOAD='(-0.01,0.01)';
      OUTPUT_LOAD='(1.0,-1.0)';
    'DDR5_DQS_DP'<15>:
      PIN_NUMBER='(0,0,0,0,0,0,0,CV35,0,0,0,0,0,0,0,0,0,0,0,0,0,0,0,0,0,0,0,0,0,0)';
      BIDIRECTIONAL='TRUE';
      INPUT_LOAD='(-0.01,0.01)';
      OUTPUT_LOAD='(1.0,-1.0)';
    'DDR5_DQS_DP'<14>:
      PIN_NUMBER='(0,0,0,0,0,0,0,DE32,0,0,0,0,0,0,0,0,0,0,0,0,0,0,0,0,0,0,0,0,0,0)';
      BIDIRECTIONAL='TRUE';
      INPUT_LOAD='(-0.01,0.01)';
      OUTPUT_LOAD='(1.0,-1.0)';
    'DDR5_DQS_DP'<13>:
      PIN_NUMBER='(0,0,0,0,0,0,0,DC40,0,0,0,0,0,0,0,0,0,0,0,0,0,0,0,0,0,0,0,0,0,0)';
      BIDIRECTIONAL='TRUE';
      INPUT_LOAD='(-0.01,0.01)';
      OUTPUT_LOAD='(1.0,-1.0)';
    'DDR5_DQS_DP'<12>:
      PIN_NUMBER='(0,0,0,0,0,0,0,CM65,0,0,0,0,0,0,0,0,0,0,0,0,0,0,0,0,0,0,0,0,0,0)';
      BIDIRECTIONAL='TRUE';
      INPUT_LOAD='(-0.01,0.01)';
      OUTPUT_LOAD='(1.0,-1.0)';
    'DDR5_DQS_DP'<11>:
      PIN_NUMBER='(0,0,0,0,0,0,0,DH69,0,0,0,0,0,0,0,0,0,0,0,0,0,0,0,0,0,0,0,0,0,0)';
      BIDIRECTIONAL='TRUE';
      INPUT_LOAD='(-0.01,0.01)';
      OUTPUT_LOAD='(1.0,-1.0)';
    'DDR5_DQS_DP'<10>:
      PIN_NUMBER='(0,0,0,0,0,0,0,DG74,0,0,0,0,0,0,0,0,0,0,0,0,0,0,0,0,0,0,0,0,0,0)';
      BIDIRECTIONAL='TRUE';
      INPUT_LOAD='(-0.01,0.01)';
      OUTPUT_LOAD='(1.0,-1.0)';
    'DDR5_DQS_DP'<9>:
      PIN_NUMBER='(0,0,0,0,0,0,0,CU74,0,0,0,0,0,0,0,0,0,0,0,0,0,0,0,0,0,0,0,0,0,0)';
      BIDIRECTIONAL='TRUE';
      INPUT_LOAD='(-0.01,0.01)';
      OUTPUT_LOAD='(1.0,-1.0)';
    'DDR5_DQS_DP'<8>:
      PIN_NUMBER='(0,0,0,0,0,0,0,CL70,0,0,0,0,0,0,0,0,0,0,0,0,0,0,0,0,0,0,0,0,0,0)';
      BIDIRECTIONAL='TRUE';
      INPUT_LOAD='(-0.01,0.01)';
      OUTPUT_LOAD='(1.0,-1.0)';
    'DDR5_DQS_DP'<7>:
      PIN_NUMBER='(0,0,0,0,0,0,0,DB29,0,0,0,0,0,0,0,0,0,0,0,0,0,0,0,0,0,0,0,0,0,0)';
      BIDIRECTIONAL='TRUE';
      INPUT_LOAD='(-0.01,0.01)';
      OUTPUT_LOAD='(1.0,-1.0)';
    'DDR5_DQS_DP'<6>:
      PIN_NUMBER='(0,0,0,0,0,0,0,DB35,0,0,0,0,0,0,0,0,0,0,0,0,0,0,0,0,0,0,0,0,0,0)';
      BIDIRECTIONAL='TRUE';
      INPUT_LOAD='(-0.01,0.01)';
      OUTPUT_LOAD='(1.0,-1.0)';
    'DDR5_DQS_DP'<5>:
      PIN_NUMBER='(0,0,0,0,0,0,0,DJ32,0,0,0,0,0,0,0,0,0,0,0,0,0,0,0,0,0,0,0,0,0,0)';
      BIDIRECTIONAL='TRUE';
      INPUT_LOAD='(-0.01,0.01)';
      OUTPUT_LOAD='(1.0,-1.0)';
    'DDR5_DQS_DP'<4>:
      PIN_NUMBER='(0,0,0,0,0,0,0,DJ40,0,0,0,0,0,0,0,0,0,0,0,0,0,0,0,0,0,0,0,0,0,0)';
      BIDIRECTIONAL='TRUE';
      INPUT_LOAD='(-0.01,0.01)';
      OUTPUT_LOAD='(1.0,-1.0)';
    'DDR5_DQS_DP'<3>:
      PIN_NUMBER='(0,0,0,0,0,0,0,CT65,0,0,0,0,0,0,0,0,0,0,0,0,0,0,0,0,0,0,0,0,0,0)';
      BIDIRECTIONAL='TRUE';
      INPUT_LOAD='(-0.01,0.01)';
      OUTPUT_LOAD='(1.0,-1.0)';
    'DDR5_DQS_DP'<2>:
      PIN_NUMBER='(0,0,0,0,0,0,0,DK71,0,0,0,0,0,0,0,0,0,0,0,0,0,0,0,0,0,0,0,0,0,0)';
      BIDIRECTIONAL='TRUE';
      INPUT_LOAD='(-0.01,0.01)';
      OUTPUT_LOAD='(1.0,-1.0)';
    'DDR5_DQS_DP'<1>:
      PIN_NUMBER='(0,0,0,0,0,0,0,DE76,0,0,0,0,0,0,0,0,0,0,0,0,0,0,0,0,0,0,0,0,0,0)';
      BIDIRECTIONAL='TRUE';
      INPUT_LOAD='(-0.01,0.01)';
      OUTPUT_LOAD='(1.0,-1.0)';
    'DDR5_DQS_DP'<0>:
      PIN_NUMBER='(0,0,0,0,0,0,0,CR76,0,0,0,0,0,0,0,0,0,0,0,0,0,0,0,0,0,0,0,0,0,0)';
      BIDIRECTIONAL='TRUE';
      INPUT_LOAD='(-0.01,0.01)';
      OUTPUT_LOAD='(1.0,-1.0)';
    'DDR5_ECC'<7>:
      PIN_NUMBER='(0,0,0,0,0,0,0,CM69,0,0,0,0,0,0,0,0,0,0,0,0,0,0,0,0,0,0,0,0,0,0)';
      BIDIRECTIONAL='TRUE';
      INPUT_LOAD='(-0.01,0.01)';
      OUTPUT_LOAD='(1.0,-1.0)';
    'DDR5_ECC'<6>:
      PIN_NUMBER='(0,0,0,0,0,0,0,CH69,0,0,0,0,0,0,0,0,0,0,0,0,0,0,0,0,0,0,0,0,0,0)';
      BIDIRECTIONAL='TRUE';
      INPUT_LOAD='(-0.01,0.01)';
      OUTPUT_LOAD='(1.0,-1.0)';
    'DDR5_ECC'<5>:
      PIN_NUMBER='(0,0,0,0,0,0,0,CL72,0,0,0,0,0,0,0,0,0,0,0,0,0,0,0,0,0,0,0,0,0,0)';
      BIDIRECTIONAL='TRUE';
      INPUT_LOAD='(-0.01,0.01)';
      OUTPUT_LOAD='(1.0,-1.0)';
    'DDR5_ECC'<4>:
      PIN_NUMBER='(0,0,0,0,0,0,0,CJ72,0,0,0,0,0,0,0,0,0,0,0,0,0,0,0,0,0,0,0,0,0,0)';
      BIDIRECTIONAL='TRUE';
      INPUT_LOAD='(-0.01,0.01)';
      OUTPUT_LOAD='(1.0,-1.0)';
    'DDR5_ECC'<3>:
      PIN_NUMBER='(0,0,0,0,0,0,0,CL68,0,0,0,0,0,0,0,0,0,0,0,0,0,0,0,0,0,0,0,0,0,0)';
      BIDIRECTIONAL='TRUE';
      INPUT_LOAD='(-0.01,0.01)';
      OUTPUT_LOAD='(1.0,-1.0)';
    'DDR5_ECC'<2>:
      PIN_NUMBER='(0,0,0,0,0,0,0,CJ68,0,0,0,0,0,0,0,0,0,0,0,0,0,0,0,0,0,0,0,0,0,0)';
      BIDIRECTIONAL='TRUE';
      INPUT_LOAD='(-0.01,0.01)';
      OUTPUT_LOAD='(1.0,-1.0)';
    'DDR5_ECC'<1>:
      PIN_NUMBER='(0,0,0,0,0,0,0,CM71,0,0,0,0,0,0,0,0,0,0,0,0,0,0,0,0,0,0,0,0,0,0)';
      BIDIRECTIONAL='TRUE';
      INPUT_LOAD='(-0.01,0.01)';
      OUTPUT_LOAD='(1.0,-1.0)';
    'DDR5_ECC'<0>:
      PIN_NUMBER='(0,0,0,0,0,0,0,CH71,0,0,0,0,0,0,0,0,0,0,0,0,0,0,0,0,0,0,0,0,0,0)';
      BIDIRECTIONAL='TRUE';
      INPUT_LOAD='(-0.01,0.01)';
      OUTPUT_LOAD='(1.0,-1.0)';
    'DDR5_MA'<17>:
      PIN_NUMBER='(0,0,0,0,0,0,0,DE46,0,0,0,0,0,0,0,0,0,0,0,0,0,0,0,0,0,0,0,0,0,0)';
      OUTPUT_LOAD='(1.0,-1.0)';
    'DDR5_MA'<16>:
      PIN_NUMBER='(0,0,0,0,0,0,0,DG52,0,0,0,0,0,0,0,0,0,0,0,0,0,0,0,0,0,0,0,0,0,0)';
      OUTPUT_LOAD='(1.0,-1.0)';
    'DDR5_MA'<15>:
      PIN_NUMBER='(0,0,0,0,0,0,0,DC54,0,0,0,0,0,0,0,0,0,0,0,0,0,0,0,0,0,0,0,0,0,0)';
      OUTPUT_LOAD='(1.0,-1.0)';
    'DDR5_MA'<14>:
      PIN_NUMBER='(0,0,0,0,0,0,0,DJ50,0,0,0,0,0,0,0,0,0,0,0,0,0,0,0,0,0,0,0,0,0,0)';
      OUTPUT_LOAD='(1.0,-1.0)';
    'DDR5_MA'<13>:
      PIN_NUMBER='(0,0,0,0,0,0,0,DD53,0,0,0,0,0,0,0,0,0,0,0,0,0,0,0,0,0,0,0,0,0,0)';
      OUTPUT_LOAD='(1.0,-1.0)';
    'DDR5_MA'<12>:
      PIN_NUMBER='(0,0,0,0,0,0,0,DG60,0,0,0,0,0,0,0,0,0,0,0,0,0,0,0,0,0,0,0,0,0,0)';
      OUTPUT_LOAD='(1.0,-1.0)';
    'DDR5_MA'<11>:
      PIN_NUMBER='(0,0,0,0,0,0,0,DA60,0,0,0,0,0,0,0,0,0,0,0,0,0,0,0,0,0,0,0,0,0,0)';
      OUTPUT_LOAD='(1.0,-1.0)';
    'DDR5_MA'<10>:
      PIN_NUMBER='(0,0,0,0,0,0,0,DD55,0,0,0,0,0,0,0,0,0,0,0,0,0,0,0,0,0,0,0,0,0,0)';
      OUTPUT_LOAD='(1.0,-1.0)';
    'DDR5_MA'<9>:
      PIN_NUMBER='(0,0,0,0,0,0,0,DA58,0,0,0,0,0,0,0,0,0,0,0,0,0,0,0,0,0,0,0,0,0,0)';
      OUTPUT_LOAD='(1.0,-1.0)';
    'DDR5_MA'<8>:
      PIN_NUMBER='(0,0,0,0,0,0,0,DD59,0,0,0,0,0,0,0,0,0,0,0,0,0,0,0,0,0,0,0,0,0,0)';
      OUTPUT_LOAD='(1.0,-1.0)';
    'DDR5_MA'<7>:
      PIN_NUMBER='(0,0,0,0,0,0,0,DC60,0,0,0,0,0,0,0,0,0,0,0,0,0,0,0,0,0,0,0,0,0,0)';
      OUTPUT_LOAD='(1.0,-1.0)';
    'DDR5_MA'<6>:
      PIN_NUMBER='(0,0,0,0,0,0,0,DK59,0,0,0,0,0,0,0,0,0,0,0,0,0,0,0,0,0,0,0,0,0,0)';
      OUTPUT_LOAD='(1.0,-1.0)';
    'DDR5_MA'<5>:
      PIN_NUMBER='(0,0,0,0,0,0,0,DF59,0,0,0,0,0,0,0,0,0,0,0,0,0,0,0,0,0,0,0,0,0,0)';
      OUTPUT_LOAD='(1.0,-1.0)';
    'DDR5_MA'<4>:
      PIN_NUMBER='(0,0,0,0,0,0,0,DJ58,0,0,0,0,0,0,0,0,0,0,0,0,0,0,0,0,0,0,0,0,0,0)';
      OUTPUT_LOAD='(1.0,-1.0)';
    'DDR5_MA'<3>:
      PIN_NUMBER='(0,0,0,0,0,0,0,DG58,0,0,0,0,0,0,0,0,0,0,0,0,0,0,0,0,0,0,0,0,0,0)';
      OUTPUT_LOAD='(1.0,-1.0)';
    'DDR5_MA'<2>:
      PIN_NUMBER='(0,0,0,0,0,0,0,DD57,0,0,0,0,0,0,0,0,0,0,0,0,0,0,0,0,0,0,0,0,0,0)';
      OUTPUT_LOAD='(1.0,-1.0)';
    'DDR5_MA'<1>:
      PIN_NUMBER='(0,0,0,0,0,0,0,DC58,0,0,0,0,0,0,0,0,0,0,0,0,0,0,0,0,0,0,0,0,0,0)';
      OUTPUT_LOAD='(1.0,-1.0)';
    'DDR5_MA'<0>:
      PIN_NUMBER='(0,0,0,0,0,0,0,DF53,0,0,0,0,0,0,0,0,0,0,0,0,0,0,0,0,0,0,0,0,0,0)';
      OUTPUT_LOAD='(1.0,-1.0)';
    'DDR5_ODT'<3>:
      PIN_NUMBER='(0,0,0,0,0,0,0,DF47,0,0,0,0,0,0,0,0,0,0,0,0,0,0,0,0,0,0,0,0,0,0)';
      OUTPUT_LOAD='(1.0,-1.0)';
    'DDR5_ODT'<2>:
      PIN_NUMBER='(0,0,0,0,0,0,0,DK49,0,0,0,0,0,0,0,0,0,0,0,0,0,0,0,0,0,0,0,0,0,0)';
      OUTPUT_LOAD='(1.0,-1.0)';
    'DDR5_ODT'<1>:
      PIN_NUMBER='(0,0,0,0,0,0,0,DG48,0,0,0,0,0,0,0,0,0,0,0,0,0,0,0,0,0,0,0,0,0,0)';
      OUTPUT_LOAD='(1.0,-1.0)';
    'DDR5_ODT'<0>:
      PIN_NUMBER='(0,0,0,0,0,0,0,DG50,0,0,0,0,0,0,0,0,0,0,0,0,0,0,0,0,0,0,0,0,0,0)';
      OUTPUT_LOAD='(1.0,-1.0)';
    'DDR5_PAR':
      PIN_NUMBER='(0,0,0,0,0,0,0,DK53,0,0,0,0,0,0,0,0,0,0,0,0,0,0,0,0,0,0,0,0,0,0)';
      OUTPUT_LOAD='(1.0,-1.0)';
    'DEBUG_EN_N':
      PIN_NUMBER='(0,AV21,0,0,0,0,0,0,0,0,0,0,0,0,0,0,0,0,0,0,0,0,0,0,0,0,0,0,0,0)';
      BIDIRECTIONAL='TRUE';
      INPUT_LOAD='(-0.01,0.01)';
      OUTPUT_LOAD='(1.0,-1.0)';
    'DMIMODE_OVERRIDE':
      PIN_NUMBER='(0,AW12,0,0,0,0,0,0,0,0,0,0,0,0,0,0,0,0,0,0,0,0,0,0,0,0,0,0,0,0)';
      BIDIRECTIONAL='TRUE';
      INPUT_LOAD='(-0.01,0.01)';
      OUTPUT_LOAD='(1.0,-1.0)';
    'DMI_RX_DN'<3>:
      PIN_NUMBER='(0,0,0,0,0,0,0,0,CT11,0,0,0,0,0,0,0,0,0,0,0,0,0,0,0,0,0,0,0,0,0)';
      INPUT_LOAD='(-0.01,0.01)';
    'DMI_RX_DN'<2>:
      PIN_NUMBER='(0,0,0,0,0,0,0,0,CR12,0,0,0,0,0,0,0,0,0,0,0,0,0,0,0,0,0,0,0,0,0)';
      INPUT_LOAD='(-0.01,0.01)';
    'DMI_RX_DN'<1>:
      PIN_NUMBER='(0,0,0,0,0,0,0,0,CM11,0,0,0,0,0,0,0,0,0,0,0,0,0,0,0,0,0,0,0,0,0)';
      INPUT_LOAD='(-0.01,0.01)';
    'DMI_RX_DN'<0>:
      PIN_NUMBER='(0,0,0,0,0,0,0,0,CK9,0,0,0,0,0,0,0,0,0,0,0,0,0,0,0,0,0,0,0,0,0)';
      INPUT_LOAD='(-0.01,0.01)';
    'DMI_RX_DP'<3>:
      PIN_NUMBER='(0,0,0,0,0,0,0,0,CV11,0,0,0,0,0,0,0,0,0,0,0,0,0,0,0,0,0,0,0,0,0)';
      INPUT_LOAD='(-0.01,0.01)';
    'DMI_RX_DP'<2>:
      PIN_NUMBER='(0,0,0,0,0,0,0,0,CP11,0,0,0,0,0,0,0,0,0,0,0,0,0,0,0,0,0,0,0,0,0)';
      INPUT_LOAD='(-0.01,0.01)';
    'DMI_RX_DP'<1>:
      PIN_NUMBER='(0,0,0,0,0,0,0,0,CN10,0,0,0,0,0,0,0,0,0,0,0,0,0,0,0,0,0,0,0,0,0)';
      INPUT_LOAD='(-0.01,0.01)';
    'DMI_RX_DP'<0>:
      PIN_NUMBER='(0,0,0,0,0,0,0,0,CL10,0,0,0,0,0,0,0,0,0,0,0,0,0,0,0,0,0,0,0,0,0)';
      INPUT_LOAD='(-0.01,0.01)';
    'DMI_TX_DN'<3>:
      PIN_NUMBER='(0,0,0,0,0,0,0,0,CP5,0,0,0,0,0,0,0,0,0,0,0,0,0,0,0,0,0,0,0,0,0)';
      OUTPUT_LOAD='(1.0,-1.0)';
    'DMI_TX_DN'<2>:
      PIN_NUMBER='(0,0,0,0,0,0,0,0,CN4,0,0,0,0,0,0,0,0,0,0,0,0,0,0,0,0,0,0,0,0,0)';
      OUTPUT_LOAD='(1.0,-1.0)';
    'DMI_TX_DN'<1>:
      PIN_NUMBER='(0,0,0,0,0,0,0,0,CJ4,0,0,0,0,0,0,0,0,0,0,0,0,0,0,0,0,0,0,0,0,0)';
      OUTPUT_LOAD='(1.0,-1.0)';
    'DMI_TX_DN'<0>:
      PIN_NUMBER='(0,0,0,0,0,0,0,0,CG4,0,0,0,0,0,0,0,0,0,0,0,0,0,0,0,0,0,0,0,0,0)';
      OUTPUT_LOAD='(1.0,-1.0)';
    'DMI_TX_DP'<3>:
      PIN_NUMBER='(0,0,0,0,0,0,0,0,CR4,0,0,0,0,0,0,0,0,0,0,0,0,0,0,0,0,0,0,0,0,0)';
      OUTPUT_LOAD='(1.0,-1.0)';
    'DMI_TX_DP'<2>:
      PIN_NUMBER='(0,0,0,0,0,0,0,0,CM3,0,0,0,0,0,0,0,0,0,0,0,0,0,0,0,0,0,0,0,0,0)';
      OUTPUT_LOAD='(1.0,-1.0)';
    'DMI_TX_DP'<1>:
      PIN_NUMBER='(0,0,0,0,0,0,0,0,CL4,0,0,0,0,0,0,0,0,0,0,0,0,0,0,0,0,0,0,0,0,0)';
      OUTPUT_LOAD='(1.0,-1.0)';
    'DMI_TX_DP'<0>:
      PIN_NUMBER='(0,0,0,0,0,0,0,0,CH5,0,0,0,0,0,0,0,0,0,0,0,0,0,0,0,0,0,0,0,0,0)';
      OUTPUT_LOAD='(1.0,-1.0)';
    'EAR_N':
      PIN_NUMBER='(AJ14,0,0,0,0,0,0,0,0,0,0,0,0,0,0,0,0,0,0,0,0,0,0,0,0,0,0,0,0,0)';
      INPUT_LOAD='(-0.01,0.01)';
    'ERROR_N'<2>:
      PIN_NUMBER='(AL12,0,0,0,0,0,0,0,0,0,0,0,0,0,0,0,0,0,0,0,0,0,0,0,0,0,0,0,0,0)';
      OUTPUT_LOAD='(1.0,-1.0)';
    'ERROR_N'<1>:
      PIN_NUMBER='(AK11,0,0,0,0,0,0,0,0,0,0,0,0,0,0,0,0,0,0,0,0,0,0,0,0,0,0,0,0,0)';
      OUTPUT_LOAD='(1.0,-1.0)';
    'ERROR_N'<0>:
      PIN_NUMBER='(AJ12,0,0,0,0,0,0,0,0,0,0,0,0,0,0,0,0,0,0,0,0,0,0,0,0,0,0,0,0,0)';
      OUTPUT_LOAD='(1.0,-1.0)';
    'FIVR_FAULT':
      PIN_NUMBER='(0,AU14,0,0,0,0,0,0,0,0,0,0,0,0,0,0,0,0,0,0,0,0,0,0,0,0,0,0,0,0)';
      OUTPUT_LOAD='(1.0,-1.0)';
    'FRMAGENT':
      PIN_NUMBER='(AV17,0,0,0,0,0,0,0,0,0,0,0,0,0,0,0,0,0,0,0,0,0,0,0,0,0,0,0,0,0)';
      INPUT_LOAD='(-0.01,0.01)';
    'LEGACY_SKT':
      PIN_NUMBER='(AE20,0,0,0,0,0,0,0,0,0,0,0,0,0,0,0,0,0,0,0,0,0,0,0,0,0,0,0,0,0)';
      INPUT_LOAD='(-0.01,0.01)';
    'MCP01_RBIAS'<1>:
      PIN_NUMBER='(CT31,0,0,0,0,0,0,0,0,0,0,0,0,0,0,0,0,0,0,0,0,0,0,0,0,0,0,0,0,0)';
      BIDIRECTIONAL='TRUE';
      INPUT_LOAD='(-0.01,0.01)';
      OUTPUT_LOAD='(1.0,-1.0)';
    'MCP01_RBIAS'<0>:
      PIN_NUMBER='(CU32,0,0,0,0,0,0,0,0,0,0,0,0,0,0,0,0,0,0,0,0,0,0,0,0,0,0,0,0,0)';
      BIDIRECTIONAL='TRUE';
      INPUT_LOAD='(-0.01,0.01)';
      OUTPUT_LOAD='(1.0,-1.0)';
    'MEM_HOT_C012_N':
      PIN_NUMBER='(AH13,0,0,0,0,0,0,0,0,0,0,0,0,0,0,0,0,0,0,0,0,0,0,0,0,0,0,0,0,0)';
      BIDIRECTIONAL='TRUE';
      INPUT_LOAD='(-0.01,0.01)';
      OUTPUT_LOAD='(1.0,-1.0)';
    'MEM_HOT_C345_N':
      PIN_NUMBER='(AF13,0,0,0,0,0,0,0,0,0,0,0,0,0,0,0,0,0,0,0,0,0,0,0,0,0,0,0,0,0)';
      BIDIRECTIONAL='TRUE';
      INPUT_LOAD='(-0.01,0.01)';
      OUTPUT_LOAD='(1.0,-1.0)';
    'MSMI_N':
      PIN_NUMBER='(AN20,0,0,0,0,0,0,0,0,0,0,0,0,0,0,0,0,0,0,0,0,0,0,0,0,0,0,0,0,0)';
      BIDIRECTIONAL='TRUE';
      INPUT_LOAD='(-0.01,0.01)';
      OUTPUT_LOAD='(1.0,-1.0)';
    'NMI':
      PIN_NUMBER='(AP11,0,0,0,0,0,0,0,0,0,0,0,0,0,0,0,0,0,0,0,0,0,0,0,0,0,0,0,0,0)';
      INPUT_LOAD='(-0.01,0.01)';
    'PE012_RBIAS'<1>:
      PIN_NUMBER='(CL30,0,0,0,0,0,0,0,0,0,0,0,0,0,0,0,0,0,0,0,0,0,0,0,0,0,0,0,0,0)';
      BIDIRECTIONAL='TRUE';
      INPUT_LOAD='(-0.01,0.01)';
      OUTPUT_LOAD='(1.0,-1.0)';
    'PE012_RBIAS'<0>:
      PIN_NUMBER='(CN30,0,0,0,0,0,0,0,0,0,0,0,0,0,0,0,0,0,0,0,0,0,0,0,0,0,0,0,0,0)';
      BIDIRECTIONAL='TRUE';
      INPUT_LOAD='(-0.01,0.01)';
      OUTPUT_LOAD='(1.0,-1.0)';
    'PE1_RX_DN'<15>:
      PIN_NUMBER='(0,0,0,0,0,0,0,0,0,DU16,0,0,0,0,0,0,0,0,0,0,0,0,0,0,0,0,0,0,0,0)';
      INPUT_LOAD='(-0.01,0.01)';
    'PE1_RX_DN'<14>:
      PIN_NUMBER='(0,0,0,0,0,0,0,0,0,DY15,0,0,0,0,0,0,0,0,0,0,0,0,0,0,0,0,0,0,0,0)';
      INPUT_LOAD='(-0.01,0.01)';
    'PE1_RX_DN'<13>:
      PIN_NUMBER='(0,0,0,0,0,0,0,0,0,DW14,0,0,0,0,0,0,0,0,0,0,0,0,0,0,0,0,0,0,0,0)';
      INPUT_LOAD='(-0.01,0.01)';
    'PE1_RX_DN'<12>:
      PIN_NUMBER='(0,0,0,0,0,0,0,0,0,DV13,0,0,0,0,0,0,0,0,0,0,0,0,0,0,0,0,0,0,0,0)';
      INPUT_LOAD='(-0.01,0.01)';
    'PE1_RX_DN'<11>:
      PIN_NUMBER='(0,0,0,0,0,0,0,0,0,DT13,0,0,0,0,0,0,0,0,0,0,0,0,0,0,0,0,0,0,0,0)';
      INPUT_LOAD='(-0.01,0.01)';
    'PE1_RX_DN'<10>:
      PIN_NUMBER='(0,0,0,0,0,0,0,0,0,DT11,0,0,0,0,0,0,0,0,0,0,0,0,0,0,0,0,0,0,0,0)';
      INPUT_LOAD='(-0.01,0.01)';
    'PE1_RX_DN'<9>:
      PIN_NUMBER='(0,0,0,0,0,0,0,0,0,DP11,0,0,0,0,0,0,0,0,0,0,0,0,0,0,0,0,0,0,0,0)';
      INPUT_LOAD='(-0.01,0.01)';
    'PE1_RX_DN'<8>:
      PIN_NUMBER='(0,0,0,0,0,0,0,0,0,DM11,0,0,0,0,0,0,0,0,0,0,0,0,0,0,0,0,0,0,0,0)';
      INPUT_LOAD='(-0.01,0.01)';
    'PE1_RX_DN'<7>:
      PIN_NUMBER='(0,0,0,0,0,0,0,0,0,DM9,0,0,0,0,0,0,0,0,0,0,0,0,0,0,0,0,0,0,0,0)';
      INPUT_LOAD='(-0.01,0.01)';
    'PE1_RX_DN'<6>:
      PIN_NUMBER='(0,0,0,0,0,0,0,0,0,DK9,0,0,0,0,0,0,0,0,0,0,0,0,0,0,0,0,0,0,0,0)';
      INPUT_LOAD='(-0.01,0.01)';
    'PE1_RX_DN'<5>:
      PIN_NUMBER='(0,0,0,0,0,0,0,0,0,DH9,0,0,0,0,0,0,0,0,0,0,0,0,0,0,0,0,0,0,0,0)';
      INPUT_LOAD='(-0.01,0.01)';
    'PE1_RX_DN'<4>:
      PIN_NUMBER='(0,0,0,0,0,0,0,0,0,DE10,0,0,0,0,0,0,0,0,0,0,0,0,0,0,0,0,0,0,0,0)';
      INPUT_LOAD='(-0.01,0.01)';
    'PE1_RX_DN'<3>:
      PIN_NUMBER='(0,0,0,0,0,0,0,0,0,DC10,0,0,0,0,0,0,0,0,0,0,0,0,0,0,0,0,0,0,0,0)';
      INPUT_LOAD='(-0.01,0.01)';
    'PE1_RX_DN'<2>:
      PIN_NUMBER='(0,0,0,0,0,0,0,0,0,DC8,0,0,0,0,0,0,0,0,0,0,0,0,0,0,0,0,0,0,0,0)';
      INPUT_LOAD='(-0.01,0.01)';
    'PE1_RX_DN'<1>:
      PIN_NUMBER='(0,0,0,0,0,0,0,0,0,DA8,0,0,0,0,0,0,0,0,0,0,0,0,0,0,0,0,0,0,0,0)';
      INPUT_LOAD='(-0.01,0.01)';
    'PE1_RX_DN'<0>:
      PIN_NUMBER='(0,0,0,0,0,0,0,0,0,CW8,0,0,0,0,0,0,0,0,0,0,0,0,0,0,0,0,0,0,0,0)';
      INPUT_LOAD='(-0.01,0.01)';
    'PE1_RX_DP'<15>:
      PIN_NUMBER='(0,0,0,0,0,0,0,0,0,DT15,0,0,0,0,0,0,0,0,0,0,0,0,0,0,0,0,0,0,0,0)';
      INPUT_LOAD='(-0.01,0.01)';
    'PE1_RX_DP'<14>:
      PIN_NUMBER='(0,0,0,0,0,0,0,0,0,DV15,0,0,0,0,0,0,0,0,0,0,0,0,0,0,0,0,0,0,0,0)';
      INPUT_LOAD='(-0.01,0.01)';
    'PE1_RX_DP'<13>:
      PIN_NUMBER='(0,0,0,0,0,0,0,0,0,DY13,0,0,0,0,0,0,0,0,0,0,0,0,0,0,0,0,0,0,0,0)';
      INPUT_LOAD='(-0.01,0.01)';
    'PE1_RX_DP'<12>:
      PIN_NUMBER='(0,0,0,0,0,0,0,0,0,DU12,0,0,0,0,0,0,0,0,0,0,0,0,0,0,0,0,0,0,0,0)';
      INPUT_LOAD='(-0.01,0.01)';
    'PE1_RX_DP'<11>:
      PIN_NUMBER='(0,0,0,0,0,0,0,0,0,DP13,0,0,0,0,0,0,0,0,0,0,0,0,0,0,0,0,0,0,0,0)';
      INPUT_LOAD='(-0.01,0.01)';
    'PE1_RX_DP'<10>:
      PIN_NUMBER='(0,0,0,0,0,0,0,0,0,DR12,0,0,0,0,0,0,0,0,0,0,0,0,0,0,0,0,0,0,0,0)';
      INPUT_LOAD='(-0.01,0.01)';
    'PE1_RX_DP'<9>:
      PIN_NUMBER='(0,0,0,0,0,0,0,0,0,DN10,0,0,0,0,0,0,0,0,0,0,0,0,0,0,0,0,0,0,0,0)';
      INPUT_LOAD='(-0.01,0.01)';
    'PE1_RX_DP'<8>:
      PIN_NUMBER='(0,0,0,0,0,0,0,0,0,DK11,0,0,0,0,0,0,0,0,0,0,0,0,0,0,0,0,0,0,0,0)';
      INPUT_LOAD='(-0.01,0.01)';
    'PE1_RX_DP'<7>:
      PIN_NUMBER='(0,0,0,0,0,0,0,0,0,DL10,0,0,0,0,0,0,0,0,0,0,0,0,0,0,0,0,0,0,0,0)';
      INPUT_LOAD='(-0.01,0.01)';
    'PE1_RX_DP'<6>:
      PIN_NUMBER='(0,0,0,0,0,0,0,0,0,DJ8,0,0,0,0,0,0,0,0,0,0,0,0,0,0,0,0,0,0,0,0)';
      INPUT_LOAD='(-0.01,0.01)';
    'PE1_RX_DP'<5>:
      PIN_NUMBER='(0,0,0,0,0,0,0,0,0,DF9,0,0,0,0,0,0,0,0,0,0,0,0,0,0,0,0,0,0,0,0)';
      INPUT_LOAD='(-0.01,0.01)';
    'PE1_RX_DP'<4>:
      PIN_NUMBER='(0,0,0,0,0,0,0,0,0,DD9,0,0,0,0,0,0,0,0,0,0,0,0,0,0,0,0,0,0,0,0)';
      INPUT_LOAD='(-0.01,0.01)';
    'PE1_RX_DP'<3>:
      PIN_NUMBER='(0,0,0,0,0,0,0,0,0,DA10,0,0,0,0,0,0,0,0,0,0,0,0,0,0,0,0,0,0,0,0)';
      INPUT_LOAD='(-0.01,0.01)';
    'PE1_RX_DP'<2>:
      PIN_NUMBER='(0,0,0,0,0,0,0,0,0,DB9,0,0,0,0,0,0,0,0,0,0,0,0,0,0,0,0,0,0,0,0)';
      INPUT_LOAD='(-0.01,0.01)';
    'PE1_RX_DP'<1>:
      PIN_NUMBER='(0,0,0,0,0,0,0,0,0,CY7,0,0,0,0,0,0,0,0,0,0,0,0,0,0,0,0,0,0,0,0)';
      INPUT_LOAD='(-0.01,0.01)';
    'PE1_RX_DP'<0>:
      PIN_NUMBER='(0,0,0,0,0,0,0,0,0,CU8,0,0,0,0,0,0,0,0,0,0,0,0,0,0,0,0,0,0,0,0)';
      INPUT_LOAD='(-0.01,0.01)';
    'PE1_TX_DN'<15>:
      PIN_NUMBER='(0,0,0,0,0,0,0,0,0,ED9,0,0,0,0,0,0,0,0,0,0,0,0,0,0,0,0,0,0,0,0)';
      OUTPUT_LOAD='(1.0,-1.0)';
    'PE1_TX_DN'<14>:
      PIN_NUMBER='(0,0,0,0,0,0,0,0,0,EA8,0,0,0,0,0,0,0,0,0,0,0,0,0,0,0,0,0,0,0,0)';
      OUTPUT_LOAD='(1.0,-1.0)';
    'PE1_TX_DN'<13>:
      PIN_NUMBER='(0,0,0,0,0,0,0,0,0,DY7,0,0,0,0,0,0,0,0,0,0,0,0,0,0,0,0,0,0,0,0)';
      OUTPUT_LOAD='(1.0,-1.0)';
    'PE1_TX_DN'<12>:
      PIN_NUMBER='(0,0,0,0,0,0,0,0,0,DV7,0,0,0,0,0,0,0,0,0,0,0,0,0,0,0,0,0,0,0,0)';
      OUTPUT_LOAD='(1.0,-1.0)';
    'PE1_TX_DN'<11>:
      PIN_NUMBER='(0,0,0,0,0,0,0,0,0,DU6,0,0,0,0,0,0,0,0,0,0,0,0,0,0,0,0,0,0,0,0)';
      OUTPUT_LOAD='(1.0,-1.0)';
    'PE1_TX_DN'<10>:
      PIN_NUMBER='(0,0,0,0,0,0,0,0,0,DW4,0,0,0,0,0,0,0,0,0,0,0,0,0,0,0,0,0,0,0,0)';
      OUTPUT_LOAD='(1.0,-1.0)';
    'PE1_TX_DN'<9>:
      PIN_NUMBER='(0,0,0,0,0,0,0,0,0,DV3,0,0,0,0,0,0,0,0,0,0,0,0,0,0,0,0,0,0,0,0)';
      OUTPUT_LOAD='(1.0,-1.0)';
    'PE1_TX_DN'<8>:
      PIN_NUMBER='(0,0,0,0,0,0,0,0,0,DT5,0,0,0,0,0,0,0,0,0,0,0,0,0,0,0,0,0,0,0,0)';
      OUTPUT_LOAD='(1.0,-1.0)';
    'PE1_TX_DN'<7>:
      PIN_NUMBER='(0,0,0,0,0,0,0,0,0,DN4,0,0,0,0,0,0,0,0,0,0,0,0,0,0,0,0,0,0,0,0)';
      OUTPUT_LOAD='(1.0,-1.0)';
    'PE1_TX_DN'<6>:
      PIN_NUMBER='(0,0,0,0,0,0,0,0,0,DM3,0,0,0,0,0,0,0,0,0,0,0,0,0,0,0,0,0,0,0,0)';
      OUTPUT_LOAD='(1.0,-1.0)';
    'PE1_TX_DN'<5>:
      PIN_NUMBER='(0,0,0,0,0,0,0,0,0,DK3,0,0,0,0,0,0,0,0,0,0,0,0,0,0,0,0,0,0,0,0)';
      OUTPUT_LOAD='(1.0,-1.0)';
    'PE1_TX_DN'<4>:
      PIN_NUMBER='(0,0,0,0,0,0,0,0,0,DG4,0,0,0,0,0,0,0,0,0,0,0,0,0,0,0,0,0,0,0,0)';
      OUTPUT_LOAD='(1.0,-1.0)';
    'PE1_TX_DN'<3>:
      PIN_NUMBER='(0,0,0,0,0,0,0,0,0,DE4,0,0,0,0,0,0,0,0,0,0,0,0,0,0,0,0,0,0,0,0)';
      OUTPUT_LOAD='(1.0,-1.0)';
    'PE1_TX_DN'<2>:
      PIN_NUMBER='(0,0,0,0,0,0,0,0,0,DE2,0,0,0,0,0,0,0,0,0,0,0,0,0,0,0,0,0,0,0,0)';
      OUTPUT_LOAD='(1.0,-1.0)';
    'PE1_TX_DN'<1>:
      PIN_NUMBER='(0,0,0,0,0,0,0,0,0,DC2,0,0,0,0,0,0,0,0,0,0,0,0,0,0,0,0,0,0,0,0)';
      OUTPUT_LOAD='(1.0,-1.0)';
    'PE1_TX_DN'<0>:
      PIN_NUMBER='(0,0,0,0,0,0,0,0,0,DA2,0,0,0,0,0,0,0,0,0,0,0,0,0,0,0,0,0,0,0,0)';
      OUTPUT_LOAD='(1.0,-1.0)';
    'PE1_TX_DP'<15>:
      PIN_NUMBER='(0,0,0,0,0,0,0,0,0,EC8,0,0,0,0,0,0,0,0,0,0,0,0,0,0,0,0,0,0,0,0)';
      OUTPUT_LOAD='(1.0,-1.0)';
    'PE1_TX_DP'<14>:
      PIN_NUMBER='(0,0,0,0,0,0,0,0,0,EB7,0,0,0,0,0,0,0,0,0,0,0,0,0,0,0,0,0,0,0,0)';
      OUTPUT_LOAD='(1.0,-1.0)';
    'PE1_TX_DP'<13>:
      PIN_NUMBER='(0,0,0,0,0,0,0,0,0,DW6,0,0,0,0,0,0,0,0,0,0,0,0,0,0,0,0,0,0,0,0)';
      OUTPUT_LOAD='(1.0,-1.0)';
    'PE1_TX_DP'<12>:
      PIN_NUMBER='(0,0,0,0,0,0,0,0,0,DT7,0,0,0,0,0,0,0,0,0,0,0,0,0,0,0,0,0,0,0,0)';
      OUTPUT_LOAD='(1.0,-1.0)';
    'PE1_TX_DP'<11>:
      PIN_NUMBER='(0,0,0,0,0,0,0,0,0,DV5,0,0,0,0,0,0,0,0,0,0,0,0,0,0,0,0,0,0,0,0)';
      OUTPUT_LOAD='(1.0,-1.0)';
    'PE1_TX_DP'<10>:
      PIN_NUMBER='(0,0,0,0,0,0,0,0,0,DU4,0,0,0,0,0,0,0,0,0,0,0,0,0,0,0,0,0,0,0,0)';
      OUTPUT_LOAD='(1.0,-1.0)';
    'PE1_TX_DP'<9>:
      PIN_NUMBER='(0,0,0,0,0,0,0,0,0,DU2,0,0,0,0,0,0,0,0,0,0,0,0,0,0,0,0,0,0,0,0)';
      OUTPUT_LOAD='(1.0,-1.0)';
    'PE1_TX_DP'<8>:
      PIN_NUMBER='(0,0,0,0,0,0,0,0,0,DR4,0,0,0,0,0,0,0,0,0,0,0,0,0,0,0,0,0,0,0,0)';
      OUTPUT_LOAD='(1.0,-1.0)';
    'PE1_TX_DP'<7>:
      PIN_NUMBER='(0,0,0,0,0,0,0,0,0,DP3,0,0,0,0,0,0,0,0,0,0,0,0,0,0,0,0,0,0,0,0)';
      OUTPUT_LOAD='(1.0,-1.0)';
    'PE1_TX_DP'<6>:
      PIN_NUMBER='(0,0,0,0,0,0,0,0,0,DL2,0,0,0,0,0,0,0,0,0,0,0,0,0,0,0,0,0,0,0,0)';
      OUTPUT_LOAD='(1.0,-1.0)';
    'PE1_TX_DP'<5>:
      PIN_NUMBER='(0,0,0,0,0,0,0,0,0,DH3,0,0,0,0,0,0,0,0,0,0,0,0,0,0,0,0,0,0,0,0)';
      OUTPUT_LOAD='(1.0,-1.0)';
    'PE1_TX_DP'<4>:
      PIN_NUMBER='(0,0,0,0,0,0,0,0,0,DF3,0,0,0,0,0,0,0,0,0,0,0,0,0,0,0,0,0,0,0,0)';
      OUTPUT_LOAD='(1.0,-1.0)';
    'PE1_TX_DP'<3>:
      PIN_NUMBER='(0,0,0,0,0,0,0,0,0,DC4,0,0,0,0,0,0,0,0,0,0,0,0,0,0,0,0,0,0,0,0)';
      OUTPUT_LOAD='(1.0,-1.0)';
    'PE1_TX_DP'<2>:
      PIN_NUMBER='(0,0,0,0,0,0,0,0,0,DD3,0,0,0,0,0,0,0,0,0,0,0,0,0,0,0,0,0,0,0,0)';
      OUTPUT_LOAD='(1.0,-1.0)';
    'PE1_TX_DP'<1>:
      PIN_NUMBER='(0,0,0,0,0,0,0,0,0,DB1,0,0,0,0,0,0,0,0,0,0,0,0,0,0,0,0,0,0,0,0)';
      OUTPUT_LOAD='(1.0,-1.0)';
    'PE1_TX_DP'<0>:
      PIN_NUMBER='(0,0,0,0,0,0,0,0,0,CW2,0,0,0,0,0,0,0,0,0,0,0,0,0,0,0,0,0,0,0,0)';
      OUTPUT_LOAD='(1.0,-1.0)';
    'PE2_RX_DN'<15>:
      PIN_NUMBER='(0,0,0,0,0,0,0,0,0,0,BK9,0,0,0,0,0,0,0,0,0,0,0,0,0,0,0,0,0,0,0)';
      INPUT_LOAD='(-0.01,0.01)';
    'PE2_RX_DN'<14>:
      PIN_NUMBER='(0,0,0,0,0,0,0,0,0,0,BL8,0,0,0,0,0,0,0,0,0,0,0,0,0,0,0,0,0,0,0)';
      INPUT_LOAD='(-0.01,0.01)';
    'PE2_RX_DN'<13>:
      PIN_NUMBER='(0,0,0,0,0,0,0,0,0,0,BN8,0,0,0,0,0,0,0,0,0,0,0,0,0,0,0,0,0,0,0)';
      INPUT_LOAD='(-0.01,0.01)';
    'PE2_RX_DN'<12>:
      PIN_NUMBER='(0,0,0,0,0,0,0,0,0,0,BR8,0,0,0,0,0,0,0,0,0,0,0,0,0,0,0,0,0,0,0)';
      INPUT_LOAD='(-0.01,0.01)';
    'PE2_RX_DN'<11>:
      PIN_NUMBER='(0,0,0,0,0,0,0,0,0,0,BT7,0,0,0,0,0,0,0,0,0,0,0,0,0,0,0,0,0,0,0)';
      INPUT_LOAD='(-0.01,0.01)';
    'PE2_RX_DN'<10>:
      PIN_NUMBER='(0,0,0,0,0,0,0,0,0,0,BV7,0,0,0,0,0,0,0,0,0,0,0,0,0,0,0,0,0,0,0)';
      INPUT_LOAD='(-0.01,0.01)';
    'PE2_RX_DN'<9>:
      PIN_NUMBER='(0,0,0,0,0,0,0,0,0,0,BY7,0,0,0,0,0,0,0,0,0,0,0,0,0,0,0,0,0,0,0)';
      INPUT_LOAD='(-0.01,0.01)';
    'PE2_RX_DN'<8>:
      PIN_NUMBER='(0,0,0,0,0,0,0,0,0,0,BY9,0,0,0,0,0,0,0,0,0,0,0,0,0,0,0,0,0,0,0)';
      INPUT_LOAD='(-0.01,0.01)';
    'PE2_RX_DN'<7>:
      PIN_NUMBER='(0,0,0,0,0,0,0,0,0,0,CE8,0,0,0,0,0,0,0,0,0,0,0,0,0,0,0,0,0,0,0)';
      INPUT_LOAD='(-0.01,0.01)';
    'PE2_RX_DN'<6>:
      PIN_NUMBER='(0,0,0,0,0,0,0,0,0,0,CE6,0,0,0,0,0,0,0,0,0,0,0,0,0,0,0,0,0,0,0)';
      INPUT_LOAD='(-0.01,0.01)';
    'PE2_RX_DN'<5>:
      PIN_NUMBER='(0,0,0,0,0,0,0,0,0,0,CG8,0,0,0,0,0,0,0,0,0,0,0,0,0,0,0,0,0,0,0)';
      INPUT_LOAD='(-0.01,0.01)';
    'PE2_RX_DN'<4>:
      PIN_NUMBER='(0,0,0,0,0,0,0,0,0,0,CK7,0,0,0,0,0,0,0,0,0,0,0,0,0,0,0,0,0,0,0)';
      INPUT_LOAD='(-0.01,0.01)';
    'PE2_RX_DN'<3>:
      PIN_NUMBER='(0,0,0,0,0,0,0,0,0,0,CM7,0,0,0,0,0,0,0,0,0,0,0,0,0,0,0,0,0,0,0)';
      INPUT_LOAD='(-0.01,0.01)';
    'PE2_RX_DN'<2>:
      PIN_NUMBER='(0,0,0,0,0,0,0,0,0,0,CP7,0,0,0,0,0,0,0,0,0,0,0,0,0,0,0,0,0,0,0)';
      INPUT_LOAD='(-0.01,0.01)';
    'PE2_RX_DN'<1>:
      PIN_NUMBER='(0,0,0,0,0,0,0,0,0,0,CP9,0,0,0,0,0,0,0,0,0,0,0,0,0,0,0,0,0,0,0)';
      INPUT_LOAD='(-0.01,0.01)';
    'PE2_RX_DN'<0>:
      PIN_NUMBER='(0,0,0,0,0,0,0,0,0,0,CT9,0,0,0,0,0,0,0,0,0,0,0,0,0,0,0,0,0,0,0)';
      INPUT_LOAD='(-0.01,0.01)';
    'PE2_RX_DP'<15>:
      PIN_NUMBER='(0,0,0,0,0,0,0,0,0,0,BJ10,0,0,0,0,0,0,0,0,0,0,0,0,0,0,0,0,0,0,0)';
      INPUT_LOAD='(-0.01,0.01)';
    'PE2_RX_DP'<14>:
      PIN_NUMBER='(0,0,0,0,0,0,0,0,0,0,BJ8,0,0,0,0,0,0,0,0,0,0,0,0,0,0,0,0,0,0,0)';
      INPUT_LOAD='(-0.01,0.01)';
    'PE2_RX_DP'<13>:
      PIN_NUMBER='(0,0,0,0,0,0,0,0,0,0,BM7,0,0,0,0,0,0,0,0,0,0,0,0,0,0,0,0,0,0,0)';
      INPUT_LOAD='(-0.01,0.01)';
    'PE2_RX_DP'<12>:
      PIN_NUMBER='(0,0,0,0,0,0,0,0,0,0,BP9,0,0,0,0,0,0,0,0,0,0,0,0,0,0,0,0,0,0,0)';
      INPUT_LOAD='(-0.01,0.01)';
    'PE2_RX_DP'<11>:
      PIN_NUMBER='(0,0,0,0,0,0,0,0,0,0,BP7,0,0,0,0,0,0,0,0,0,0,0,0,0,0,0,0,0,0,0)';
      INPUT_LOAD='(-0.01,0.01)';
    'PE2_RX_DP'<10>:
      PIN_NUMBER='(0,0,0,0,0,0,0,0,0,0,BU6,0,0,0,0,0,0,0,0,0,0,0,0,0,0,0,0,0,0,0)';
      INPUT_LOAD='(-0.01,0.01)';
    'PE2_RX_DP'<9>:
      PIN_NUMBER='(0,0,0,0,0,0,0,0,0,0,BW8,0,0,0,0,0,0,0,0,0,0,0,0,0,0,0,0,0,0,0)';
      INPUT_LOAD='(-0.01,0.01)';
    'PE2_RX_DP'<8>:
      PIN_NUMBER='(0,0,0,0,0,0,0,0,0,0,BV9,0,0,0,0,0,0,0,0,0,0,0,0,0,0,0,0,0,0,0)';
      INPUT_LOAD='(-0.01,0.01)';
    'PE2_RX_DP'<7>:
      PIN_NUMBER='(0,0,0,0,0,0,0,0,0,0,CC8,0,0,0,0,0,0,0,0,0,0,0,0,0,0,0,0,0,0,0)';
      INPUT_LOAD='(-0.01,0.01)';
    'PE2_RX_DP'<6>:
      PIN_NUMBER='(0,0,0,0,0,0,0,0,0,0,CD7,0,0,0,0,0,0,0,0,0,0,0,0,0,0,0,0,0,0,0)';
      INPUT_LOAD='(-0.01,0.01)';
    'PE2_RX_DP'<5>:
      PIN_NUMBER='(0,0,0,0,0,0,0,0,0,0,CF7,0,0,0,0,0,0,0,0,0,0,0,0,0,0,0,0,0,0,0)';
      INPUT_LOAD='(-0.01,0.01)';
    'PE2_RX_DP'<4>:
      PIN_NUMBER='(0,0,0,0,0,0,0,0,0,0,CH7,0,0,0,0,0,0,0,0,0,0,0,0,0,0,0,0,0,0,0)';
      INPUT_LOAD='(-0.01,0.01)';
    'PE2_RX_DP'<3>:
      PIN_NUMBER='(0,0,0,0,0,0,0,0,0,0,CL6,0,0,0,0,0,0,0,0,0,0,0,0,0,0,0,0,0,0,0)';
      INPUT_LOAD='(-0.01,0.01)';
    'PE2_RX_DP'<2>:
      PIN_NUMBER='(0,0,0,0,0,0,0,0,0,0,CN8,0,0,0,0,0,0,0,0,0,0,0,0,0,0,0,0,0,0,0)';
      INPUT_LOAD='(-0.01,0.01)';
    'PE2_RX_DP'<1>:
      PIN_NUMBER='(0,0,0,0,0,0,0,0,0,0,CM9,0,0,0,0,0,0,0,0,0,0,0,0,0,0,0,0,0,0,0)';
      INPUT_LOAD='(-0.01,0.01)';
    'PE2_RX_DP'<0>:
      PIN_NUMBER='(0,0,0,0,0,0,0,0,0,0,CR8,0,0,0,0,0,0,0,0,0,0,0,0,0,0,0,0,0,0,0)';
      INPUT_LOAD='(-0.01,0.01)';
    'PE2_TX_DN'<15>:
      PIN_NUMBER='(0,0,0,0,0,0,0,0,0,0,BM5,0,0,0,0,0,0,0,0,0,0,0,0,0,0,0,0,0,0,0)';
      OUTPUT_LOAD='(1.0,-1.0)';
    'PE2_TX_DN'<14>:
      PIN_NUMBER='(0,0,0,0,0,0,0,0,0,0,BL4,0,0,0,0,0,0,0,0,0,0,0,0,0,0,0,0,0,0,0)';
      OUTPUT_LOAD='(1.0,-1.0)';
    'PE2_TX_DN'<13>:
      PIN_NUMBER='(0,0,0,0,0,0,0,0,0,0,BP5,0,0,0,0,0,0,0,0,0,0,0,0,0,0,0,0,0,0,0)';
      OUTPUT_LOAD='(1.0,-1.0)';
    'PE2_TX_DN'<12>:
      PIN_NUMBER='(0,0,0,0,0,0,0,0,0,0,BU4,0,0,0,0,0,0,0,0,0,0,0,0,0,0,0,0,0,0,0)';
      OUTPUT_LOAD='(1.0,-1.0)';
    'PE2_TX_DN'<11>:
      PIN_NUMBER='(0,0,0,0,0,0,0,0,0,0,BW4,0,0,0,0,0,0,0,0,0,0,0,0,0,0,0,0,0,0,0)';
      OUTPUT_LOAD='(1.0,-1.0)';
    'PE2_TX_DN'<10>:
      PIN_NUMBER='(0,0,0,0,0,0,0,0,0,0,CA4,0,0,0,0,0,0,0,0,0,0,0,0,0,0,0,0,0,0,0)';
      OUTPUT_LOAD='(1.0,-1.0)';
    'PE2_TX_DN'<9>:
      PIN_NUMBER='(0,0,0,0,0,0,0,0,0,0,CB3,0,0,0,0,0,0,0,0,0,0,0,0,0,0,0,0,0,0,0)';
      OUTPUT_LOAD='(1.0,-1.0)';
    'PE2_TX_DN'<8>:
      PIN_NUMBER='(0,0,0,0,0,0,0,0,0,0,CC2,0,0,0,0,0,0,0,0,0,0,0,0,0,0,0,0,0,0,0)';
      OUTPUT_LOAD='(1.0,-1.0)';
    'PE2_TX_DN'<7>:
      PIN_NUMBER='(0,0,0,0,0,0,0,0,0,0,CF3,0,0,0,0,0,0,0,0,0,0,0,0,0,0,0,0,0,0,0)';
      OUTPUT_LOAD='(1.0,-1.0)';
    'PE2_TX_DN'<6>:
      PIN_NUMBER='(0,0,0,0,0,0,0,0,0,0,CG2,0,0,0,0,0,0,0,0,0,0,0,0,0,0,0,0,0,0,0)';
      OUTPUT_LOAD='(1.0,-1.0)';
    'PE2_TX_DN'<5>:
      PIN_NUMBER='(0,0,0,0,0,0,0,0,0,0,CL2,0,0,0,0,0,0,0,0,0,0,0,0,0,0,0,0,0,0,0)';
      OUTPUT_LOAD='(1.0,-1.0)';
    'PE2_TX_DN'<4>:
      PIN_NUMBER='(0,0,0,0,0,0,0,0,0,0,CM1,0,0,0,0,0,0,0,0,0,0,0,0,0,0,0,0,0,0,0)';
      OUTPUT_LOAD='(1.0,-1.0)';
    'PE2_TX_DN'<3>:
      PIN_NUMBER='(0,0,0,0,0,0,0,0,0,0,CT3,0,0,0,0,0,0,0,0,0,0,0,0,0,0,0,0,0,0,0)';
      OUTPUT_LOAD='(1.0,-1.0)';
    'PE2_TX_DN'<2>:
      PIN_NUMBER='(0,0,0,0,0,0,0,0,0,0,CT1,0,0,0,0,0,0,0,0,0,0,0,0,0,0,0,0,0,0,0)';
      OUTPUT_LOAD='(1.0,-1.0)';
    'PE2_TX_DN'<1>:
      PIN_NUMBER='(0,0,0,0,0,0,0,0,0,0,CV3,0,0,0,0,0,0,0,0,0,0,0,0,0,0,0,0,0,0,0)';
      OUTPUT_LOAD='(1.0,-1.0)';
    'PE2_TX_DN'<0>:
      PIN_NUMBER='(0,0,0,0,0,0,0,0,0,0,CY3,0,0,0,0,0,0,0,0,0,0,0,0,0,0,0,0,0,0,0)';
      OUTPUT_LOAD='(1.0,-1.0)';
    'PE2_TX_DP'<15>:
      PIN_NUMBER='(0,0,0,0,0,0,0,0,0,0,BK5,0,0,0,0,0,0,0,0,0,0,0,0,0,0,0,0,0,0,0)';
      OUTPUT_LOAD='(1.0,-1.0)';
    'PE2_TX_DP'<14>:
      PIN_NUMBER='(0,0,0,0,0,0,0,0,0,0,BM3,0,0,0,0,0,0,0,0,0,0,0,0,0,0,0,0,0,0,0)';
      OUTPUT_LOAD='(1.0,-1.0)';
    'PE2_TX_DP'<13>:
      PIN_NUMBER='(0,0,0,0,0,0,0,0,0,0,BN4,0,0,0,0,0,0,0,0,0,0,0,0,0,0,0,0,0,0,0)';
      OUTPUT_LOAD='(1.0,-1.0)';
    'PE2_TX_DP'<12>:
      PIN_NUMBER='(0,0,0,0,0,0,0,0,0,0,BR4,0,0,0,0,0,0,0,0,0,0,0,0,0,0,0,0,0,0,0)';
      OUTPUT_LOAD='(1.0,-1.0)';
    'PE2_TX_DP'<11>:
      PIN_NUMBER='(0,0,0,0,0,0,0,0,0,0,BV3,0,0,0,0,0,0,0,0,0,0,0,0,0,0,0,0,0,0,0)';
      OUTPUT_LOAD='(1.0,-1.0)';
    'PE2_TX_DP'<10>:
      PIN_NUMBER='(0,0,0,0,0,0,0,0,0,0,BY5,0,0,0,0,0,0,0,0,0,0,0,0,0,0,0,0,0,0,0)';
      OUTPUT_LOAD='(1.0,-1.0)';
    'PE2_TX_DP'<9>:
      PIN_NUMBER='(0,0,0,0,0,0,0,0,0,0,BY3,0,0,0,0,0,0,0,0,0,0,0,0,0,0,0,0,0,0,0)';
      OUTPUT_LOAD='(1.0,-1.0)';
    'PE2_TX_DP'<8>:
      PIN_NUMBER='(0,0,0,0,0,0,0,0,0,0,CD3,0,0,0,0,0,0,0,0,0,0,0,0,0,0,0,0,0,0,0)';
      OUTPUT_LOAD='(1.0,-1.0)';
    'PE2_TX_DP'<7>:
      PIN_NUMBER='(0,0,0,0,0,0,0,0,0,0,CE4,0,0,0,0,0,0,0,0,0,0,0,0,0,0,0,0,0,0,0)';
      OUTPUT_LOAD='(1.0,-1.0)';
    'PE2_TX_DP'<6>:
      PIN_NUMBER='(0,0,0,0,0,0,0,0,0,0,CE2,0,0,0,0,0,0,0,0,0,0,0,0,0,0,0,0,0,0,0)';
      OUTPUT_LOAD='(1.0,-1.0)';
    'PE2_TX_DP'<5>:
      PIN_NUMBER='(0,0,0,0,0,0,0,0,0,0,CK3,0,0,0,0,0,0,0,0,0,0,0,0,0,0,0,0,0,0,0)';
      OUTPUT_LOAD='(1.0,-1.0)';
    'PE2_TX_DP'<4>:
      PIN_NUMBER='(0,0,0,0,0,0,0,0,0,0,CK1,0,0,0,0,0,0,0,0,0,0,0,0,0,0,0,0,0,0,0)';
      OUTPUT_LOAD='(1.0,-1.0)';
    'PE2_TX_DP'<3>:
      PIN_NUMBER='(0,0,0,0,0,0,0,0,0,0,CP3,0,0,0,0,0,0,0,0,0,0,0,0,0,0,0,0,0,0,0)';
      OUTPUT_LOAD='(1.0,-1.0)';
    'PE2_TX_DP'<2>:
      PIN_NUMBER='(0,0,0,0,0,0,0,0,0,0,CR2,0,0,0,0,0,0,0,0,0,0,0,0,0,0,0,0,0,0,0)';
      OUTPUT_LOAD='(1.0,-1.0)';
    'PE2_TX_DP'<1>:
      PIN_NUMBER='(0,0,0,0,0,0,0,0,0,0,CU2,0,0,0,0,0,0,0,0,0,0,0,0,0,0,0,0,0,0,0)';
      OUTPUT_LOAD='(1.0,-1.0)';
    'PE2_TX_DP'<0>:
      PIN_NUMBER='(0,0,0,0,0,0,0,0,0,0,CW4,0,0,0,0,0,0,0,0,0,0,0,0,0,0,0,0,0,0,0)';
      OUTPUT_LOAD='(1.0,-1.0)';
    'PE3_RBIAS'<1>:
      PIN_NUMBER='(CR30,0,0,0,0,0,0,0,0,0,0,0,0,0,0,0,0,0,0,0,0,0,0,0,0,0,0,0,0,0)';
      INPUT_LOAD='(-0.01,0.01)';
    'PE3_RBIAS'<0>:
      PIN_NUMBER='(CP29,0,0,0,0,0,0,0,0,0,0,0,0,0,0,0,0,0,0,0,0,0,0,0,0,0,0,0,0,0)';
      INPUT_LOAD='(-0.01,0.01)';
    'PE3_RX_DN'<15>:
      PIN_NUMBER='(0,0,0,0,0,0,0,0,0,0,0,CV9,0,0,0,0,0,0,0,0,0,0,0,0,0,0,0,0,0,0)';
      INPUT_LOAD='(-0.01,0.01)';
    'PE3_RX_DN'<14>:
      PIN_NUMBER='(0,0,0,0,0,0,0,0,0,0,0,CY11,0,0,0,0,0,0,0,0,0,0,0,0,0,0,0,0,0,0)';
      INPUT_LOAD='(-0.01,0.01)';
    'PE3_RX_DN'<13>:
      PIN_NUMBER='(0,0,0,0,0,0,0,0,0,0,0,DB11,0,0,0,0,0,0,0,0,0,0,0,0,0,0,0,0,0,0)';
      INPUT_LOAD='(-0.01,0.01)';
    'PE3_RX_DN'<12>:
      PIN_NUMBER='(0,0,0,0,0,0,0,0,0,0,0,DD13,0,0,0,0,0,0,0,0,0,0,0,0,0,0,0,0,0,0)';
      INPUT_LOAD='(-0.01,0.01)';
    'PE3_RX_DN'<11>:
      PIN_NUMBER='(0,0,0,0,0,0,0,0,0,0,0,DG10,0,0,0,0,0,0,0,0,0,0,0,0,0,0,0,0,0,0)';
      INPUT_LOAD='(-0.01,0.01)';
    'PE3_RX_DN'<10>:
      PIN_NUMBER='(0,0,0,0,0,0,0,0,0,0,0,DG12,0,0,0,0,0,0,0,0,0,0,0,0,0,0,0,0,0,0)';
      INPUT_LOAD='(-0.01,0.01)';
    'PE3_RX_DN'<9>:
      PIN_NUMBER='(0,0,0,0,0,0,0,0,0,0,0,DJ12,0,0,0,0,0,0,0,0,0,0,0,0,0,0,0,0,0,0)';
      INPUT_LOAD='(-0.01,0.01)';
    'PE3_RX_DN'<8>:
      PIN_NUMBER='(0,0,0,0,0,0,0,0,0,0,0,DL12,0,0,0,0,0,0,0,0,0,0,0,0,0,0,0,0,0,0)';
      INPUT_LOAD='(-0.01,0.01)';
    'PE3_RX_DN'<7>:
      PIN_NUMBER='(0,0,0,0,0,0,0,0,0,0,0,DL14,0,0,0,0,0,0,0,0,0,0,0,0,0,0,0,0,0,0)';
      INPUT_LOAD='(-0.01,0.01)';
    'PE3_RX_DN'<6>:
      PIN_NUMBER='(0,0,0,0,0,0,0,0,0,0,0,DN14,0,0,0,0,0,0,0,0,0,0,0,0,0,0,0,0,0,0)';
      INPUT_LOAD='(-0.01,0.01)';
    'PE3_RX_DN'<5>:
      PIN_NUMBER='(0,0,0,0,0,0,0,0,0,0,0,DR14,0,0,0,0,0,0,0,0,0,0,0,0,0,0,0,0,0,0)';
      INPUT_LOAD='(-0.01,0.01)';
    'PE3_RX_DN'<4>:
      PIN_NUMBER='(0,0,0,0,0,0,0,0,0,0,0,DR16,0,0,0,0,0,0,0,0,0,0,0,0,0,0,0,0,0,0)';
      INPUT_LOAD='(-0.01,0.01)';
    'PE3_RX_DN'<3>:
      PIN_NUMBER='(0,0,0,0,0,0,0,0,0,0,0,DT19,0,0,0,0,0,0,0,0,0,0,0,0,0,0,0,0,0,0)';
      INPUT_LOAD='(-0.01,0.01)';
    'PE3_RX_DN'<2>:
      PIN_NUMBER='(0,0,0,0,0,0,0,0,0,0,0,DW16,0,0,0,0,0,0,0,0,0,0,0,0,0,0,0,0,0,0)';
      INPUT_LOAD='(-0.01,0.01)';
    'PE3_RX_DN'<1>:
      PIN_NUMBER='(0,0,0,0,0,0,0,0,0,0,0,DW18,0,0,0,0,0,0,0,0,0,0,0,0,0,0,0,0,0,0)';
      INPUT_LOAD='(-0.01,0.01)';
    'PE3_RX_DN'<0>:
      PIN_NUMBER='(0,0,0,0,0,0,0,0,0,0,0,EA18,0,0,0,0,0,0,0,0,0,0,0,0,0,0,0,0,0,0)';
      INPUT_LOAD='(-0.01,0.01)';
    'PE3_RX_DP'<15>:
      PIN_NUMBER='(0,0,0,0,0,0,0,0,0,0,0,CU10,0,0,0,0,0,0,0,0,0,0,0,0,0,0,0,0,0,0)';
      INPUT_LOAD='(-0.01,0.01)';
    'PE3_RX_DP'<14>:
      PIN_NUMBER='(0,0,0,0,0,0,0,0,0,0,0,CW10,0,0,0,0,0,0,0,0,0,0,0,0,0,0,0,0,0,0)';
      INPUT_LOAD='(-0.01,0.01)';
    'PE3_RX_DP'<13>:
      PIN_NUMBER='(0,0,0,0,0,0,0,0,0,0,0,DA12,0,0,0,0,0,0,0,0,0,0,0,0,0,0,0,0,0,0)';
      INPUT_LOAD='(-0.01,0.01)';
    'PE3_RX_DP'<12>:
      PIN_NUMBER='(0,0,0,0,0,0,0,0,0,0,0,DC12,0,0,0,0,0,0,0,0,0,0,0,0,0,0,0,0,0,0)';
      INPUT_LOAD='(-0.01,0.01)';
    'PE3_RX_DP'<11>:
      PIN_NUMBER='(0,0,0,0,0,0,0,0,0,0,0,DF11,0,0,0,0,0,0,0,0,0,0,0,0,0,0,0,0,0,0)';
      INPUT_LOAD='(-0.01,0.01)';
    'PE3_RX_DP'<10>:
      PIN_NUMBER='(0,0,0,0,0,0,0,0,0,0,0,DE12,0,0,0,0,0,0,0,0,0,0,0,0,0,0,0,0,0,0)';
      INPUT_LOAD='(-0.01,0.01)';
    'PE3_RX_DP'<9>:
      PIN_NUMBER='(0,0,0,0,0,0,0,0,0,0,0,DH11,0,0,0,0,0,0,0,0,0,0,0,0,0,0,0,0,0,0)';
      INPUT_LOAD='(-0.01,0.01)';
    'PE3_RX_DP'<8>:
      PIN_NUMBER='(0,0,0,0,0,0,0,0,0,0,0,DK13,0,0,0,0,0,0,0,0,0,0,0,0,0,0,0,0,0,0)';
      INPUT_LOAD='(-0.01,0.01)';
    'PE3_RX_DP'<7>:
      PIN_NUMBER='(0,0,0,0,0,0,0,0,0,0,0,DJ14,0,0,0,0,0,0,0,0,0,0,0,0,0,0,0,0,0,0)';
      INPUT_LOAD='(-0.01,0.01)';
    'PE3_RX_DP'<6>:
      PIN_NUMBER='(0,0,0,0,0,0,0,0,0,0,0,DM13,0,0,0,0,0,0,0,0,0,0,0,0,0,0,0,0,0,0)';
      INPUT_LOAD='(-0.01,0.01)';
    'PE3_RX_DP'<5>:
      PIN_NUMBER='(0,0,0,0,0,0,0,0,0,0,0,DP15,0,0,0,0,0,0,0,0,0,0,0,0,0,0,0,0,0,0)';
      INPUT_LOAD='(-0.01,0.01)';
    'PE3_RX_DP'<4>:
      PIN_NUMBER='(0,0,0,0,0,0,0,0,0,0,0,DN16,0,0,0,0,0,0,0,0,0,0,0,0,0,0,0,0,0,0)';
      INPUT_LOAD='(-0.01,0.01)';
    'PE3_RX_DP'<3>:
      PIN_NUMBER='(0,0,0,0,0,0,0,0,0,0,0,DR18,0,0,0,0,0,0,0,0,0,0,0,0,0,0,0,0,0,0)';
      INPUT_LOAD='(-0.01,0.01)';
    'PE3_RX_DP'<2>:
      PIN_NUMBER='(0,0,0,0,0,0,0,0,0,0,0,DV17,0,0,0,0,0,0,0,0,0,0,0,0,0,0,0,0,0,0)';
      INPUT_LOAD='(-0.01,0.01)';
    'PE3_RX_DP'<1>:
      PIN_NUMBER='(0,0,0,0,0,0,0,0,0,0,0,DU18,0,0,0,0,0,0,0,0,0,0,0,0,0,0,0,0,0,0)';
      INPUT_LOAD='(-0.01,0.01)';
    'PE3_RX_DP'<0>:
      PIN_NUMBER='(0,0,0,0,0,0,0,0,0,0,0,DY17,0,0,0,0,0,0,0,0,0,0,0,0,0,0,0,0,0,0)';
      INPUT_LOAD='(-0.01,0.01)';
    'PE3_TX_DN'<15>:
      PIN_NUMBER='(0,0,0,0,0,0,0,0,0,0,0,CY5,0,0,0,0,0,0,0,0,0,0,0,0,0,0,0,0,0,0)';
      OUTPUT_LOAD='(1.0,-1.0)';
    'PE3_TX_DN'<14>:
      PIN_NUMBER='(0,0,0,0,0,0,0,0,0,0,0,DB5,0,0,0,0,0,0,0,0,0,0,0,0,0,0,0,0,0,0)';
      OUTPUT_LOAD='(1.0,-1.0)';
    'PE3_TX_DN'<13>:
      PIN_NUMBER='(0,0,0,0,0,0,0,0,0,0,0,DD5,0,0,0,0,0,0,0,0,0,0,0,0,0,0,0,0,0,0)';
      OUTPUT_LOAD='(1.0,-1.0)';
    'PE3_TX_DN'<12>:
      PIN_NUMBER='(0,0,0,0,0,0,0,0,0,0,0,DJ6,0,0,0,0,0,0,0,0,0,0,0,0,0,0,0,0,0,0)';
      OUTPUT_LOAD='(1.0,-1.0)';
    'PE3_TX_DN'<11>:
      PIN_NUMBER='(0,0,0,0,0,0,0,0,0,0,0,DJ4,0,0,0,0,0,0,0,0,0,0,0,0,0,0,0,0,0,0)';
      OUTPUT_LOAD='(1.0,-1.0)';
    'PE3_TX_DN'<10>:
      PIN_NUMBER='(0,0,0,0,0,0,0,0,0,0,0,DL6,0,0,0,0,0,0,0,0,0,0,0,0,0,0,0,0,0,0)';
      OUTPUT_LOAD='(1.0,-1.0)';
    'PE3_TX_DN'<9>:
      PIN_NUMBER='(0,0,0,0,0,0,0,0,0,0,0,DP5,0,0,0,0,0,0,0,0,0,0,0,0,0,0,0,0,0,0)';
      OUTPUT_LOAD='(1.0,-1.0)';
    'PE3_TX_DN'<8>:
      PIN_NUMBER='(0,0,0,0,0,0,0,0,0,0,0,DM7,0,0,0,0,0,0,0,0,0,0,0,0,0,0,0,0,0,0)';
      OUTPUT_LOAD='(1.0,-1.0)';
    'PE3_TX_DN'<7>:
      PIN_NUMBER='(0,0,0,0,0,0,0,0,0,0,0,DR8,0,0,0,0,0,0,0,0,0,0,0,0,0,0,0,0,0,0)';
      OUTPUT_LOAD='(1.0,-1.0)';
    'PE3_TX_DN'<6>:
      PIN_NUMBER='(0,0,0,0,0,0,0,0,0,0,0,DU8,0,0,0,0,0,0,0,0,0,0,0,0,0,0,0,0,0,0)';
      OUTPUT_LOAD='(1.0,-1.0)';
    'PE3_TX_DN'<5>:
      PIN_NUMBER='(0,0,0,0,0,0,0,0,0,0,0,DW10,0,0,0,0,0,0,0,0,0,0,0,0,0,0,0,0,0,0)';
      OUTPUT_LOAD='(1.0,-1.0)';
    'PE3_TX_DN'<4>:
      PIN_NUMBER='(0,0,0,0,0,0,0,0,0,0,0,EB9,0,0,0,0,0,0,0,0,0,0,0,0,0,0,0,0,0,0)';
      OUTPUT_LOAD='(1.0,-1.0)';
    'PE3_TX_DN'<3>:
      PIN_NUMBER='(0,0,0,0,0,0,0,0,0,0,0,DY11,0,0,0,0,0,0,0,0,0,0,0,0,0,0,0,0,0,0)';
      OUTPUT_LOAD='(1.0,-1.0)';
    'PE3_TX_DN'<2>:
      PIN_NUMBER='(0,0,0,0,0,0,0,0,0,0,0,EC12,0,0,0,0,0,0,0,0,0,0,0,0,0,0,0,0,0,0)';
      OUTPUT_LOAD='(1.0,-1.0)';
    'PE3_TX_DN'<1>:
      PIN_NUMBER='(0,0,0,0,0,0,0,0,0,0,0,EE12,0,0,0,0,0,0,0,0,0,0,0,0,0,0,0,0,0,0)';
      OUTPUT_LOAD='(1.0,-1.0)';
    'PE3_TX_DN'<0>:
      PIN_NUMBER='(0,0,0,0,0,0,0,0,0,0,0,EE14,0,0,0,0,0,0,0,0,0,0,0,0,0,0,0,0,0,0)';
      OUTPUT_LOAD='(1.0,-1.0)';
    'PE3_TX_DP'<15>:
      PIN_NUMBER='(0,0,0,0,0,0,0,0,0,0,0,CV5,0,0,0,0,0,0,0,0,0,0,0,0,0,0,0,0,0,0)';
      OUTPUT_LOAD='(1.0,-1.0)';
    'PE3_TX_DP'<14>:
      PIN_NUMBER='(0,0,0,0,0,0,0,0,0,0,0,DA4,0,0,0,0,0,0,0,0,0,0,0,0,0,0,0,0,0,0)';
      OUTPUT_LOAD='(1.0,-1.0)';
    'PE3_TX_DP'<13>:
      PIN_NUMBER='(0,0,0,0,0,0,0,0,0,0,0,DC6,0,0,0,0,0,0,0,0,0,0,0,0,0,0,0,0,0,0)';
      OUTPUT_LOAD='(1.0,-1.0)';
    'PE3_TX_DP'<12>:
      PIN_NUMBER='(0,0,0,0,0,0,0,0,0,0,0,DG6,0,0,0,0,0,0,0,0,0,0,0,0,0,0,0,0,0,0)';
      OUTPUT_LOAD='(1.0,-1.0)';
    'PE3_TX_DP'<11>:
      PIN_NUMBER='(0,0,0,0,0,0,0,0,0,0,0,DH5,0,0,0,0,0,0,0,0,0,0,0,0,0,0,0,0,0,0)';
      OUTPUT_LOAD='(1.0,-1.0)';
    'PE3_TX_DP'<10>:
      PIN_NUMBER='(0,0,0,0,0,0,0,0,0,0,0,DK5,0,0,0,0,0,0,0,0,0,0,0,0,0,0,0,0,0,0)';
      OUTPUT_LOAD='(1.0,-1.0)';
    'PE3_TX_DP'<9>:
      PIN_NUMBER='(0,0,0,0,0,0,0,0,0,0,0,DM5,0,0,0,0,0,0,0,0,0,0,0,0,0,0,0,0,0,0)';
      OUTPUT_LOAD='(1.0,-1.0)';
    'PE3_TX_DP'<8>:
      PIN_NUMBER='(0,0,0,0,0,0,0,0,0,0,0,DN6,0,0,0,0,0,0,0,0,0,0,0,0,0,0,0,0,0,0)';
      OUTPUT_LOAD='(1.0,-1.0)';
    'PE3_TX_DP'<7>:
      PIN_NUMBER='(0,0,0,0,0,0,0,0,0,0,0,DP7,0,0,0,0,0,0,0,0,0,0,0,0,0,0,0,0,0,0)';
      OUTPUT_LOAD='(1.0,-1.0)';
    'PE3_TX_DP'<6>:
      PIN_NUMBER='(0,0,0,0,0,0,0,0,0,0,0,DT9,0,0,0,0,0,0,0,0,0,0,0,0,0,0,0,0,0,0)';
      OUTPUT_LOAD='(1.0,-1.0)';
    'PE3_TX_DP'<5>:
      PIN_NUMBER='(0,0,0,0,0,0,0,0,0,0,0,DV9,0,0,0,0,0,0,0,0,0,0,0,0,0,0,0,0,0,0)';
      OUTPUT_LOAD='(1.0,-1.0)';
    'PE3_TX_DP'<4>:
      PIN_NUMBER='(0,0,0,0,0,0,0,0,0,0,0,DY9,0,0,0,0,0,0,0,0,0,0,0,0,0,0,0,0,0,0)';
      OUTPUT_LOAD='(1.0,-1.0)';
    'PE3_TX_DP'<3>:
      PIN_NUMBER='(0,0,0,0,0,0,0,0,0,0,0,EA10,0,0,0,0,0,0,0,0,0,0,0,0,0,0,0,0,0,0)';
      OUTPUT_LOAD='(1.0,-1.0)';
    'PE3_TX_DP'<2>:
      PIN_NUMBER='(0,0,0,0,0,0,0,0,0,0,0,EB11,0,0,0,0,0,0,0,0,0,0,0,0,0,0,0,0,0,0)';
      OUTPUT_LOAD='(1.0,-1.0)';
    'PE3_TX_DP'<1>:
      PIN_NUMBER='(0,0,0,0,0,0,0,0,0,0,0,ED13,0,0,0,0,0,0,0,0,0,0,0,0,0,0,0,0,0,0)';
      OUTPUT_LOAD='(1.0,-1.0)';
    'PE3_TX_DP'<0>:
      PIN_NUMBER='(0,0,0,0,0,0,0,0,0,0,0,EC14,0,0,0,0,0,0,0,0,0,0,0,0,0,0,0,0,0,0)';
      OUTPUT_LOAD='(1.0,-1.0)';
    'PECI':
      PIN_NUMBER='(AU12,0,0,0,0,0,0,0,0,0,0,0,0,0,0,0,0,0,0,0,0,0,0,0,0,0,0,0,0,0)';
      BIDIRECTIONAL='TRUE';
      INPUT_LOAD='(-0.01,0.01)';
      OUTPUT_LOAD='(1.0,-1.0)';
    'PE_HP_SCL':
      PIN_NUMBER='(AM19,0,0,0,0,0,0,0,0,0,0,0,0,0,0,0,0,0,0,0,0,0,0,0,0,0,0,0,0,0)';
      BIDIRECTIONAL='TRUE';
      INPUT_LOAD='(-0.01,0.01)';
      OUTPUT_LOAD='(1.0,-1.0)';
    'PE_HP_SDA':
      PIN_NUMBER='(AL18,0,0,0,0,0,0,0,0,0,0,0,0,0,0,0,0,0,0,0,0,0,0,0,0,0,0,0,0,0)';
      BIDIRECTIONAL='TRUE';
      INPUT_LOAD='(-0.01,0.01)';
      OUTPUT_LOAD='(1.0,-1.0)';
    'PIROM_ADDR'<2>:
      PIN_NUMBER='(CW56,0,0,0,0,0,0,0,0,0,0,0,0,0,0,0,0,0,0,0,0,0,0,0,0,0,0,0,0,0)';
      BIDIRECTIONAL='TRUE';
      INPUT_LOAD='(-0.01,0.01)';
      OUTPUT_LOAD='(1.0,-1.0)';
    'PIROM_ADDR'<1>:
      PIN_NUMBER='(CV57,0,0,0,0,0,0,0,0,0,0,0,0,0,0,0,0,0,0,0,0,0,0,0,0,0,0,0,0,0)';
      BIDIRECTIONAL='TRUE';
      INPUT_LOAD='(-0.01,0.01)';
      OUTPUT_LOAD='(1.0,-1.0)';
    'PIROM_ADDR'<0>:
      PIN_NUMBER='(CU58,0,0,0,0,0,0,0,0,0,0,0,0,0,0,0,0,0,0,0,0,0,0,0,0,0,0,0,0,0)';
      BIDIRECTIONAL='TRUE';
      INPUT_LOAD='(-0.01,0.01)';
      OUTPUT_LOAD='(1.0,-1.0)';
    'PKGID'<2>:
      PIN_NUMBER='(DA72,0,0,0,0,0,0,0,0,0,0,0,0,0,0,0,0,0,0,0,0,0,0,0,0,0,0,0,0,0)';
      BIDIRECTIONAL='TRUE';
      INPUT_LOAD='(-0.01,0.01)';
      OUTPUT_LOAD='(1.0,-1.0)';
    'PKGID'<1>:
      PIN_NUMBER='(CW72,0,0,0,0,0,0,0,0,0,0,0,0,0,0,0,0,0,0,0,0,0,0,0,0,0,0,0,0,0)';
      BIDIRECTIONAL='TRUE';
      INPUT_LOAD='(-0.01,0.01)';
      OUTPUT_LOAD='(1.0,-1.0)';
    'PKGID'<0>:
      PIN_NUMBER='(DC72,0,0,0,0,0,0,0,0,0,0,0,0,0,0,0,0,0,0,0,0,0,0,0,0,0,0,0,0,0)';
      BIDIRECTIONAL='TRUE';
      INPUT_LOAD='(-0.01,0.01)';
      OUTPUT_LOAD='(1.0,-1.0)';
    'PMSYNC':
      PIN_NUMBER='(AR14,0,0,0,0,0,0,0,0,0,0,0,0,0,0,0,0,0,0,0,0,0,0,0,0,0,0,0,0,0)';
      INPUT_LOAD='(-0.01,0.01)';
    'PMSYNC_CLK':
      PIN_NUMBER='(AT19,0,0,0,0,0,0,0,0,0,0,0,0,0,0,0,0,0,0,0,0,0,0,0,0,0,0,0,0,0)';
      INPUT_LOAD='(-0.01,0.01)';
    'PM_FAST_WAKE_N':
      PIN_NUMBER='(AF15,0,0,0,0,0,0,0,0,0,0,0,0,0,0,0,0,0,0,0,0,0,0,0,0,0,0,0,0,0)';
      BIDIRECTIONAL='TRUE';
      INPUT_LOAD='(-0.01,0.01)';
      OUTPUT_LOAD='(1.0,-1.0)';
    'PRDY_N':
      PIN_NUMBER='(AG16,0,0,0,0,0,0,0,0,0,0,0,0,0,0,0,0,0,0,0,0,0,0,0,0,0,0,0,0,0)';
      OUTPUT_LOAD='(1.0,-1.0)';
    'PREQ_N':
      PIN_NUMBER='(AR12,0,0,0,0,0,0,0,0,0,0,0,0,0,0,0,0,0,0,0,0,0,0,0,0,0,0,0,0,0)';
      INPUT_LOAD='(-0.01,0.01)';
    'PROCDIS_N':
      PIN_NUMBER='(AB17,0,0,0,0,0,0,0,0,0,0,0,0,0,0,0,0,0,0,0,0,0,0,0,0,0,0,0,0,0)';
      INPUT_LOAD='(-0.01,0.01)';
    'PROCHOT_N':
      PIN_NUMBER='(AC16,0,0,0,0,0,0,0,0,0,0,0,0,0,0,0,0,0,0,0,0,0,0,0,0,0,0,0,0,0)';
      BIDIRECTIONAL='TRUE';
      INPUT_LOAD='(-0.01,0.01)';
      OUTPUT_LOAD='(1.0,-1.0)';
    'PROC_ID'<1>:
      PIN_NUMBER='(DB71,0,0,0,0,0,0,0,0,0,0,0,0,0,0,0,0,0,0,0,0,0,0,0,0,0,0,0,0,0)';
      OUTPUT_LOAD='(1.0,-1.0)';
    'PROC_ID'<0>:
      PIN_NUMBER='(CY71,0,0,0,0,0,0,0,0,0,0,0,0,0,0,0,0,0,0,0,0,0,0,0,0,0,0,0,0,0)';
      OUTPUT_LOAD='(1.0,-1.0)';
    'PWRGOOD':
      PIN_NUMBER='(BC24,0,0,0,0,0,0,0,0,0,0,0,0,0,0,0,0,0,0,0,0,0,0,0,0,0,0,0,0,0)';
      INPUT_LOAD='(-0.01,0.01)';
    'PWR_DEBUG_N':
      PIN_NUMBER='(0,AP17,0,0,0,0,0,0,0,0,0,0,0,0,0,0,0,0,0,0,0,0,0,0,0,0,0,0,0,0)';
      INPUT_LOAD='(-0.01,0.01)';
    'RESET_N':
      PIN_NUMBER='(AP21,0,0,0,0,0,0,0,0,0,0,0,0,0,0,0,0,0,0,0,0,0,0,0,0,0,0,0,0,0)';
      INPUT_LOAD='(-0.01,0.01)';
    'RSVD'<304>:
      PIN_NUMBER='(0,A4,0,0,0,0,0,0,0,0,0,0,0,0,0,0,0,0,0,0,0,0,0,0,0,0,0,0,0,0)';
      BIDIRECTIONAL='TRUE';
      INPUT_LOAD='(-0.01,0.01)';
      OUTPUT_LOAD='(1.0,-1.0)';
    'RSVD'<303>:
      PIN_NUMBER='(0,A6,0,0,0,0,0,0,0,0,0,0,0,0,0,0,0,0,0,0,0,0,0,0,0,0,0,0,0,0)';
      BIDIRECTIONAL='TRUE';
      INPUT_LOAD='(-0.01,0.01)';
      OUTPUT_LOAD='(1.0,-1.0)';
    'RSVD'<302>:
      PIN_NUMBER='(0,A14,0,0,0,0,0,0,0,0,0,0,0,0,0,0,0,0,0,0,0,0,0,0,0,0,0,0,0,0)';
      BIDIRECTIONAL='TRUE';
      INPUT_LOAD='(-0.01,0.01)';
      OUTPUT_LOAD='(1.0,-1.0)';
    'RSVD'<301>:
      PIN_NUMBER='(0,A16,0,0,0,0,0,0,0,0,0,0,0,0,0,0,0,0,0,0,0,0,0,0,0,0,0,0,0,0)';
      BIDIRECTIONAL='TRUE';
      INPUT_LOAD='(-0.01,0.01)';
      OUTPUT_LOAD='(1.0,-1.0)';
    'RSVD'<300>:
      PIN_NUMBER='(0,A24,0,0,0,0,0,0,0,0,0,0,0,0,0,0,0,0,0,0,0,0,0,0,0,0,0,0,0,0)';
      BIDIRECTIONAL='TRUE';
      INPUT_LOAD='(-0.01,0.01)';
      OUTPUT_LOAD='(1.0,-1.0)';
    'RSVD'<299>:
      PIN_NUMBER='(0,B3,0,0,0,0,0,0,0,0,0,0,0,0,0,0,0,0,0,0,0,0,0,0,0,0,0,0,0,0)';
      BIDIRECTIONAL='TRUE';
      INPUT_LOAD='(-0.01,0.01)';
      OUTPUT_LOAD='(1.0,-1.0)';
    'RSVD'<298>:
      PIN_NUMBER='(0,B7,0,0,0,0,0,0,0,0,0,0,0,0,0,0,0,0,0,0,0,0,0,0,0,0,0,0,0,0)';
      BIDIRECTIONAL='TRUE';
      INPUT_LOAD='(-0.01,0.01)';
      OUTPUT_LOAD='(1.0,-1.0)';
    'RSVD'<296>:
      PIN_NUMBER='(0,B13,0,0,0,0,0,0,0,0,0,0,0,0,0,0,0,0,0,0,0,0,0,0,0,0,0,0,0,0)';
      BIDIRECTIONAL='TRUE';
      INPUT_LOAD='(-0.01,0.01)';
      OUTPUT_LOAD='(1.0,-1.0)';
    'RSVD'<295>:
      PIN_NUMBER='(0,B15,0,0,0,0,0,0,0,0,0,0,0,0,0,0,0,0,0,0,0,0,0,0,0,0,0,0,0,0)';
      BIDIRECTIONAL='TRUE';
      INPUT_LOAD='(-0.01,0.01)';
      OUTPUT_LOAD='(1.0,-1.0)';
    'RSVD'<294>:
      PIN_NUMBER='(0,B17,0,0,0,0,0,0,0,0,0,0,0,0,0,0,0,0,0,0,0,0,0,0,0,0,0,0,0,0)';
      BIDIRECTIONAL='TRUE';
      INPUT_LOAD='(-0.01,0.01)';
      OUTPUT_LOAD='(1.0,-1.0)';
    'RSVD'<293>:
      PIN_NUMBER='(0,B77,0,0,0,0,0,0,0,0,0,0,0,0,0,0,0,0,0,0,0,0,0,0,0,0,0,0,0,0)';
      BIDIRECTIONAL='TRUE';
      INPUT_LOAD='(-0.01,0.01)';
      OUTPUT_LOAD='(1.0,-1.0)';
    'RSVD'<292>:
      PIN_NUMBER='(0,B81,0,0,0,0,0,0,0,0,0,0,0,0,0,0,0,0,0,0,0,0,0,0,0,0,0,0,0,0)';
      BIDIRECTIONAL='TRUE';
      INPUT_LOAD='(-0.01,0.01)';
      OUTPUT_LOAD='(1.0,-1.0)';
    'RSVD'<291>:
      PIN_NUMBER='(0,C6,0,0,0,0,0,0,0,0,0,0,0,0,0,0,0,0,0,0,0,0,0,0,0,0,0,0,0,0)';
      BIDIRECTIONAL='TRUE';
      INPUT_LOAD='(-0.01,0.01)';
      OUTPUT_LOAD='(1.0,-1.0)';
    'RSVD'<290>:
      PIN_NUMBER='(0,C18,0,0,0,0,0,0,0,0,0,0,0,0,0,0,0,0,0,0,0,0,0,0,0,0,0,0,0,0)';
      BIDIRECTIONAL='TRUE';
      INPUT_LOAD='(-0.01,0.01)';
      OUTPUT_LOAD='(1.0,-1.0)';
    'RSVD'<289>:
      PIN_NUMBER='(0,C24,0,0,0,0,0,0,0,0,0,0,0,0,0,0,0,0,0,0,0,0,0,0,0,0,0,0,0,0)';
      BIDIRECTIONAL='TRUE';
      INPUT_LOAD='(-0.01,0.01)';
      OUTPUT_LOAD='(1.0,-1.0)';
    'RSVD'<288>:
      PIN_NUMBER='(0,C82,0,0,0,0,0,0,0,0,0,0,0,0,0,0,0,0,0,0,0,0,0,0,0,0,0,0,0,0)';
      BIDIRECTIONAL='TRUE';
      INPUT_LOAD='(-0.01,0.01)';
      OUTPUT_LOAD='(1.0,-1.0)';
    'RSVD'<287>:
      PIN_NUMBER='(0,D5,0,0,0,0,0,0,0,0,0,0,0,0,0,0,0,0,0,0,0,0,0,0,0,0,0,0,0,0)';
      BIDIRECTIONAL='TRUE';
      INPUT_LOAD='(-0.01,0.01)';
      OUTPUT_LOAD='(1.0,-1.0)';
    'RSVD'<286>:
      PIN_NUMBER='(0,D17,0,0,0,0,0,0,0,0,0,0,0,0,0,0,0,0,0,0,0,0,0,0,0,0,0,0,0,0)';
      BIDIRECTIONAL='TRUE';
      INPUT_LOAD='(-0.01,0.01)';
      OUTPUT_LOAD='(1.0,-1.0)';
    'RSVD'<285>:
      PIN_NUMBER='(0,D65,0,0,0,0,0,0,0,0,0,0,0,0,0,0,0,0,0,0,0,0,0,0,0,0,0,0,0,0)';
      BIDIRECTIONAL='TRUE';
      INPUT_LOAD='(-0.01,0.01)';
      OUTPUT_LOAD='(1.0,-1.0)';
    'RSVD'<284>:
      PIN_NUMBER='(0,D83,0,0,0,0,0,0,0,0,0,0,0,0,0,0,0,0,0,0,0,0,0,0,0,0,0,0,0,0)';
      BIDIRECTIONAL='TRUE';
      INPUT_LOAD='(-0.01,0.01)';
      OUTPUT_LOAD='(1.0,-1.0)';
    'RSVD'<283>:
      PIN_NUMBER='(0,E2,0,0,0,0,0,0,0,0,0,0,0,0,0,0,0,0,0,0,0,0,0,0,0,0,0,0,0,0)';
      BIDIRECTIONAL='TRUE';
      INPUT_LOAD='(-0.01,0.01)';
      OUTPUT_LOAD='(1.0,-1.0)';
    'RSVD'<282>:
      PIN_NUMBER='(0,E4,0,0,0,0,0,0,0,0,0,0,0,0,0,0,0,0,0,0,0,0,0,0,0,0,0,0,0,0)';
      BIDIRECTIONAL='TRUE';
      INPUT_LOAD='(-0.01,0.01)';
      OUTPUT_LOAD='(1.0,-1.0)';
    'RSVD'<281>:
      PIN_NUMBER='(0,E24,0,0,0,0,0,0,0,0,0,0,0,0,0,0,0,0,0,0,0,0,0,0,0,0,0,0,0,0)';
      BIDIRECTIONAL='TRUE';
      INPUT_LOAD='(-0.01,0.01)';
      OUTPUT_LOAD='(1.0,-1.0)';
    'RSVD'<280>:
      PIN_NUMBER='(0,E84,0,0,0,0,0,0,0,0,0,0,0,0,0,0,0,0,0,0,0,0,0,0,0,0,0,0,0,0)';
      BIDIRECTIONAL='TRUE';
      INPUT_LOAD='(-0.01,0.01)';
      OUTPUT_LOAD='(1.0,-1.0)';
    'RSVD'<279>:
      PIN_NUMBER='(0,F3,0,0,0,0,0,0,0,0,0,0,0,0,0,0,0,0,0,0,0,0,0,0,0,0,0,0,0,0)';
      BIDIRECTIONAL='TRUE';
      INPUT_LOAD='(-0.01,0.01)';
      OUTPUT_LOAD='(1.0,-1.0)';
    'RSVD'<278>:
      PIN_NUMBER='(0,F23,0,0,0,0,0,0,0,0,0,0,0,0,0,0,0,0,0,0,0,0,0,0,0,0,0,0,0,0)';
      BIDIRECTIONAL='TRUE';
      INPUT_LOAD='(-0.01,0.01)';
      OUTPUT_LOAD='(1.0,-1.0)';
    'RSVD'<277>:
      PIN_NUMBER='(0,F65,0,0,0,0,0,0,0,0,0,0,0,0,0,0,0,0,0,0,0,0,0,0,0,0,0,0,0,0)';
      BIDIRECTIONAL='TRUE';
      INPUT_LOAD='(-0.01,0.01)';
      OUTPUT_LOAD='(1.0,-1.0)';
    'RSVD'<276>:
      PIN_NUMBER='(0,F83,0,0,0,0,0,0,0,0,0,0,0,0,0,0,0,0,0,0,0,0,0,0,0,0,0,0,0,0)';
      BIDIRECTIONAL='TRUE';
      INPUT_LOAD='(-0.01,0.01)';
      OUTPUT_LOAD='(1.0,-1.0)';
    'RSVD'<275>:
      PIN_NUMBER='(0,G2,0,0,0,0,0,0,0,0,0,0,0,0,0,0,0,0,0,0,0,0,0,0,0,0,0,0,0,0)';
      BIDIRECTIONAL='TRUE';
      INPUT_LOAD='(-0.01,0.01)';
      OUTPUT_LOAD='(1.0,-1.0)';
    'RSVD'<274>:
      PIN_NUMBER='(0,G64,0,0,0,0,0,0,0,0,0,0,0,0,0,0,0,0,0,0,0,0,0,0,0,0,0,0,0,0)';
      BIDIRECTIONAL='TRUE';
      INPUT_LOAD='(-0.01,0.01)';
      OUTPUT_LOAD='(1.0,-1.0)';
    'RSVD'<273>:
      PIN_NUMBER='(0,G84,0,0,0,0,0,0,0,0,0,0,0,0,0,0,0,0,0,0,0,0,0,0,0,0,0,0,0,0)';
      BIDIRECTIONAL='TRUE';
      INPUT_LOAD='(-0.01,0.01)';
      OUTPUT_LOAD='(1.0,-1.0)';
    'RSVD'<272>:
      PIN_NUMBER='(0,H1,0,0,0,0,0,0,0,0,0,0,0,0,0,0,0,0,0,0,0,0,0,0,0,0,0,0,0,0)';
      BIDIRECTIONAL='TRUE';
      INPUT_LOAD='(-0.01,0.01)';
      OUTPUT_LOAD='(1.0,-1.0)';
    'RSVD'<271>:
      PIN_NUMBER='(0,H83,0,0,0,0,0,0,0,0,0,0,0,0,0,0,0,0,0,0,0,0,0,0,0,0,0,0,0,0)';
      BIDIRECTIONAL='TRUE';
      INPUT_LOAD='(-0.01,0.01)';
      OUTPUT_LOAD='(1.0,-1.0)';
    'RSVD'<270>:
      PIN_NUMBER='(0,H85,0,0,0,0,0,0,0,0,0,0,0,0,0,0,0,0,0,0,0,0,0,0,0,0,0,0,0,0)';
      BIDIRECTIONAL='TRUE';
      INPUT_LOAD='(-0.01,0.01)';
      OUTPUT_LOAD='(1.0,-1.0)';
    'RSVD'<269>:
      PIN_NUMBER='(0,J46,0,0,0,0,0,0,0,0,0,0,0,0,0,0,0,0,0,0,0,0,0,0,0,0,0,0,0,0)';
      BIDIRECTIONAL='TRUE';
      INPUT_LOAD='(-0.01,0.01)';
      OUTPUT_LOAD='(1.0,-1.0)';
    'RSVD'<268>:
      PIN_NUMBER='(0,J62,0,0,0,0,0,0,0,0,0,0,0,0,0,0,0,0,0,0,0,0,0,0,0,0,0,0,0,0)';
      BIDIRECTIONAL='TRUE';
      INPUT_LOAD='(-0.01,0.01)';
      OUTPUT_LOAD='(1.0,-1.0)';
    'RSVD'<267>:
      PIN_NUMBER='(0,K61,0,0,0,0,0,0,0,0,0,0,0,0,0,0,0,0,0,0,0,0,0,0,0,0,0,0,0,0)';
      BIDIRECTIONAL='TRUE';
      INPUT_LOAD='(-0.01,0.01)';
      OUTPUT_LOAD='(1.0,-1.0)';
    'RSVD'<266>:
      PIN_NUMBER='(0,M63,0,0,0,0,0,0,0,0,0,0,0,0,0,0,0,0,0,0,0,0,0,0,0,0,0,0,0,0)';
      BIDIRECTIONAL='TRUE';
      INPUT_LOAD='(-0.01,0.01)';
      OUTPUT_LOAD='(1.0,-1.0)';
    'RSVD'<265>:
      PIN_NUMBER='(0,P65,0,0,0,0,0,0,0,0,0,0,0,0,0,0,0,0,0,0,0,0,0,0,0,0,0,0,0,0)';
      BIDIRECTIONAL='TRUE';
      INPUT_LOAD='(-0.01,0.01)';
      OUTPUT_LOAD='(1.0,-1.0)';
    'RSVD'<264>:
      PIN_NUMBER='(0,R62,0,0,0,0,0,0,0,0,0,0,0,0,0,0,0,0,0,0,0,0,0,0,0,0,0,0,0,0)';
      BIDIRECTIONAL='TRUE';
      INPUT_LOAD='(-0.01,0.01)';
      OUTPUT_LOAD='(1.0,-1.0)';
    'RSVD'<263>:
      PIN_NUMBER='(0,R66,0,0,0,0,0,0,0,0,0,0,0,0,0,0,0,0,0,0,0,0,0,0,0,0,0,0,0,0)';
      BIDIRECTIONAL='TRUE';
      INPUT_LOAD='(-0.01,0.01)';
      OUTPUT_LOAD='(1.0,-1.0)';
    'RSVD'<262>:
      PIN_NUMBER='(0,T67,0,0,0,0,0,0,0,0,0,0,0,0,0,0,0,0,0,0,0,0,0,0,0,0,0,0,0,0)';
      BIDIRECTIONAL='TRUE';
      INPUT_LOAD='(-0.01,0.01)';
      OUTPUT_LOAD='(1.0,-1.0)';
    'RSVD'<261>:
      PIN_NUMBER='(0,U66,0,0,0,0,0,0,0,0,0,0,0,0,0,0,0,0,0,0,0,0,0,0,0,0,0,0,0,0)';
      BIDIRECTIONAL='TRUE';
      INPUT_LOAD='(-0.01,0.01)';
      OUTPUT_LOAD='(1.0,-1.0)';
    'RSVD'<260>:
      PIN_NUMBER='(0,V65,0,0,0,0,0,0,0,0,0,0,0,0,0,0,0,0,0,0,0,0,0,0,0,0,0,0,0,0)';
      BIDIRECTIONAL='TRUE';
      INPUT_LOAD='(-0.01,0.01)';
      OUTPUT_LOAD='(1.0,-1.0)';
    'RSVD'<259>:
      PIN_NUMBER='(0,V67,0,0,0,0,0,0,0,0,0,0,0,0,0,0,0,0,0,0,0,0,0,0,0,0,0,0,0,0)';
      BIDIRECTIONAL='TRUE';
      INPUT_LOAD='(-0.01,0.01)';
      OUTPUT_LOAD='(1.0,-1.0)';
    'RSVD'<258>:
      PIN_NUMBER='(0,W66,0,0,0,0,0,0,0,0,0,0,0,0,0,0,0,0,0,0,0,0,0,0,0,0,0,0,0,0)';
      BIDIRECTIONAL='TRUE';
      INPUT_LOAD='(-0.01,0.01)';
      OUTPUT_LOAD='(1.0,-1.0)';
    'RSVD'<257>:
      PIN_NUMBER='(0,Y23,0,0,0,0,0,0,0,0,0,0,0,0,0,0,0,0,0,0,0,0,0,0,0,0,0,0,0,0)';
      BIDIRECTIONAL='TRUE';
      INPUT_LOAD='(-0.01,0.01)';
      OUTPUT_LOAD='(1.0,-1.0)';
    'RSVD'<256>:
      PIN_NUMBER='(0,Y65,0,0,0,0,0,0,0,0,0,0,0,0,0,0,0,0,0,0,0,0,0,0,0,0,0,0,0,0)';
      BIDIRECTIONAL='TRUE';
      INPUT_LOAD='(-0.01,0.01)';
      OUTPUT_LOAD='(1.0,-1.0)';
    'RSVD'<255>:
      PIN_NUMBER='(0,0,0,0,0,0,0,0,0,0,0,0,0,0,0,AY83,0,0,0,0,0,0,0,0,0,0,0,0,0,0)';
      BIDIRECTIONAL='TRUE';
      INPUT_LOAD='(-0.01,0.01)';
      OUTPUT_LOAD='(1.0,-1.0)';
    'RSVD'<254>:
      PIN_NUMBER='(0,AD47,0,0,0,0,0,0,0,0,0,0,0,0,0,0,0,0,0,0,0,0,0,0,0,0,0,0,0,0)';
      BIDIRECTIONAL='TRUE';
      INPUT_LOAD='(-0.01,0.01)';
      OUTPUT_LOAD='(1.0,-1.0)';
    'RSVD'<253>:
      PIN_NUMBER='(0,AD49,0,0,0,0,0,0,0,0,0,0,0,0,0,0,0,0,0,0,0,0,0,0,0,0,0,0,0,0)';
      BIDIRECTIONAL='TRUE';
      INPUT_LOAD='(-0.01,0.01)';
      OUTPUT_LOAD='(1.0,-1.0)';
    'RSVD'<252>:
      PIN_NUMBER='(0,AD51,0,0,0,0,0,0,0,0,0,0,0,0,0,0,0,0,0,0,0,0,0,0,0,0,0,0,0,0)';
      BIDIRECTIONAL='TRUE';
      INPUT_LOAD='(-0.01,0.01)';
      OUTPUT_LOAD='(1.0,-1.0)';
    'RSVD'<251>:
      PIN_NUMBER='(0,AE46,0,0,0,0,0,0,0,0,0,0,0,0,0,0,0,0,0,0,0,0,0,0,0,0,0,0,0,0)';
      BIDIRECTIONAL='TRUE';
      INPUT_LOAD='(-0.01,0.01)';
      OUTPUT_LOAD='(1.0,-1.0)';
    'RSVD'<250>:
      PIN_NUMBER='(0,AE48,0,0,0,0,0,0,0,0,0,0,0,0,0,0,0,0,0,0,0,0,0,0,0,0,0,0,0,0)';
      BIDIRECTIONAL='TRUE';
      INPUT_LOAD='(-0.01,0.01)';
      OUTPUT_LOAD='(1.0,-1.0)';
    'RSVD'<249>:
      PIN_NUMBER='(0,AE50,0,0,0,0,0,0,0,0,0,0,0,0,0,0,0,0,0,0,0,0,0,0,0,0,0,0,0,0)';
      BIDIRECTIONAL='TRUE';
      INPUT_LOAD='(-0.01,0.01)';
      OUTPUT_LOAD='(1.0,-1.0)';
    'RSVD'<248>:
      PIN_NUMBER='(0,AE52,0,0,0,0,0,0,0,0,0,0,0,0,0,0,0,0,0,0,0,0,0,0,0,0,0,0,0,0)';
      BIDIRECTIONAL='TRUE';
      INPUT_LOAD='(-0.01,0.01)';
      OUTPUT_LOAD='(1.0,-1.0)';
    'RSVD'<247>:
      PIN_NUMBER='(0,AE72,0,0,0,0,0,0,0,0,0,0,0,0,0,0,0,0,0,0,0,0,0,0,0,0,0,0,0,0)';
      BIDIRECTIONAL='TRUE';
      INPUT_LOAD='(-0.01,0.01)';
      OUTPUT_LOAD='(1.0,-1.0)';
    'RSVD'<246>:
      PIN_NUMBER='(0,AF19,0,0,0,0,0,0,0,0,0,0,0,0,0,0,0,0,0,0,0,0,0,0,0,0,0,0,0,0)';
      BIDIRECTIONAL='TRUE';
      INPUT_LOAD='(-0.01,0.01)';
      OUTPUT_LOAD='(1.0,-1.0)';
    'RSVD'<245>:
      PIN_NUMBER='(0,AF47,0,0,0,0,0,0,0,0,0,0,0,0,0,0,0,0,0,0,0,0,0,0,0,0,0,0,0,0)';
      BIDIRECTIONAL='TRUE';
      INPUT_LOAD='(-0.01,0.01)';
      OUTPUT_LOAD='(1.0,-1.0)';
    'RSVD'<244>:
      PIN_NUMBER='(0,AF49,0,0,0,0,0,0,0,0,0,0,0,0,0,0,0,0,0,0,0,0,0,0,0,0,0,0,0,0)';
      BIDIRECTIONAL='TRUE';
      INPUT_LOAD='(-0.01,0.01)';
      OUTPUT_LOAD='(1.0,-1.0)';
    'RSVD'<243>:
      PIN_NUMBER='(0,AF51,0,0,0,0,0,0,0,0,0,0,0,0,0,0,0,0,0,0,0,0,0,0,0,0,0,0,0,0)';
      BIDIRECTIONAL='TRUE';
      INPUT_LOAD='(-0.01,0.01)';
      OUTPUT_LOAD='(1.0,-1.0)';
    'RSVD'<242>:
      PIN_NUMBER='(0,AF53,0,0,0,0,0,0,0,0,0,0,0,0,0,0,0,0,0,0,0,0,0,0,0,0,0,0,0,0)';
      BIDIRECTIONAL='TRUE';
      INPUT_LOAD='(-0.01,0.01)';
      OUTPUT_LOAD='(1.0,-1.0)';
    'RSVD'<241>:
      PIN_NUMBER='(0,AF71,0,0,0,0,0,0,0,0,0,0,0,0,0,0,0,0,0,0,0,0,0,0,0,0,0,0,0,0)';
      BIDIRECTIONAL='TRUE';
      INPUT_LOAD='(-0.01,0.01)';
      OUTPUT_LOAD='(1.0,-1.0)';
    'RSVD'<240>:
      PIN_NUMBER='(0,AG20,0,0,0,0,0,0,0,0,0,0,0,0,0,0,0,0,0,0,0,0,0,0,0,0,0,0,0,0)';
      BIDIRECTIONAL='TRUE';
      INPUT_LOAD='(-0.01,0.01)';
      OUTPUT_LOAD='(1.0,-1.0)';
    'RSVD'<239>:
      PIN_NUMBER='(0,AG48,0,0,0,0,0,0,0,0,0,0,0,0,0,0,0,0,0,0,0,0,0,0,0,0,0,0,0,0)';
      BIDIRECTIONAL='TRUE';
      INPUT_LOAD='(-0.01,0.01)';
      OUTPUT_LOAD='(1.0,-1.0)';
    'RSVD'<238>:
      PIN_NUMBER='(0,AG50,0,0,0,0,0,0,0,0,0,0,0,0,0,0,0,0,0,0,0,0,0,0,0,0,0,0,0,0)';
      BIDIRECTIONAL='TRUE';
      INPUT_LOAD='(-0.01,0.01)';
      OUTPUT_LOAD='(1.0,-1.0)';
    'RSVD'<237>:
      PIN_NUMBER='(0,AG52,0,0,0,0,0,0,0,0,0,0,0,0,0,0,0,0,0,0,0,0,0,0,0,0,0,0,0,0)';
      BIDIRECTIONAL='TRUE';
      INPUT_LOAD='(-0.01,0.01)';
      OUTPUT_LOAD='(1.0,-1.0)';
    'RSVD'<236>:
      PIN_NUMBER='(0,AG54,0,0,0,0,0,0,0,0,0,0,0,0,0,0,0,0,0,0,0,0,0,0,0,0,0,0,0,0)';
      BIDIRECTIONAL='TRUE';
      INPUT_LOAD='(-0.01,0.01)';
      OUTPUT_LOAD='(1.0,-1.0)';
    'RSVD'<235>:
      PIN_NUMBER='(0,AG56,0,0,0,0,0,0,0,0,0,0,0,0,0,0,0,0,0,0,0,0,0,0,0,0,0,0,0,0)';
      BIDIRECTIONAL='TRUE';
      INPUT_LOAD='(-0.01,0.01)';
      OUTPUT_LOAD='(1.0,-1.0)';
    'RSVD'<234>:
      PIN_NUMBER='(0,AG72,0,0,0,0,0,0,0,0,0,0,0,0,0,0,0,0,0,0,0,0,0,0,0,0,0,0,0,0)';
      BIDIRECTIONAL='TRUE';
      INPUT_LOAD='(-0.01,0.01)';
      OUTPUT_LOAD='(1.0,-1.0)';
    'RSVD'<233>:
      PIN_NUMBER='(0,AH15,0,0,0,0,0,0,0,0,0,0,0,0,0,0,0,0,0,0,0,0,0,0,0,0,0,0,0,0)';
      BIDIRECTIONAL='TRUE';
      INPUT_LOAD='(-0.01,0.01)';
      OUTPUT_LOAD='(1.0,-1.0)';
    'RSVD'<232>:
      PIN_NUMBER='(0,AH19,0,0,0,0,0,0,0,0,0,0,0,0,0,0,0,0,0,0,0,0,0,0,0,0,0,0,0,0)';
      BIDIRECTIONAL='TRUE';
      INPUT_LOAD='(-0.01,0.01)';
      OUTPUT_LOAD='(1.0,-1.0)';
    'RSVD'<231>:
      PIN_NUMBER='(0,AH55,0,0,0,0,0,0,0,0,0,0,0,0,0,0,0,0,0,0,0,0,0,0,0,0,0,0,0,0)';
      BIDIRECTIONAL='TRUE';
      INPUT_LOAD='(-0.01,0.01)';
      OUTPUT_LOAD='(1.0,-1.0)';
    'RSVD'<230>:
      PIN_NUMBER='(0,AH57,0,0,0,0,0,0,0,0,0,0,0,0,0,0,0,0,0,0,0,0,0,0,0,0,0,0,0,0)';
      BIDIRECTIONAL='TRUE';
      INPUT_LOAD='(-0.01,0.01)';
      OUTPUT_LOAD='(1.0,-1.0)';
    'RSVD'<229>:
      PIN_NUMBER='(0,AH71,0,0,0,0,0,0,0,0,0,0,0,0,0,0,0,0,0,0,0,0,0,0,0,0,0,0,0,0)';
      BIDIRECTIONAL='TRUE';
      INPUT_LOAD='(-0.01,0.01)';
      OUTPUT_LOAD='(1.0,-1.0)';
    'RSVD'<228>:
      PIN_NUMBER='(0,AH73,0,0,0,0,0,0,0,0,0,0,0,0,0,0,0,0,0,0,0,0,0,0,0,0,0,0,0,0)';
      BIDIRECTIONAL='TRUE';
      INPUT_LOAD='(-0.01,0.01)';
      OUTPUT_LOAD='(1.0,-1.0)';
    'RSVD'<227>:
      PIN_NUMBER='(0,AJ20,0,0,0,0,0,0,0,0,0,0,0,0,0,0,0,0,0,0,0,0,0,0,0,0,0,0,0,0)';
      BIDIRECTIONAL='TRUE';
      INPUT_LOAD='(-0.01,0.01)';
      OUTPUT_LOAD='(1.0,-1.0)';
    'RSVD'<226>:
      PIN_NUMBER='(0,AJ56,0,0,0,0,0,0,0,0,0,0,0,0,0,0,0,0,0,0,0,0,0,0,0,0,0,0,0,0)';
      BIDIRECTIONAL='TRUE';
      INPUT_LOAD='(-0.01,0.01)';
      OUTPUT_LOAD='(1.0,-1.0)';
    'RSVD'<225>:
      PIN_NUMBER='(0,AJ58,0,0,0,0,0,0,0,0,0,0,0,0,0,0,0,0,0,0,0,0,0,0,0,0,0,0,0,0)';
      BIDIRECTIONAL='TRUE';
      INPUT_LOAD='(-0.01,0.01)';
      OUTPUT_LOAD='(1.0,-1.0)';
    'RSVD'<224>:
      PIN_NUMBER='(0,AJ60,0,0,0,0,0,0,0,0,0,0,0,0,0,0,0,0,0,0,0,0,0,0,0,0,0,0,0,0)';
      BIDIRECTIONAL='TRUE';
      INPUT_LOAD='(-0.01,0.01)';
      OUTPUT_LOAD='(1.0,-1.0)';
    'RSVD'<223>:
      PIN_NUMBER='(0,AJ62,0,0,0,0,0,0,0,0,0,0,0,0,0,0,0,0,0,0,0,0,0,0,0,0,0,0,0,0)';
      BIDIRECTIONAL='TRUE';
      INPUT_LOAD='(-0.01,0.01)';
      OUTPUT_LOAD='(1.0,-1.0)';
    'RSVD'<222>:
      PIN_NUMBER='(0,AJ70,0,0,0,0,0,0,0,0,0,0,0,0,0,0,0,0,0,0,0,0,0,0,0,0,0,0,0,0)';
      BIDIRECTIONAL='TRUE';
      INPUT_LOAD='(-0.01,0.01)';
      OUTPUT_LOAD='(1.0,-1.0)';
    'RSVD'<221>:
      PIN_NUMBER='(0,AK21,0,0,0,0,0,0,0,0,0,0,0,0,0,0,0,0,0,0,0,0,0,0,0,0,0,0,0,0)';
      BIDIRECTIONAL='TRUE';
      INPUT_LOAD='(-0.01,0.01)';
      OUTPUT_LOAD='(1.0,-1.0)';
    'RSVD'<220>:
      PIN_NUMBER='(0,AK27,0,0,0,0,0,0,0,0,0,0,0,0,0,0,0,0,0,0,0,0,0,0,0,0,0,0,0,0)';
      BIDIRECTIONAL='TRUE';
      INPUT_LOAD='(-0.01,0.01)';
      OUTPUT_LOAD='(1.0,-1.0)';
    'RSVD'<219>:
      PIN_NUMBER='(0,AK57,0,0,0,0,0,0,0,0,0,0,0,0,0,0,0,0,0,0,0,0,0,0,0,0,0,0,0,0)';
      BIDIRECTIONAL='TRUE';
      INPUT_LOAD='(-0.01,0.01)';
      OUTPUT_LOAD='(1.0,-1.0)';
    'RSVD'<218>:
      PIN_NUMBER='(0,AK59,0,0,0,0,0,0,0,0,0,0,0,0,0,0,0,0,0,0,0,0,0,0,0,0,0,0,0,0)';
      BIDIRECTIONAL='TRUE';
      INPUT_LOAD='(-0.01,0.01)';
      OUTPUT_LOAD='(1.0,-1.0)';
    'RSVD'<217>:
      PIN_NUMBER='(0,AK61,0,0,0,0,0,0,0,0,0,0,0,0,0,0,0,0,0,0,0,0,0,0,0,0,0,0,0,0)';
      BIDIRECTIONAL='TRUE';
      INPUT_LOAD='(-0.01,0.01)';
      OUTPUT_LOAD='(1.0,-1.0)';
    'RSVD'<216>:
      PIN_NUMBER='(0,AK69,0,0,0,0,0,0,0,0,0,0,0,0,0,0,0,0,0,0,0,0,0,0,0,0,0,0,0,0)';
      BIDIRECTIONAL='TRUE';
      INPUT_LOAD='(-0.01,0.01)';
      OUTPUT_LOAD='(1.0,-1.0)';
    'RSVD'<215>:
      PIN_NUMBER='(0,AL20,0,0,0,0,0,0,0,0,0,0,0,0,0,0,0,0,0,0,0,0,0,0,0,0,0,0,0,0)';
      BIDIRECTIONAL='TRUE';
      INPUT_LOAD='(-0.01,0.01)';
      OUTPUT_LOAD='(1.0,-1.0)';
    'RSVD'<214>:
      PIN_NUMBER='(0,AL22,0,0,0,0,0,0,0,0,0,0,0,0,0,0,0,0,0,0,0,0,0,0,0,0,0,0,0,0)';
      BIDIRECTIONAL='TRUE';
      INPUT_LOAD='(-0.01,0.01)';
      OUTPUT_LOAD='(1.0,-1.0)';
    'RSVD'<213>:
      PIN_NUMBER='(0,AL26,0,0,0,0,0,0,0,0,0,0,0,0,0,0,0,0,0,0,0,0,0,0,0,0,0,0,0,0)';
      BIDIRECTIONAL='TRUE';
      INPUT_LOAD='(-0.01,0.01)';
      OUTPUT_LOAD='(1.0,-1.0)';
    'RSVD'<212>:
      PIN_NUMBER='(0,AL58,0,0,0,0,0,0,0,0,0,0,0,0,0,0,0,0,0,0,0,0,0,0,0,0,0,0,0,0)';
      BIDIRECTIONAL='TRUE';
      INPUT_LOAD='(-0.01,0.01)';
      OUTPUT_LOAD='(1.0,-1.0)';
    'RSVD'<211>:
      PIN_NUMBER='(0,AL60,0,0,0,0,0,0,0,0,0,0,0,0,0,0,0,0,0,0,0,0,0,0,0,0,0,0,0,0)';
      BIDIRECTIONAL='TRUE';
      INPUT_LOAD='(-0.01,0.01)';
      OUTPUT_LOAD='(1.0,-1.0)';
    'RSVD'<210>:
      PIN_NUMBER='(0,AL62,0,0,0,0,0,0,0,0,0,0,0,0,0,0,0,0,0,0,0,0,0,0,0,0,0,0,0,0)';
      BIDIRECTIONAL='TRUE';
      INPUT_LOAD='(-0.01,0.01)';
      OUTPUT_LOAD='(1.0,-1.0)';
    'RSVD'<209>:
      PIN_NUMBER='(0,AM21,0,0,0,0,0,0,0,0,0,0,0,0,0,0,0,0,0,0,0,0,0,0,0,0,0,0,0,0)';
      BIDIRECTIONAL='TRUE';
      INPUT_LOAD='(-0.01,0.01)';
      OUTPUT_LOAD='(1.0,-1.0)';
    'RSVD'<208>:
      PIN_NUMBER='(0,AM23,0,0,0,0,0,0,0,0,0,0,0,0,0,0,0,0,0,0,0,0,0,0,0,0,0,0,0,0)';
      BIDIRECTIONAL='TRUE';
      INPUT_LOAD='(-0.01,0.01)';
      OUTPUT_LOAD='(1.0,-1.0)';
    'RSVD'<207>:
      PIN_NUMBER='(0,AM25,0,0,0,0,0,0,0,0,0,0,0,0,0,0,0,0,0,0,0,0,0,0,0,0,0,0,0,0)';
      BIDIRECTIONAL='TRUE';
      INPUT_LOAD='(-0.01,0.01)';
      OUTPUT_LOAD='(1.0,-1.0)';
    'RSVD'<206>:
      PIN_NUMBER='(0,AM27,0,0,0,0,0,0,0,0,0,0,0,0,0,0,0,0,0,0,0,0,0,0,0,0,0,0,0,0)';
      BIDIRECTIONAL='TRUE';
      INPUT_LOAD='(-0.01,0.01)';
      OUTPUT_LOAD='(1.0,-1.0)';
    'RSVD'<205>:
      PIN_NUMBER='(0,AM59,0,0,0,0,0,0,0,0,0,0,0,0,0,0,0,0,0,0,0,0,0,0,0,0,0,0,0,0)';
      BIDIRECTIONAL='TRUE';
      INPUT_LOAD='(-0.01,0.01)';
      OUTPUT_LOAD='(1.0,-1.0)';
    'RSVD'<204>:
      PIN_NUMBER='(0,AM61,0,0,0,0,0,0,0,0,0,0,0,0,0,0,0,0,0,0,0,0,0,0,0,0,0,0,0,0)';
      BIDIRECTIONAL='TRUE';
      INPUT_LOAD='(-0.01,0.01)';
      OUTPUT_LOAD='(1.0,-1.0)';
    'RSVD'<203>:
      PIN_NUMBER='(0,AN18,0,0,0,0,0,0,0,0,0,0,0,0,0,0,0,0,0,0,0,0,0,0,0,0,0,0,0,0)';
      BIDIRECTIONAL='TRUE';
      INPUT_LOAD='(-0.01,0.01)';
      OUTPUT_LOAD='(1.0,-1.0)';
    'RSVD'<202>:
      PIN_NUMBER='(0,AN22,0,0,0,0,0,0,0,0,0,0,0,0,0,0,0,0,0,0,0,0,0,0,0,0,0,0,0,0)';
      BIDIRECTIONAL='TRUE';
      INPUT_LOAD='(-0.01,0.01)';
      OUTPUT_LOAD='(1.0,-1.0)';
    'RSVD'<201>:
      PIN_NUMBER='(0,AN24,0,0,0,0,0,0,0,0,0,0,0,0,0,0,0,0,0,0,0,0,0,0,0,0,0,0,0,0)';
      BIDIRECTIONAL='TRUE';
      INPUT_LOAD='(-0.01,0.01)';
      OUTPUT_LOAD='(1.0,-1.0)';
    'RSVD'<200>:
      PIN_NUMBER='(0,AN26,0,0,0,0,0,0,0,0,0,0,0,0,0,0,0,0,0,0,0,0,0,0,0,0,0,0,0,0)';
      BIDIRECTIONAL='TRUE';
      INPUT_LOAD='(-0.01,0.01)';
      OUTPUT_LOAD='(1.0,-1.0)';
    'RSVD'<199>:
      PIN_NUMBER='(0,AN60,0,0,0,0,0,0,0,0,0,0,0,0,0,0,0,0,0,0,0,0,0,0,0,0,0,0,0,0)';
      BIDIRECTIONAL='TRUE';
      INPUT_LOAD='(-0.01,0.01)';
      OUTPUT_LOAD='(1.0,-1.0)';
    'RSVD'<198>:
      PIN_NUMBER='(0,AN62,0,0,0,0,0,0,0,0,0,0,0,0,0,0,0,0,0,0,0,0,0,0,0,0,0,0,0,0)';
      BIDIRECTIONAL='TRUE';
      INPUT_LOAD='(-0.01,0.01)';
      OUTPUT_LOAD='(1.0,-1.0)';
    'RSVD'<197>:
      PIN_NUMBER='(0,AP23,0,0,0,0,0,0,0,0,0,0,0,0,0,0,0,0,0,0,0,0,0,0,0,0,0,0,0,0)';
      BIDIRECTIONAL='TRUE';
      INPUT_LOAD='(-0.01,0.01)';
      OUTPUT_LOAD='(1.0,-1.0)';
    'RSVD'<196>:
      PIN_NUMBER='(0,AP25,0,0,0,0,0,0,0,0,0,0,0,0,0,0,0,0,0,0,0,0,0,0,0,0,0,0,0,0)';
      BIDIRECTIONAL='TRUE';
      INPUT_LOAD='(-0.01,0.01)';
      OUTPUT_LOAD='(1.0,-1.0)';
    'RSVD'<195>:
      PIN_NUMBER='(0,AP27,0,0,0,0,0,0,0,0,0,0,0,0,0,0,0,0,0,0,0,0,0,0,0,0,0,0,0,0)';
      BIDIRECTIONAL='TRUE';
      INPUT_LOAD='(-0.01,0.01)';
      OUTPUT_LOAD='(1.0,-1.0)';
    'RSVD'<194>:
      PIN_NUMBER='(0,AP61,0,0,0,0,0,0,0,0,0,0,0,0,0,0,0,0,0,0,0,0,0,0,0,0,0,0,0,0)';
      BIDIRECTIONAL='TRUE';
      INPUT_LOAD='(-0.01,0.01)';
      OUTPUT_LOAD='(1.0,-1.0)';
    'RSVD'<193>:
      PIN_NUMBER='(0,0,0,0,0,0,0,0,AR20,0,0,0,0,0,0,0,0,0,0,0,0,0,0,0,0,0,0,0,0,0)';
      BIDIRECTIONAL='TRUE';
      INPUT_LOAD='(-0.01,0.01)';
      OUTPUT_LOAD='(1.0,-1.0)';
    'RSVD'<192>:
      PIN_NUMBER='(0,0,0,0,0,0,0,0,AR22,0,0,0,0,0,0,0,0,0,0,0,0,0,0,0,0,0,0,0,0,0)';
      BIDIRECTIONAL='TRUE';
      INPUT_LOAD='(-0.01,0.01)';
      OUTPUT_LOAD='(1.0,-1.0)';
    'RSVD'<191>:
      PIN_NUMBER='(0,0,0,0,0,0,0,0,AR26,0,0,0,0,0,0,0,0,0,0,0,0,0,0,0,0,0,0,0,0,0)';
      BIDIRECTIONAL='TRUE';
      INPUT_LOAD='(-0.01,0.01)';
      OUTPUT_LOAD='(1.0,-1.0)';
    'RSVD'<190>:
      PIN_NUMBER='(0,0,0,0,0,0,0,0,AR62,0,0,0,0,0,0,0,0,0,0,0,0,0,0,0,0,0,0,0,0,0)';
      BIDIRECTIONAL='TRUE';
      INPUT_LOAD='(-0.01,0.01)';
      OUTPUT_LOAD='(1.0,-1.0)';
    'RSVD'<189>:
      PIN_NUMBER='(0,0,0,0,0,0,0,0,AT13,0,0,0,0,0,0,0,0,0,0,0,0,0,0,0,0,0,0,0,0,0)';
      BIDIRECTIONAL='TRUE';
      INPUT_LOAD='(-0.01,0.01)';
      OUTPUT_LOAD='(1.0,-1.0)';
    'RSVD'<188>:
      PIN_NUMBER='(0,0,0,0,0,0,0,0,AT23,0,0,0,0,0,0,0,0,0,0,0,0,0,0,0,0,0,0,0,0,0)';
      BIDIRECTIONAL='TRUE';
      INPUT_LOAD='(-0.01,0.01)';
      OUTPUT_LOAD='(1.0,-1.0)';
    'RSVD'<187>:
      PIN_NUMBER='(0,0,0,0,0,0,0,0,AT25,0,0,0,0,0,0,0,0,0,0,0,0,0,0,0,0,0,0,0,0,0)';
      BIDIRECTIONAL='TRUE';
      INPUT_LOAD='(-0.01,0.01)';
      OUTPUT_LOAD='(1.0,-1.0)';
    'RSVD'<186>:
      PIN_NUMBER='(0,0,0,0,0,0,0,0,AV77,0,0,0,0,0,0,0,0,0,0,0,0,0,0,0,0,0,0,0,0,0)';
      BIDIRECTIONAL='TRUE';
      INPUT_LOAD='(-0.01,0.01)';
      OUTPUT_LOAD='(1.0,-1.0)';
    'RSVD'<184>:
      PIN_NUMBER='(0,0,0,0,0,0,0,0,AW64,0,0,0,0,0,0,0,0,0,0,0,0,0,0,0,0,0,0,0,0,0)';
      BIDIRECTIONAL='TRUE';
      INPUT_LOAD='(-0.01,0.01)';
      OUTPUT_LOAD='(1.0,-1.0)';
    'RSVD'<183>:
      PIN_NUMBER='(0,0,0,0,0,0,0,0,AW76,0,0,0,0,0,0,0,0,0,0,0,0,0,0,0,0,0,0,0,0,0)';
      BIDIRECTIONAL='TRUE';
      INPUT_LOAD='(-0.01,0.01)';
      OUTPUT_LOAD='(1.0,-1.0)';
    'RSVD'<182>:
      PIN_NUMBER='(0,0,0,0,0,0,0,0,AY65,0,0,0,0,0,0,0,0,0,0,0,0,0,0,0,0,0,0,0,0,0)';
      BIDIRECTIONAL='TRUE';
      INPUT_LOAD='(-0.01,0.01)';
      OUTPUT_LOAD='(1.0,-1.0)';
    'RSVD'<181>:
      PIN_NUMBER='(0,0,0,0,0,0,0,0,AY67,0,0,0,0,0,0,0,0,0,0,0,0,0,0,0,0,0,0,0,0,0)';
      BIDIRECTIONAL='TRUE';
      INPUT_LOAD='(-0.01,0.01)';
      OUTPUT_LOAD='(1.0,-1.0)';
    'RSVD'<180>:
      PIN_NUMBER='(0,0,0,0,0,0,0,0,AY75,0,0,0,0,0,0,0,0,0,0,0,0,0,0,0,0,0,0,0,0,0)';
      BIDIRECTIONAL='TRUE';
      INPUT_LOAD='(-0.01,0.01)';
      OUTPUT_LOAD='(1.0,-1.0)';
    'RSVD'<179>:
      PIN_NUMBER='(0,0,0,0,0,0,0,0,AY77,0,0,0,0,0,0,0,0,0,0,0,0,0,0,0,0,0,0,0,0,0)';
      BIDIRECTIONAL='TRUE';
      INPUT_LOAD='(-0.01,0.01)';
      OUTPUT_LOAD='(1.0,-1.0)';
    'RSVD'<178>:
      PIN_NUMBER='(0,0,0,0,0,0,0,0,BA14,0,0,0,0,0,0,0,0,0,0,0,0,0,0,0,0,0,0,0,0,0)';
      BIDIRECTIONAL='TRUE';
      INPUT_LOAD='(-0.01,0.01)';
      OUTPUT_LOAD='(1.0,-1.0)';
    'RSVD'<177>:
      PIN_NUMBER='(0,0,0,0,0,0,0,0,BA16,0,0,0,0,0,0,0,0,0,0,0,0,0,0,0,0,0,0,0,0,0)';
      BIDIRECTIONAL='TRUE';
      INPUT_LOAD='(-0.01,0.01)';
      OUTPUT_LOAD='(1.0,-1.0)';
    'RSVD'<176>:
      PIN_NUMBER='(0,0,0,0,0,0,0,0,BA18,0,0,0,0,0,0,0,0,0,0,0,0,0,0,0,0,0,0,0,0,0)';
      BIDIRECTIONAL='TRUE';
      INPUT_LOAD='(-0.01,0.01)';
      OUTPUT_LOAD='(1.0,-1.0)';
    'RSVD'<175>:
      PIN_NUMBER='(0,0,0,0,0,0,0,0,BA22,0,0,0,0,0,0,0,0,0,0,0,0,0,0,0,0,0,0,0,0,0)';
      BIDIRECTIONAL='TRUE';
      INPUT_LOAD='(-0.01,0.01)';
      OUTPUT_LOAD='(1.0,-1.0)';
    'RSVD'<174>:
      PIN_NUMBER='(0,0,0,0,0,0,0,0,BA64,0,0,0,0,0,0,0,0,0,0,0,0,0,0,0,0,0,0,0,0,0)';
      BIDIRECTIONAL='TRUE';
      INPUT_LOAD='(-0.01,0.01)';
      OUTPUT_LOAD='(1.0,-1.0)';
    'RSVD'<173>:
      PIN_NUMBER='(0,0,0,0,0,0,0,0,BA66,0,0,0,0,0,0,0,0,0,0,0,0,0,0,0,0,0,0,0,0,0)';
      BIDIRECTIONAL='TRUE';
      INPUT_LOAD='(-0.01,0.01)';
      OUTPUT_LOAD='(1.0,-1.0)';
    'RSVD'<172>:
      PIN_NUMBER='(0,0,0,0,0,0,0,0,BA76,0,0,0,0,0,0,0,0,0,0,0,0,0,0,0,0,0,0,0,0,0)';
      BIDIRECTIONAL='TRUE';
      INPUT_LOAD='(-0.01,0.01)';
      OUTPUT_LOAD='(1.0,-1.0)';
    'RSVD'<171>:
      PIN_NUMBER='(0,0,0,0,0,0,0,0,0,0,0,0,0,0,0,BA78,0,0,0,0,0,0,0,0,0,0,0,0,0,0)';
      BIDIRECTIONAL='TRUE';
      INPUT_LOAD='(-0.01,0.01)';
      OUTPUT_LOAD='(1.0,-1.0)';
    'RSVD'<170>:
      PIN_NUMBER='(0,0,0,0,0,0,0,0,0,0,0,0,0,0,0,BA82,0,0,0,0,0,0,0,0,0,0,0,0,0,0)';
      BIDIRECTIONAL='TRUE';
      INPUT_LOAD='(-0.01,0.01)';
      OUTPUT_LOAD='(1.0,-1.0)';
    'RSVD'<169>:
      PIN_NUMBER='(0,0,0,0,0,0,0,0,0,0,0,0,0,0,0,BB13,0,0,0,0,0,0,0,0,0,0,0,0,0,0)';
      BIDIRECTIONAL='TRUE';
      INPUT_LOAD='(-0.01,0.01)';
      OUTPUT_LOAD='(1.0,-1.0)';
    'RSVD'<168>:
      PIN_NUMBER='(0,0,0,0,0,0,0,0,0,0,0,0,0,0,0,BB15,0,0,0,0,0,0,0,0,0,0,0,0,0,0)';
      BIDIRECTIONAL='TRUE';
      INPUT_LOAD='(-0.01,0.01)';
      OUTPUT_LOAD='(1.0,-1.0)';
    'RSVD'<167>:
      PIN_NUMBER='(0,0,0,0,0,0,0,0,0,0,0,0,0,0,0,BB17,0,0,0,0,0,0,0,0,0,0,0,0,0,0)';
      BIDIRECTIONAL='TRUE';
      INPUT_LOAD='(-0.01,0.01)';
      OUTPUT_LOAD='(1.0,-1.0)';
    'RSVD'<166>:
      PIN_NUMBER='(0,0,0,0,0,0,0,0,0,0,0,0,0,0,0,BB21,0,0,0,0,0,0,0,0,0,0,0,0,0,0)';
      BIDIRECTIONAL='TRUE';
      INPUT_LOAD='(-0.01,0.01)';
      OUTPUT_LOAD='(1.0,-1.0)';
    'RSVD'<165>:
      PIN_NUMBER='(0,0,0,0,0,0,0,0,0,0,0,0,0,0,0,BB25,0,0,0,0,0,0,0,0,0,0,0,0,0,0)';
      BIDIRECTIONAL='TRUE';
      INPUT_LOAD='(-0.01,0.01)';
      OUTPUT_LOAD='(1.0,-1.0)';
    'RSVD'<164>:
      PIN_NUMBER='(0,0,0,0,0,0,0,0,0,0,0,0,0,0,0,BB65,0,0,0,0,0,0,0,0,0,0,0,0,0,0)';
      BIDIRECTIONAL='TRUE';
      INPUT_LOAD='(-0.01,0.01)';
      OUTPUT_LOAD='(1.0,-1.0)';
    'RSVD'<163>:
      PIN_NUMBER='(0,0,0,0,0,0,0,0,0,0,0,0,0,0,0,BB67,0,0,0,0,0,0,0,0,0,0,0,0,0,0)';
      BIDIRECTIONAL='TRUE';
      INPUT_LOAD='(-0.01,0.01)';
      OUTPUT_LOAD='(1.0,-1.0)';
    'RSVD'<162>:
      PIN_NUMBER='(0,0,0,0,0,0,0,0,0,0,0,0,0,0,0,BC14,0,0,0,0,0,0,0,0,0,0,0,0,0,0)';
      BIDIRECTIONAL='TRUE';
      INPUT_LOAD='(-0.01,0.01)';
      OUTPUT_LOAD='(1.0,-1.0)';
    'RSVD'<161>:
      PIN_NUMBER='(0,0,0,0,0,0,0,0,0,0,0,0,0,0,0,BC18,0,0,0,0,0,0,0,0,0,0,0,0,0,0)';
      BIDIRECTIONAL='TRUE';
      INPUT_LOAD='(-0.01,0.01)';
      OUTPUT_LOAD='(1.0,-1.0)';
    'RSVD'<160>:
      PIN_NUMBER='(0,0,0,0,0,0,0,0,0,0,0,0,0,0,0,BC20,0,0,0,0,0,0,0,0,0,0,0,0,0,0)';
      BIDIRECTIONAL='TRUE';
      INPUT_LOAD='(-0.01,0.01)';
      OUTPUT_LOAD='(1.0,-1.0)';
    'RSVD'<159>:
      PIN_NUMBER='(0,0,0,0,0,0,0,0,0,0,0,0,0,0,0,BC22,0,0,0,0,0,0,0,0,0,0,0,0,0,0)';
      BIDIRECTIONAL='TRUE';
      INPUT_LOAD='(-0.01,0.01)';
      OUTPUT_LOAD='(1.0,-1.0)';
    'RSVD'<158>:
      PIN_NUMBER='(0,0,0,0,0,0,0,0,0,0,0,0,0,0,0,BC64,0,0,0,0,0,0,0,0,0,0,0,0,0,0)';
      BIDIRECTIONAL='TRUE';
      INPUT_LOAD='(-0.01,0.01)';
      OUTPUT_LOAD='(1.0,-1.0)';
    'RSVD'<157>:
      PIN_NUMBER='(0,0,0,0,0,0,0,0,0,0,0,0,0,0,0,BC66,0,0,0,0,0,0,0,0,0,0,0,0,0,0)';
      BIDIRECTIONAL='TRUE';
      INPUT_LOAD='(-0.01,0.01)';
      OUTPUT_LOAD='(1.0,-1.0)';
    'RSVD'<156>:
      PIN_NUMBER='(0,0,0,0,0,0,0,0,0,0,0,0,0,0,0,BC68,0,0,0,0,0,0,0,0,0,0,0,0,0,0)';
      BIDIRECTIONAL='TRUE';
      INPUT_LOAD='(-0.01,0.01)';
      OUTPUT_LOAD='(1.0,-1.0)';
    'RSVD'<155>:
      PIN_NUMBER='(0,0,0,0,0,0,0,0,0,0,0,0,0,0,0,BD17,0,0,0,0,0,0,0,0,0,0,0,0,0,0)';
      BIDIRECTIONAL='TRUE';
      INPUT_LOAD='(-0.01,0.01)';
      OUTPUT_LOAD='(1.0,-1.0)';
    'RSVD'<154>:
      PIN_NUMBER='(0,0,0,0,0,0,0,0,0,0,0,0,0,0,0,BD19,0,0,0,0,0,0,0,0,0,0,0,0,0,0)';
      BIDIRECTIONAL='TRUE';
      INPUT_LOAD='(-0.01,0.01)';
      OUTPUT_LOAD='(1.0,-1.0)';
    'RSVD'<153>:
      PIN_NUMBER='(0,0,0,0,0,0,0,0,0,0,0,0,0,0,0,BD25,0,0,0,0,0,0,0,0,0,0,0,0,0,0)';
      BIDIRECTIONAL='TRUE';
      INPUT_LOAD='(-0.01,0.01)';
      OUTPUT_LOAD='(1.0,-1.0)';
    'RSVD'<152>:
      PIN_NUMBER='(0,0,0,0,0,0,0,0,0,0,0,0,0,0,0,BD65,0,0,0,0,0,0,0,0,0,0,0,0,0,0)';
      BIDIRECTIONAL='TRUE';
      INPUT_LOAD='(-0.01,0.01)';
      OUTPUT_LOAD='(1.0,-1.0)';
    'RSVD'<151>:
      PIN_NUMBER='(0,0,0,0,0,0,0,0,0,0,0,0,0,0,0,BD67,0,0,0,0,0,0,0,0,0,0,0,0,0,0)';
      BIDIRECTIONAL='TRUE';
      INPUT_LOAD='(-0.01,0.01)';
      OUTPUT_LOAD='(1.0,-1.0)';
    'RSVD'<150>:
      PIN_NUMBER='(0,0,0,0,0,0,0,0,0,0,0,0,0,0,0,BD69,0,0,0,0,0,0,0,0,0,0,0,0,0,0)';
      BIDIRECTIONAL='TRUE';
      INPUT_LOAD='(-0.01,0.01)';
      OUTPUT_LOAD='(1.0,-1.0)';
    'RSVD'<149>:
      PIN_NUMBER='(0,0,0,0,0,0,0,0,0,0,0,0,0,0,0,BE18,0,0,0,0,0,0,0,0,0,0,0,0,0,0)';
      BIDIRECTIONAL='TRUE';
      INPUT_LOAD='(-0.01,0.01)';
      OUTPUT_LOAD='(1.0,-1.0)';
    'RSVD'<148>:
      PIN_NUMBER='(0,0,0,0,0,0,0,0,0,0,0,0,0,0,0,BE20,0,0,0,0,0,0,0,0,0,0,0,0,0,0)';
      BIDIRECTIONAL='TRUE';
      INPUT_LOAD='(-0.01,0.01)';
      OUTPUT_LOAD='(1.0,-1.0)';
    'RSVD'<147>:
      PIN_NUMBER='(0,0,0,0,0,0,0,0,0,0,0,0,0,0,0,BE22,0,0,0,0,0,0,0,0,0,0,0,0,0,0)';
      BIDIRECTIONAL='TRUE';
      INPUT_LOAD='(-0.01,0.01)';
      OUTPUT_LOAD='(1.0,-1.0)';
    'RSVD'<146>:
      PIN_NUMBER='(0,0,0,0,0,0,0,0,0,0,0,0,0,0,0,BF21,0,0,0,0,0,0,0,0,0,0,0,0,0,0)';
      BIDIRECTIONAL='TRUE';
      INPUT_LOAD='(-0.01,0.01)';
      OUTPUT_LOAD='(1.0,-1.0)';
    'RSVD'<145>:
      PIN_NUMBER='(0,0,0,0,0,0,0,0,0,0,0,0,0,0,0,BG18,0,0,0,0,0,0,0,0,0,0,0,0,0,0)';
      BIDIRECTIONAL='TRUE';
      INPUT_LOAD='(-0.01,0.01)';
      OUTPUT_LOAD='(1.0,-1.0)';
    'RSVD'<144>:
      PIN_NUMBER='(0,0,0,0,0,0,0,0,0,0,0,0,0,0,0,BG20,0,0,0,0,0,0,0,0,0,0,0,0,0,0)';
      BIDIRECTIONAL='TRUE';
      INPUT_LOAD='(-0.01,0.01)';
      OUTPUT_LOAD='(1.0,-1.0)';
    'RSVD'<143>:
      PIN_NUMBER='(0,0,0,0,0,0,0,0,0,0,0,0,0,0,0,BH19,0,0,0,0,0,0,0,0,0,0,0,0,0,0)';
      BIDIRECTIONAL='TRUE';
      INPUT_LOAD='(-0.01,0.01)';
      OUTPUT_LOAD='(1.0,-1.0)';
    'RSVD'<142>:
      PIN_NUMBER='(0,0,0,0,0,0,0,0,0,0,0,0,0,0,0,BJ16,0,0,0,0,0,0,0,0,0,0,0,0,0,0)';
      BIDIRECTIONAL='TRUE';
      INPUT_LOAD='(-0.01,0.01)';
      OUTPUT_LOAD='(1.0,-1.0)';
    'RSVD'<141>:
      PIN_NUMBER='(0,0,0,0,0,0,0,0,0,0,0,0,0,0,0,BJ18,0,0,0,0,0,0,0,0,0,0,0,0,0,0)';
      BIDIRECTIONAL='TRUE';
      INPUT_LOAD='(-0.01,0.01)';
      OUTPUT_LOAD='(1.0,-1.0)';
    'RSVD'<140>:
      PIN_NUMBER='(0,0,0,0,0,0,0,0,0,0,0,0,0,0,0,BJ20,0,0,0,0,0,0,0,0,0,0,0,0,0,0)';
      BIDIRECTIONAL='TRUE';
      INPUT_LOAD='(-0.01,0.01)';
      OUTPUT_LOAD='(1.0,-1.0)';
    'RSVD'<139>:
      PIN_NUMBER='(0,0,0,0,0,0,0,0,0,0,0,0,0,0,0,BK17,0,0,0,0,0,0,0,0,0,0,0,0,0,0)';
      BIDIRECTIONAL='TRUE';
      INPUT_LOAD='(-0.01,0.01)';
      OUTPUT_LOAD='(1.0,-1.0)';
    'RSVD'<138>:
      PIN_NUMBER='(0,0,0,0,0,0,0,0,0,0,0,0,0,0,0,BL18,0,0,0,0,0,0,0,0,0,0,0,0,0,0)';
      BIDIRECTIONAL='TRUE';
      INPUT_LOAD='(-0.01,0.01)';
      OUTPUT_LOAD='(1.0,-1.0)';
    'RSVD'<137>:
      PIN_NUMBER='(0,0,0,0,0,0,0,0,0,0,0,0,0,0,0,BL20,0,0,0,0,0,0,0,0,0,0,0,0,0,0)';
      BIDIRECTIONAL='TRUE';
      INPUT_LOAD='(-0.01,0.01)';
      OUTPUT_LOAD='(1.0,-1.0)';
    'RSVD'<136>:
      PIN_NUMBER='(0,0,0,0,0,0,0,0,0,0,0,0,0,0,0,BM17,0,0,0,0,0,0,0,0,0,0,0,0,0,0)';
      BIDIRECTIONAL='TRUE';
      INPUT_LOAD='(-0.01,0.01)';
      OUTPUT_LOAD='(1.0,-1.0)';
    'RSVD'<135>:
      PIN_NUMBER='(0,0,0,0,0,0,0,0,0,0,0,0,0,0,0,BM19,0,0,0,0,0,0,0,0,0,0,0,0,0,0)';
      BIDIRECTIONAL='TRUE';
      INPUT_LOAD='(-0.01,0.01)';
      OUTPUT_LOAD='(1.0,-1.0)';
    'RSVD'<134>:
      PIN_NUMBER='(0,0,0,0,0,0,0,0,0,0,0,0,0,0,0,BN18,0,0,0,0,0,0,0,0,0,0,0,0,0,0)';
      BIDIRECTIONAL='TRUE';
      INPUT_LOAD='(-0.01,0.01)';
      OUTPUT_LOAD='(1.0,-1.0)';
    'RSVD'<133>:
      PIN_NUMBER='(0,0,0,0,0,0,0,0,0,0,0,0,0,0,0,BP17,0,0,0,0,0,0,0,0,0,0,0,0,0,0)';
      BIDIRECTIONAL='TRUE';
      INPUT_LOAD='(-0.01,0.01)';
      OUTPUT_LOAD='(1.0,-1.0)';
    'RSVD'<132>:
      PIN_NUMBER='(0,0,0,0,0,0,0,0,0,0,0,0,0,0,0,BP21,0,0,0,0,0,0,0,0,0,0,0,0,0,0)';
      BIDIRECTIONAL='TRUE';
      INPUT_LOAD='(-0.01,0.01)';
      OUTPUT_LOAD='(1.0,-1.0)';
    'RSVD'<131>:
      PIN_NUMBER='(0,0,0,0,0,0,0,0,0,0,0,0,0,0,0,BR22,0,0,0,0,0,0,0,0,0,0,0,0,0,0)';
      BIDIRECTIONAL='TRUE';
      INPUT_LOAD='(-0.01,0.01)';
      OUTPUT_LOAD='(1.0,-1.0)';
    'RSVD'<130>:
      PIN_NUMBER='(0,0,0,0,0,0,0,0,0,0,0,0,0,0,0,BR24,0,0,0,0,0,0,0,0,0,0,0,0,0,0)';
      BIDIRECTIONAL='TRUE';
      INPUT_LOAD='(-0.01,0.01)';
      OUTPUT_LOAD='(1.0,-1.0)';
    'RSVD'<129>:
      PIN_NUMBER='(0,0,0,0,0,0,0,0,0,0,0,0,0,0,0,BU18,0,0,0,0,0,0,0,0,0,0,0,0,0,0)';
      BIDIRECTIONAL='TRUE';
      INPUT_LOAD='(-0.01,0.01)';
      OUTPUT_LOAD='(1.0,-1.0)';
    'RSVD'<128>:
      PIN_NUMBER='(0,0,0,0,0,0,0,0,0,0,0,0,0,0,0,BU20,0,0,0,0,0,0,0,0,0,0,0,0,0,0)';
      BIDIRECTIONAL='TRUE';
      INPUT_LOAD='(-0.01,0.01)';
      OUTPUT_LOAD='(1.0,-1.0)';
    'RSVD'<127>:
      PIN_NUMBER='(0,0,0,0,0,0,0,0,0,0,0,0,0,0,0,BU22,0,0,0,0,0,0,0,0,0,0,0,0,0,0)';
      BIDIRECTIONAL='TRUE';
      INPUT_LOAD='(-0.01,0.01)';
      OUTPUT_LOAD='(1.0,-1.0)';
    'RSVD'<126>:
      PIN_NUMBER='(0,0,0,0,0,0,0,0,0,0,0,0,0,0,0,BV19,0,0,0,0,0,0,0,0,0,0,0,0,0,0)';
      BIDIRECTIONAL='TRUE';
      INPUT_LOAD='(-0.01,0.01)';
      OUTPUT_LOAD='(1.0,-1.0)';
    'RSVD'<125>:
      PIN_NUMBER='(0,0,0,0,0,0,0,0,0,0,0,0,0,0,0,BV21,0,0,0,0,0,0,0,0,0,0,0,0,0,0)';
      BIDIRECTIONAL='TRUE';
      INPUT_LOAD='(-0.01,0.01)';
      OUTPUT_LOAD='(1.0,-1.0)';
    'RSVD'<124>:
      PIN_NUMBER='(0,0,0,0,0,0,0,0,0,0,0,0,0,0,0,BV23,0,0,0,0,0,0,0,0,0,0,0,0,0,0)';
      BIDIRECTIONAL='TRUE';
      INPUT_LOAD='(-0.01,0.01)';
      OUTPUT_LOAD='(1.0,-1.0)';
    'RSVD'<123>:
      PIN_NUMBER='(0,0,0,0,0,0,0,0,0,0,0,0,0,0,0,BW10,0,0,0,0,0,0,0,0,0,0,0,0,0,0)';
      BIDIRECTIONAL='TRUE';
      INPUT_LOAD='(-0.01,0.01)';
      OUTPUT_LOAD='(1.0,-1.0)';
    'RSVD'<122>:
      PIN_NUMBER='(0,0,0,0,0,0,0,0,0,0,0,0,0,0,0,BW20,0,0,0,0,0,0,0,0,0,0,0,0,0,0)';
      BIDIRECTIONAL='TRUE';
      INPUT_LOAD='(-0.01,0.01)';
      OUTPUT_LOAD='(1.0,-1.0)';
    'RSVD'<121>:
      PIN_NUMBER='(0,0,0,0,0,0,0,0,0,0,0,0,0,0,0,BW22,0,0,0,0,0,0,0,0,0,0,0,0,0,0)';
      BIDIRECTIONAL='TRUE';
      INPUT_LOAD='(-0.01,0.01)';
      OUTPUT_LOAD='(1.0,-1.0)';
    'RSVD'<120>:
      PIN_NUMBER='(0,0,0,0,0,0,0,0,0,0,0,0,0,0,0,BY19,0,0,0,0,0,0,0,0,0,0,0,0,0,0)';
      BIDIRECTIONAL='TRUE';
      INPUT_LOAD='(-0.01,0.01)';
      OUTPUT_LOAD='(1.0,-1.0)';
    'RSVD'<119>:
      PIN_NUMBER='(0,0,0,0,0,0,0,0,0,0,0,0,0,0,0,BY25,0,0,0,0,0,0,0,0,0,0,0,0,0,0)';
      BIDIRECTIONAL='TRUE';
      INPUT_LOAD='(-0.01,0.01)';
      OUTPUT_LOAD='(1.0,-1.0)';
    'RSVD'<118>:
      PIN_NUMBER='(0,0,0,0,0,0,0,0,0,0,0,0,0,0,0,CA22,0,0,0,0,0,0,0,0,0,0,0,0,0,0)';
      BIDIRECTIONAL='TRUE';
      INPUT_LOAD='(-0.01,0.01)';
      OUTPUT_LOAD='(1.0,-1.0)';
    'RSVD'<117>:
      PIN_NUMBER='(0,0,0,0,0,0,0,0,0,0,0,0,0,0,0,CA24,0,0,0,0,0,0,0,0,0,0,0,0,0,0)';
      BIDIRECTIONAL='TRUE';
      INPUT_LOAD='(-0.01,0.01)';
      OUTPUT_LOAD='(1.0,-1.0)';
    'RSVD'<116>:
      PIN_NUMBER='(0,0,0,0,0,0,0,0,0,0,0,0,0,0,0,CB19,0,0,0,0,0,0,0,0,0,0,0,0,0,0)';
      BIDIRECTIONAL='TRUE';
      INPUT_LOAD='(-0.01,0.01)';
      OUTPUT_LOAD='(1.0,-1.0)';
    'RSVD'<115>:
      PIN_NUMBER='(0,0,0,0,0,0,0,0,0,0,0,0,0,0,0,CB21,0,0,0,0,0,0,0,0,0,0,0,0,0,0)';
      BIDIRECTIONAL='TRUE';
      INPUT_LOAD='(-0.01,0.01)';
      OUTPUT_LOAD='(1.0,-1.0)';
    'RSVD'<114>:
      PIN_NUMBER='(0,0,0,0,0,0,0,0,0,0,0,0,0,0,0,CB25,0,0,0,0,0,0,0,0,0,0,0,0,0,0)';
      BIDIRECTIONAL='TRUE';
      INPUT_LOAD='(-0.01,0.01)';
      OUTPUT_LOAD='(1.0,-1.0)';
    'RSVD'<113>:
      PIN_NUMBER='(0,0,0,0,0,0,0,0,0,0,0,0,0,0,0,CB5,0,0,0,0,0,0,0,0,0,0,0,0,0,0)';
      BIDIRECTIONAL='TRUE';
      INPUT_LOAD='(-0.01,0.01)';
      OUTPUT_LOAD='(1.0,-1.0)';
    'RSVD'<112>:
      PIN_NUMBER='(0,0,0,0,0,0,0,0,0,0,0,0,0,0,0,CC20,0,0,0,0,0,0,0,0,0,0,0,0,0,0)';
      BIDIRECTIONAL='TRUE';
      INPUT_LOAD='(-0.01,0.01)';
      OUTPUT_LOAD='(1.0,-1.0)';
    'RSVD'<111>:
      PIN_NUMBER='(0,0,0,0,0,0,0,0,0,0,0,0,0,0,0,CC6,0,0,0,0,0,0,0,0,0,0,0,0,0,0)';
      BIDIRECTIONAL='TRUE';
      INPUT_LOAD='(-0.01,0.01)';
      OUTPUT_LOAD='(1.0,-1.0)';
    'RSVD'<110>:
      PIN_NUMBER='(0,0,0,0,0,0,0,0,0,0,0,0,0,0,0,CD19,0,0,0,0,0,0,0,0,0,0,0,0,0,0)';
      BIDIRECTIONAL='TRUE';
      INPUT_LOAD='(-0.01,0.01)';
      OUTPUT_LOAD='(1.0,-1.0)';
    'RSVD'<109>:
      PIN_NUMBER='(0,0,0,0,0,0,0,0,0,0,0,0,0,0,0,CD21,0,0,0,0,0,0,0,0,0,0,0,0,0,0)';
      BIDIRECTIONAL='TRUE';
      INPUT_LOAD='(-0.01,0.01)';
      OUTPUT_LOAD='(1.0,-1.0)';
    'RSVD'<108>:
      PIN_NUMBER='(0,0,0,0,0,0,0,0,0,0,0,0,0,0,0,CD25,0,0,0,0,0,0,0,0,0,0,0,0,0,0)';
      BIDIRECTIONAL='TRUE';
      INPUT_LOAD='(-0.01,0.01)';
      OUTPUT_LOAD='(1.0,-1.0)';
    'RSVD'<107>:
      PIN_NUMBER='(0,0,0,0,0,0,0,0,0,0,0,0,0,0,0,CE22,0,0,0,0,0,0,0,0,0,0,0,0,0,0)';
      BIDIRECTIONAL='TRUE';
      INPUT_LOAD='(-0.01,0.01)';
      OUTPUT_LOAD='(1.0,-1.0)';
    'RSVD'<106>:
      PIN_NUMBER='(0,0,0,0,0,0,0,0,0,0,0,0,0,0,0,CE78,0,0,0,0,0,0,0,0,0,0,0,0,0,0)';
      BIDIRECTIONAL='TRUE';
      INPUT_LOAD='(-0.01,0.01)';
      OUTPUT_LOAD='(1.0,-1.0)';
    'RSVD'<105>:
      PIN_NUMBER='(0,0,0,0,0,0,0,0,0,0,0,0,0,0,0,CE80,0,0,0,0,0,0,0,0,0,0,0,0,0,0)';
      BIDIRECTIONAL='TRUE';
      INPUT_LOAD='(-0.01,0.01)';
      OUTPUT_LOAD='(1.0,-1.0)';
    'RSVD'<104>:
      PIN_NUMBER='(0,0,0,0,0,0,0,0,0,0,0,0,0,0,0,CF19,0,0,0,0,0,0,0,0,0,0,0,0,0,0)';
      BIDIRECTIONAL='TRUE';
      INPUT_LOAD='(-0.01,0.01)';
      OUTPUT_LOAD='(1.0,-1.0)';
    'RSVD'<103>:
      PIN_NUMBER='(0,0,0,0,0,0,0,0,0,0,0,0,0,0,0,CF21,0,0,0,0,0,0,0,0,0,0,0,0,0,0)';
      BIDIRECTIONAL='TRUE';
      INPUT_LOAD='(-0.01,0.01)';
      OUTPUT_LOAD='(1.0,-1.0)';
    'RSVD'<102>:
      PIN_NUMBER='(0,0,0,0,0,0,0,0,0,0,0,0,0,0,0,CF23,0,0,0,0,0,0,0,0,0,0,0,0,0,0)';
      BIDIRECTIONAL='TRUE';
      INPUT_LOAD='(-0.01,0.01)';
      OUTPUT_LOAD='(1.0,-1.0)';
    'RSVD'<101>:
      PIN_NUMBER='(0,0,0,0,0,0,0,0,0,0,0,0,0,0,0,CF79,0,0,0,0,0,0,0,0,0,0,0,0,0,0)';
      BIDIRECTIONAL='TRUE';
      INPUT_LOAD='(-0.01,0.01)';
      OUTPUT_LOAD='(1.0,-1.0)';
    'RSVD'<100>:
      PIN_NUMBER='(0,0,0,0,0,0,0,0,0,0,0,0,0,0,0,CF81,0,0,0,0,0,0,0,0,0,0,0,0,0,0)';
      BIDIRECTIONAL='TRUE';
      INPUT_LOAD='(-0.01,0.01)';
      OUTPUT_LOAD='(1.0,-1.0)';
    'RSVD'<99>:
      PIN_NUMBER='(0,0,0,0,0,0,0,0,0,0,0,0,0,0,0,CG10,0,0,0,0,0,0,0,0,0,0,0,0,0,0)';
      BIDIRECTIONAL='TRUE';
      INPUT_LOAD='(-0.01,0.01)';
      OUTPUT_LOAD='(1.0,-1.0)';
    'RSVD'<98>:
      PIN_NUMBER='(0,0,0,0,0,0,0,0,0,0,0,0,0,0,0,CG20,0,0,0,0,0,0,0,0,0,0,0,0,0,0)';
      BIDIRECTIONAL='TRUE';
      INPUT_LOAD='(-0.01,0.01)';
      OUTPUT_LOAD='(1.0,-1.0)';
    'RSVD'<97>:
      PIN_NUMBER='(0,0,0,0,0,0,0,0,0,0,0,0,0,0,0,CG24,0,0,0,0,0,0,0,0,0,0,0,0,0,0)';
      BIDIRECTIONAL='TRUE';
      INPUT_LOAD='(-0.01,0.01)';
      OUTPUT_LOAD='(1.0,-1.0)';
    'RSVD'<96>:
      PIN_NUMBER='(0,0,0,0,0,0,0,0,0,0,0,0,0,0,0,CG26,0,0,0,0,0,0,0,0,0,0,0,0,0,0)';
      BIDIRECTIONAL='TRUE';
      INPUT_LOAD='(-0.01,0.01)';
      OUTPUT_LOAD='(1.0,-1.0)';
    'RSVD'<95>:
      PIN_NUMBER='(0,0,0,0,0,0,0,0,0,0,0,0,0,0,0,CG78,0,0,0,0,0,0,0,0,0,0,0,0,0,0)';
      BIDIRECTIONAL='TRUE';
      INPUT_LOAD='(-0.01,0.01)';
      OUTPUT_LOAD='(1.0,-1.0)';
    'RSVD'<94>:
      PIN_NUMBER='(0,0,0,0,0,0,0,0,0,0,0,0,0,0,0,CG82,0,0,0,0,0,0,0,0,0,0,0,0,0,0)';
      BIDIRECTIONAL='TRUE';
      INPUT_LOAD='(-0.01,0.01)';
      OUTPUT_LOAD='(1.0,-1.0)';
    'RSVD'<93>:
      PIN_NUMBER='(0,0,0,0,0,0,0,0,0,0,0,0,0,0,0,CH21,0,0,0,0,0,0,0,0,0,0,0,0,0,0)';
      BIDIRECTIONAL='TRUE';
      INPUT_LOAD='(-0.01,0.01)';
      OUTPUT_LOAD='(1.0,-1.0)';
    'RSVD'<92>:
      PIN_NUMBER='(0,0,0,0,0,0,0,0,0,0,0,0,0,0,0,CH23,0,0,0,0,0,0,0,0,0,0,0,0,0,0)';
      BIDIRECTIONAL='TRUE';
      INPUT_LOAD='(-0.01,0.01)';
      OUTPUT_LOAD='(1.0,-1.0)';
    'RSVD'<91>:
      PIN_NUMBER='(0,0,0,0,0,0,0,0,0,0,0,0,0,0,0,0,CH25,0,0,0,0,0,0,0,0,0,0,0,0,0)';
      BIDIRECTIONAL='TRUE';
      INPUT_LOAD='(-0.01,0.01)';
      OUTPUT_LOAD='(1.0,-1.0)';
    'RSVD'<90>:
      PIN_NUMBER='(0,0,0,0,0,0,0,0,0,0,0,0,0,0,0,0,CH77,0,0,0,0,0,0,0,0,0,0,0,0,0)';
      BIDIRECTIONAL='TRUE';
      INPUT_LOAD='(-0.01,0.01)';
      OUTPUT_LOAD='(1.0,-1.0)';
    'RSVD'<89>:
      PIN_NUMBER='(0,0,0,0,0,0,0,0,0,0,0,0,0,0,0,0,CJ20,0,0,0,0,0,0,0,0,0,0,0,0,0)';
      BIDIRECTIONAL='TRUE';
      INPUT_LOAD='(-0.01,0.01)';
      OUTPUT_LOAD='(1.0,-1.0)';
    'RSVD'<88>:
      PIN_NUMBER='(0,0,0,0,0,0,0,0,0,0,0,0,0,0,0,0,CJ22,0,0,0,0,0,0,0,0,0,0,0,0,0)';
      BIDIRECTIONAL='TRUE';
      INPUT_LOAD='(-0.01,0.01)';
      OUTPUT_LOAD='(1.0,-1.0)';
    'RSVD'<87>:
      PIN_NUMBER='(0,0,0,0,0,0,0,0,0,0,0,0,0,0,0,0,CJ24,0,0,0,0,0,0,0,0,0,0,0,0,0)';
      BIDIRECTIONAL='TRUE';
      INPUT_LOAD='(-0.01,0.01)';
      OUTPUT_LOAD='(1.0,-1.0)';
    'RSVD'<86>:
      PIN_NUMBER='(0,0,0,0,0,0,0,0,0,0,0,0,0,0,0,0,CJ26,0,0,0,0,0,0,0,0,0,0,0,0,0)';
      BIDIRECTIONAL='TRUE';
      INPUT_LOAD='(-0.01,0.01)';
      OUTPUT_LOAD='(1.0,-1.0)';
    'RSVD'<85>:
      PIN_NUMBER='(0,0,0,0,0,0,0,0,0,0,0,0,0,0,0,0,CK19,0,0,0,0,0,0,0,0,0,0,0,0,0)';
      BIDIRECTIONAL='TRUE';
      INPUT_LOAD='(-0.01,0.01)';
      OUTPUT_LOAD='(1.0,-1.0)';
    'RSVD'<84>:
      PIN_NUMBER='(0,0,0,0,0,0,0,0,0,0,0,0,0,0,0,0,CK23,0,0,0,0,0,0,0,0,0,0,0,0,0)';
      BIDIRECTIONAL='TRUE';
      INPUT_LOAD='(-0.01,0.01)';
      OUTPUT_LOAD='(1.0,-1.0)';
    'RSVD'<83>:
      PIN_NUMBER='(0,0,0,0,0,0,0,0,0,0,0,0,0,0,0,0,CK25,0,0,0,0,0,0,0,0,0,0,0,0,0)';
      BIDIRECTIONAL='TRUE';
      INPUT_LOAD='(-0.01,0.01)';
      OUTPUT_LOAD='(1.0,-1.0)';
    'RSVD'<82>:
      PIN_NUMBER='(0,0,0,0,0,0,0,0,0,0,0,0,0,0,0,0,CK77,0,0,0,0,0,0,0,0,0,0,0,0,0)';
      BIDIRECTIONAL='TRUE';
      INPUT_LOAD='(-0.01,0.01)';
      OUTPUT_LOAD='(1.0,-1.0)';
    'RSVD'<81>:
      PIN_NUMBER='(0,0,0,0,0,0,0,0,0,0,0,0,0,0,0,0,CL24,0,0,0,0,0,0,0,0,0,0,0,0,0)';
      BIDIRECTIONAL='TRUE';
      INPUT_LOAD='(-0.01,0.01)';
      OUTPUT_LOAD='(1.0,-1.0)';
    'RSVD'<80>:
      PIN_NUMBER='(0,0,0,0,0,0,0,0,0,0,0,0,0,0,0,0,0,0,0,0,0,CL26,0,0,0,0,0,0,0,0)';
      BIDIRECTIONAL='TRUE';
      INPUT_LOAD='(-0.01,0.01)';
      OUTPUT_LOAD='(1.0,-1.0)';
    'RSVD'<79>:
      PIN_NUMBER='(0,0,0,0,0,0,0,0,0,0,0,0,0,0,0,0,0,0,0,0,0,CM23,0,0,0,0,0,0,0,0)';
      BIDIRECTIONAL='TRUE';
      INPUT_LOAD='(-0.01,0.01)';
      OUTPUT_LOAD='(1.0,-1.0)';
    'RSVD'<78>:
      PIN_NUMBER='(0,0,0,0,0,0,0,0,0,0,0,0,0,0,0,0,0,0,0,0,0,CM25,0,0,0,0,0,0,0,0)';
      BIDIRECTIONAL='TRUE';
      INPUT_LOAD='(-0.01,0.01)';
      OUTPUT_LOAD='(1.0,-1.0)';
    'RSVD'<77>:
      PIN_NUMBER='(0,0,0,0,0,0,0,0,0,0,0,0,0,0,0,0,0,0,0,0,0,CN22,0,0,0,0,0,0,0,0)';
      BIDIRECTIONAL='TRUE';
      INPUT_LOAD='(-0.01,0.01)';
      OUTPUT_LOAD='(1.0,-1.0)';
    'RSVD'<76>:
      PIN_NUMBER='(0,0,0,0,0,0,0,0,0,0,0,0,0,0,0,0,0,0,0,0,0,CN24,0,0,0,0,0,0,0,0)';
      BIDIRECTIONAL='TRUE';
      INPUT_LOAD='(-0.01,0.01)';
      OUTPUT_LOAD='(1.0,-1.0)';
    'RSVD'<75>:
      PIN_NUMBER='(0,0,0,0,0,0,0,0,0,0,0,0,0,0,0,0,0,0,0,0,0,CN28,0,0,0,0,0,0,0,0)';
      BIDIRECTIONAL='TRUE';
      INPUT_LOAD='(-0.01,0.01)';
      OUTPUT_LOAD='(1.0,-1.0)';
    'RSVD'<74>:
      PIN_NUMBER='(0,0,0,0,0,0,0,0,0,0,0,0,0,0,0,0,0,0,0,0,0,CP23,0,0,0,0,0,0,0,0)';
      BIDIRECTIONAL='TRUE';
      INPUT_LOAD='(-0.01,0.01)';
      OUTPUT_LOAD='(1.0,-1.0)';
    'RSVD'<73>:
      PIN_NUMBER='(0,0,0,0,0,0,0,0,0,0,0,0,0,0,0,0,0,0,0,0,0,CP31,0,0,0,0,0,0,0,0)';
      BIDIRECTIONAL='TRUE';
      INPUT_LOAD='(-0.01,0.01)';
      OUTPUT_LOAD='(1.0,-1.0)';
    'RSVD'<72>:
      PIN_NUMBER='(0,0,0,0,0,0,0,0,0,0,0,0,0,0,0,0,0,0,0,0,0,CR60,0,0,0,0,0,0,0,0)';
      BIDIRECTIONAL='TRUE';
      INPUT_LOAD='(-0.01,0.01)';
      OUTPUT_LOAD='(1.0,-1.0)';
    'RSVD'<71>:
      PIN_NUMBER='(0,0,0,0,0,0,0,0,0,0,0,0,0,0,0,0,0,0,0,0,0,CT23,0,0,0,0,0,0,0,0)';
      BIDIRECTIONAL='TRUE';
      INPUT_LOAD='(-0.01,0.01)';
      OUTPUT_LOAD='(1.0,-1.0)';
    'RSVD'<70>:
      PIN_NUMBER='(0,0,0,0,0,0,0,0,0,0,0,0,0,0,0,0,0,0,0,0,0,CT5,0,0,0,0,0,0,0,0)';
      BIDIRECTIONAL='TRUE';
      INPUT_LOAD='(-0.01,0.01)';
      OUTPUT_LOAD='(1.0,-1.0)';
    'RSVD'<69>:
      PIN_NUMBER='(0,0,0,0,0,0,0,0,0,0,0,0,0,0,0,0,0,0,0,0,0,CT69,0,0,0,0,0,0,0,0)';
      BIDIRECTIONAL='TRUE';
      INPUT_LOAD='(-0.01,0.01)';
      OUTPUT_LOAD='(1.0,-1.0)';
    'RSVD'<68>:
      PIN_NUMBER='(0,0,0,0,0,0,0,0,0,0,0,0,0,0,0,0,0,0,0,0,0,CU24,0,0,0,0,0,0,0,0)';
      BIDIRECTIONAL='TRUE';
      INPUT_LOAD='(-0.01,0.01)';
      OUTPUT_LOAD='(1.0,-1.0)';
    'RSVD'<67>:
      PIN_NUMBER='(0,0,0,0,0,0,0,0,0,0,0,0,0,0,0,0,0,0,0,0,0,CU6,0,0,0,0,0,0,0,0)';
      BIDIRECTIONAL='TRUE';
      INPUT_LOAD='(-0.01,0.01)';
      OUTPUT_LOAD='(1.0,-1.0)';
    'RSVD'<66>:
      PIN_NUMBER='(0,0,0,0,0,0,0,0,0,0,0,0,0,0,0,0,0,0,0,0,0,CU60,0,0,0,0,0,0,0,0)';
      BIDIRECTIONAL='TRUE';
      INPUT_LOAD='(-0.01,0.01)';
      OUTPUT_LOAD='(1.0,-1.0)';
    'RSVD'<65>:
      PIN_NUMBER='(0,0,0,0,0,0,0,0,0,0,0,0,0,0,0,0,0,0,0,0,0,CV23,0,0,0,0,0,0,0,0)';
      BIDIRECTIONAL='TRUE';
      INPUT_LOAD='(-0.01,0.01)';
      OUTPUT_LOAD='(1.0,-1.0)';
    'RSVD'<64>:
      PIN_NUMBER='(0,0,0,0,0,0,0,0,0,0,0,0,0,0,0,0,0,0,0,0,0,CV69,0,0,0,0,0,0,0,0)';
      BIDIRECTIONAL='TRUE';
      INPUT_LOAD='(-0.01,0.01)';
      OUTPUT_LOAD='(1.0,-1.0)';
    'RSVD'<63>:
      PIN_NUMBER='(0,0,0,0,0,0,0,0,0,0,0,0,0,0,0,0,0,0,0,0,0,CW22,0,0,0,0,0,0,0,0)';
      BIDIRECTIONAL='TRUE';
      INPUT_LOAD='(-0.01,0.01)';
      OUTPUT_LOAD='(1.0,-1.0)';
    'RSVD'<62>:
      PIN_NUMBER='(0,0,0,0,0,0,0,0,0,0,0,0,0,0,0,0,0,0,0,0,0,CW24,0,0,0,0,0,0,0,0)';
      BIDIRECTIONAL='TRUE';
      INPUT_LOAD='(-0.01,0.01)';
      OUTPUT_LOAD='(1.0,-1.0)';
    'RSVD'<61>:
      PIN_NUMBER='(0,0,0,0,0,0,0,0,0,0,0,0,0,0,0,0,0,0,0,0,0,CW60,0,0,0,0,0,0,0,0)';
      BIDIRECTIONAL='TRUE';
      INPUT_LOAD='(-0.01,0.01)';
      OUTPUT_LOAD='(1.0,-1.0)';
    'RSVD'<60>:
      PIN_NUMBER='(0,0,0,0,0,0,0,0,0,0,0,0,0,0,0,0,0,0,0,0,0,CW62,0,0,0,0,0,0,0,0)';
      BIDIRECTIONAL='TRUE';
      INPUT_LOAD='(-0.01,0.01)';
      OUTPUT_LOAD='(1.0,-1.0)';
    'RSVD'<59>:
      PIN_NUMBER='(0,0,0,0,0,0,0,0,0,0,0,0,0,0,0,0,0,0,0,0,0,CY23,0,0,0,0,0,0,0,0)';
      BIDIRECTIONAL='TRUE';
      INPUT_LOAD='(-0.01,0.01)';
      OUTPUT_LOAD='(1.0,-1.0)';
    'RSVD'<58>:
      PIN_NUMBER='(0,0,0,0,0,0,0,0,0,0,0,0,0,0,0,0,0,0,0,0,0,CY25,0,0,0,0,0,0,0,0)';
      BIDIRECTIONAL='TRUE';
      INPUT_LOAD='(-0.01,0.01)';
      OUTPUT_LOAD='(1.0,-1.0)';
    'RSVD'<57>:
      PIN_NUMBER='(0,0,0,0,0,0,0,0,0,0,0,0,0,0,0,0,0,0,0,0,0,CY39,0,0,0,0,0,0,0,0)';
      BIDIRECTIONAL='TRUE';
      INPUT_LOAD='(-0.01,0.01)';
      OUTPUT_LOAD='(1.0,-1.0)';
    'RSVD'<56>:
      PIN_NUMBER='(0,0,0,0,0,0,0,0,0,0,0,0,0,0,0,0,0,0,0,0,0,CY53,0,0,0,0,0,0,0,0)';
      BIDIRECTIONAL='TRUE';
      INPUT_LOAD='(-0.01,0.01)';
      OUTPUT_LOAD='(1.0,-1.0)';
    'RSVD'<55>:
      PIN_NUMBER='(0,0,0,0,0,0,0,0,0,0,0,0,0,0,0,0,0,0,0,0,0,CY57,0,0,0,0,0,0,0,0)';
      BIDIRECTIONAL='TRUE';
      INPUT_LOAD='(-0.01,0.01)';
      OUTPUT_LOAD='(1.0,-1.0)';
    'RSVD'<54>:
      PIN_NUMBER='(0,0,0,0,0,0,0,0,0,0,0,0,0,0,0,0,0,0,0,0,0,CY63,0,0,0,0,0,0,0,0)';
      BIDIRECTIONAL='TRUE';
      INPUT_LOAD='(-0.01,0.01)';
      OUTPUT_LOAD='(1.0,-1.0)';
    'RSVD'<53>:
      PIN_NUMBER='(0,0,0,0,0,0,0,0,0,0,0,0,0,0,0,0,0,0,0,0,0,CY73,0,0,0,0,0,0,0,0)';
      BIDIRECTIONAL='TRUE';
      INPUT_LOAD='(-0.01,0.01)';
      OUTPUT_LOAD='(1.0,-1.0)';
    'RSVD'<52>:
      PIN_NUMBER='(0,0,0,0,0,0,0,0,0,0,0,0,0,0,0,0,0,0,0,0,0,DA24,0,0,0,0,0,0,0,0)';
      BIDIRECTIONAL='TRUE';
      INPUT_LOAD='(-0.01,0.01)';
      OUTPUT_LOAD='(1.0,-1.0)';
    'RSVD'<51>:
      PIN_NUMBER='(0,0,0,0,0,0,0,0,0,0,0,0,0,0,0,0,0,0,0,0,0,DA40,0,0,0,0,0,0,0,0)';
      BIDIRECTIONAL='TRUE';
      INPUT_LOAD='(-0.01,0.01)';
      OUTPUT_LOAD='(1.0,-1.0)';
    'RSVD'<50>:
      PIN_NUMBER='(0,0,0,0,0,0,0,0,0,0,0,0,0,0,0,0,0,0,0,0,0,DA52,0,0,0,0,0,0,0,0)';
      BIDIRECTIONAL='TRUE';
      INPUT_LOAD='(-0.01,0.01)';
      OUTPUT_LOAD='(1.0,-1.0)';
    'RSVD'<49>:
      PIN_NUMBER='(0,0,0,0,0,0,0,0,0,0,0,0,0,0,0,0,0,0,0,0,0,DA54,0,0,0,0,0,0,0,0)';
      BIDIRECTIONAL='TRUE';
      INPUT_LOAD='(-0.01,0.01)';
      OUTPUT_LOAD='(1.0,-1.0)';
    'RSVD'<48>:
      PIN_NUMBER='(0,0,0,0,0,0,0,0,0,0,0,0,0,0,0,0,0,0,0,0,0,DA56,0,0,0,0,0,0,0,0)';
      BIDIRECTIONAL='TRUE';
      INPUT_LOAD='(-0.01,0.01)';
      OUTPUT_LOAD='(1.0,-1.0)';
    'RSVD'<47>:
      PIN_NUMBER='(0,0,0,0,0,0,0,0,0,0,0,0,0,0,0,0,0,0,0,0,0,DC46,0,0,0,0,0,0,0,0)';
      BIDIRECTIONAL='TRUE';
      INPUT_LOAD='(-0.01,0.01)';
      OUTPUT_LOAD='(1.0,-1.0)';
    'RSVD'<46>:
      PIN_NUMBER='(0,0,0,0,0,0,0,0,0,0,0,0,0,0,0,0,0,0,0,0,0,DC52,0,0,0,0,0,0,0,0)';
      BIDIRECTIONAL='TRUE';
      INPUT_LOAD='(-0.01,0.01)';
      OUTPUT_LOAD='(1.0,-1.0)';
    'RSVD'<45>:
      PIN_NUMBER='(0,0,0,0,0,0,0,0,0,0,0,0,0,0,0,0,0,0,0,0,0,DD51,0,0,0,0,0,0,0,0)';
      BIDIRECTIONAL='TRUE';
      INPUT_LOAD='(-0.01,0.01)';
      OUTPUT_LOAD='(1.0,-1.0)';
    'RSVD'<44>:
      PIN_NUMBER='(0,0,0,0,0,0,0,0,0,0,0,0,0,0,0,0,0,0,0,0,0,DG36,0,0,0,0,0,0,0,0)';
      BIDIRECTIONAL='TRUE';
      INPUT_LOAD='(-0.01,0.01)';
      OUTPUT_LOAD='(1.0,-1.0)';
    'RSVD'<43>:
      PIN_NUMBER='(0,0,0,0,0,0,0,0,0,0,0,0,0,0,0,0,0,0,0,0,0,DG64,0,0,0,0,0,0,0,0)';
      BIDIRECTIONAL='TRUE';
      INPUT_LOAD='(-0.01,0.01)';
      OUTPUT_LOAD='(1.0,-1.0)';
    'RSVD'<42>:
      PIN_NUMBER='(0,0,0,0,0,0,0,0,0,0,0,0,0,0,0,0,0,0,0,0,0,DH65,0,0,0,0,0,0,0,0)';
      BIDIRECTIONAL='TRUE';
      INPUT_LOAD='(-0.01,0.01)';
      OUTPUT_LOAD='(1.0,-1.0)';
    'RSVD'<41>:
      PIN_NUMBER='(0,0,0,0,0,0,0,0,0,0,0,0,0,0,0,0,0,0,0,0,0,DJ36,0,0,0,0,0,0,0,0)';
      BIDIRECTIONAL='TRUE';
      INPUT_LOAD='(-0.01,0.01)';
      OUTPUT_LOAD='(1.0,-1.0)';
    'RSVD'<40>:
      PIN_NUMBER='(0,0,0,0,0,0,0,0,0,0,0,0,0,0,0,0,0,0,0,0,0,DJ66,0,0,0,0,0,0,0,0)';
      BIDIRECTIONAL='TRUE';
      INPUT_LOAD='(-0.01,0.01)';
      OUTPUT_LOAD='(1.0,-1.0)';
    'RSVD'<39>:
      PIN_NUMBER='(0,0,0,0,0,0,0,0,0,0,0,0,0,0,0,0,0,0,0,0,0,DK15,0,0,0,0,0,0,0,0)';
      BIDIRECTIONAL='TRUE';
      INPUT_LOAD='(-0.01,0.01)';
      OUTPUT_LOAD='(1.0,-1.0)';
    'RSVD'<38>:
      PIN_NUMBER='(0,0,0,0,0,0,0,0,0,0,0,0,0,0,0,0,0,0,0,0,0,DK37,0,0,0,0,0,0,0,0)';
      BIDIRECTIONAL='TRUE';
      INPUT_LOAD='(-0.01,0.01)';
      OUTPUT_LOAD='(1.0,-1.0)';
    'RSVD'<37>:
      PIN_NUMBER='(0,0,0,0,0,0,0,0,0,0,0,0,0,0,0,0,0,0,0,0,0,DK65,0,0,0,0,0,0,0,0)';
      BIDIRECTIONAL='TRUE';
      INPUT_LOAD='(-0.01,0.01)';
      OUTPUT_LOAD='(1.0,-1.0)';
    'RSVD'<36>:
      PIN_NUMBER='(0,0,0,0,0,0,0,0,0,0,0,0,0,0,0,0,0,0,0,0,0,DK67,0,0,0,0,0,0,0,0)';
      BIDIRECTIONAL='TRUE';
      INPUT_LOAD='(-0.01,0.01)';
      OUTPUT_LOAD='(1.0,-1.0)';
    'RSVD'<35>:
      PIN_NUMBER='(0,0,0,0,0,0,0,0,0,0,0,0,0,0,0,0,0,0,0,0,0,DL38,0,0,0,0,0,0,0,0)';
      BIDIRECTIONAL='TRUE';
      INPUT_LOAD='(-0.01,0.01)';
      OUTPUT_LOAD='(1.0,-1.0)';
    'RSVD'<34>:
      PIN_NUMBER='(0,0,0,0,0,0,0,0,0,0,0,0,0,0,0,0,0,0,0,0,0,DL66,0,0,0,0,0,0,0,0)';
      BIDIRECTIONAL='TRUE';
      INPUT_LOAD='(-0.01,0.01)';
      OUTPUT_LOAD='(1.0,-1.0)';
    'RSVD'<33>:
      PIN_NUMBER='(0,0,0,0,0,0,0,0,0,0,0,0,0,0,0,0,0,0,0,0,0,DM67,0,0,0,0,0,0,0,0)';
      BIDIRECTIONAL='TRUE';
      INPUT_LOAD='(-0.01,0.01)';
      OUTPUT_LOAD='(1.0,-1.0)';
    'RSVD'<32>:
      PIN_NUMBER='(0,0,0,0,0,0,0,0,0,0,0,0,0,0,0,0,0,0,0,0,0,DN62,0,0,0,0,0,0,0,0)';
      BIDIRECTIONAL='TRUE';
      INPUT_LOAD='(-0.01,0.01)';
      OUTPUT_LOAD='(1.0,-1.0)';
    'RSVD'<31>:
      PIN_NUMBER='(0,0,0,0,0,0,0,0,0,0,0,0,0,0,0,0,0,0,0,0,0,DN66,0,0,0,0,0,0,0,0)';
      BIDIRECTIONAL='TRUE';
      INPUT_LOAD='(-0.01,0.01)';
      OUTPUT_LOAD='(1.0,-1.0)';
    'RSVD'<30>:
      PIN_NUMBER='(0,0,0,0,0,0,0,0,0,0,0,0,0,0,0,0,0,0,0,0,0,DP17,0,0,0,0,0,0,0,0)';
      BIDIRECTIONAL='TRUE';
      INPUT_LOAD='(-0.01,0.01)';
      OUTPUT_LOAD='(1.0,-1.0)';
    'RSVD'<29>:
      PIN_NUMBER='(0,0,0,0,0,0,0,0,0,0,0,0,0,0,0,0,0,0,0,0,0,DP65,0,0,0,0,0,0,0,0)';
      BIDIRECTIONAL='TRUE';
      INPUT_LOAD='(-0.01,0.01)';
      OUTPUT_LOAD='(1.0,-1.0)';
    'RSVD'<28>:
      PIN_NUMBER='(0,0,0,0,0,0,0,0,0,0,0,0,0,0,0,0,0,0,0,0,0,DR44,0,0,0,0,0,0,0,0)';
      BIDIRECTIONAL='TRUE';
      INPUT_LOAD='(-0.01,0.01)';
      OUTPUT_LOAD='(1.0,-1.0)';
    'RSVD'<27>:
      PIN_NUMBER='(0,0,0,0,0,0,0,0,0,0,0,0,0,0,0,0,0,0,0,0,0,DT71,0,0,0,0,0,0,0,0)';
      BIDIRECTIONAL='TRUE';
      INPUT_LOAD='(-0.01,0.01)';
      OUTPUT_LOAD='(1.0,-1.0)';
    'RSVD'<26>:
      PIN_NUMBER='(0,0,0,0,0,0,0,0,0,0,0,0,0,0,0,0,0,0,0,0,0,DU44,0,0,0,0,0,0,0,0)';
      BIDIRECTIONAL='TRUE';
      INPUT_LOAD='(-0.01,0.01)';
      OUTPUT_LOAD='(1.0,-1.0)';
    'RSVD'<25>:
      PIN_NUMBER='(0,0,0,0,0,0,0,0,0,0,0,0,0,0,0,0,0,0,0,0,0,DV61,0,0,0,0,0,0,0,0)';
      BIDIRECTIONAL='TRUE';
      INPUT_LOAD='(-0.01,0.01)';
      OUTPUT_LOAD='(1.0,-1.0)';
    'RSVD'<24>:
      PIN_NUMBER='(0,0,0,0,0,0,0,0,0,0,0,0,0,0,0,0,0,0,0,0,0,DV71,0,0,0,0,0,0,0,0)';
      BIDIRECTIONAL='TRUE';
      INPUT_LOAD='(-0.01,0.01)';
      OUTPUT_LOAD='(1.0,-1.0)';
    'RSVD'<23>:
      PIN_NUMBER='(0,0,0,0,0,0,0,0,0,0,0,0,0,0,0,0,0,0,0,0,0,DW44,0,0,0,0,0,0,0,0)';
      BIDIRECTIONAL='TRUE';
      INPUT_LOAD='(-0.01,0.01)';
      OUTPUT_LOAD='(1.0,-1.0)';
    'RSVD'<22>:
      PIN_NUMBER='(0,0,0,0,0,0,0,0,0,0,0,0,0,0,0,0,0,0,0,0,0,DW46,0,0,0,0,0,0,0,0)';
      BIDIRECTIONAL='TRUE';
      INPUT_LOAD='(-0.01,0.01)';
      OUTPUT_LOAD='(1.0,-1.0)';
    'RSVD'<21>:
      PIN_NUMBER='(0,0,0,0,0,0,0,0,0,0,0,0,0,0,0,0,0,0,0,0,0,DY3,0,0,0,0,0,0,0,0)';
      BIDIRECTIONAL='TRUE';
      INPUT_LOAD='(-0.01,0.01)';
      OUTPUT_LOAD='(1.0,-1.0)';
    'RSVD'<20>:
      PIN_NUMBER='(0,0,0,0,0,0,0,0,0,0,0,0,0,0,0,0,0,0,0,0,0,EA4,0,0,0,0,0,0,0,0)';
      BIDIRECTIONAL='TRUE';
      INPUT_LOAD='(-0.01,0.01)';
      OUTPUT_LOAD='(1.0,-1.0)';
    'RSVD'<19>:
      PIN_NUMBER='(0,0,0,0,0,0,0,0,0,0,0,0,0,0,0,0,0,0,0,0,0,EA44,0,0,0,0,0,0,0,0)';
      BIDIRECTIONAL='TRUE';
      INPUT_LOAD='(-0.01,0.01)';
      OUTPUT_LOAD='(1.0,-1.0)';
    'RSVD'<18>:
      PIN_NUMBER='(0,0,0,0,0,0,0,0,0,0,0,0,0,0,0,0,0,0,0,0,0,EB3,0,0,0,0,0,0,0,0)';
      BIDIRECTIONAL='TRUE';
      INPUT_LOAD='(-0.01,0.01)';
      OUTPUT_LOAD='(1.0,-1.0)';
    'RSVD'<17>:
      PIN_NUMBER='(0,0,0,0,0,0,0,0,0,0,0,0,0,0,0,0,0,0,0,0,0,EB5,0,0,0,0,0,0,0,0)';
      BIDIRECTIONAL='TRUE';
      INPUT_LOAD='(-0.01,0.01)';
      OUTPUT_LOAD='(1.0,-1.0)';
    'RSVD'<16>:
      PIN_NUMBER='(0,0,0,0,0,0,0,0,0,0,0,0,0,0,0,0,0,0,0,0,0,EB85,0,0,0,0,0,0,0,0)';
      BIDIRECTIONAL='TRUE';
      INPUT_LOAD='(-0.01,0.01)';
      OUTPUT_LOAD='(1.0,-1.0)';
    'RSVD'<15>:
      PIN_NUMBER='(0,0,0,0,0,0,0,0,0,0,0,0,0,0,0,0,0,0,0,0,0,EC16,0,0,0,0,0,0,0,0)';
      BIDIRECTIONAL='TRUE';
      INPUT_LOAD='(-0.01,0.01)';
      OUTPUT_LOAD='(1.0,-1.0)';
    'RSVD'<14>:
      PIN_NUMBER='(0,0,0,0,0,0,0,0,0,0,0,0,0,0,0,0,0,0,0,0,0,EC4,0,0,0,0,0,0,0,0)';
      BIDIRECTIONAL='TRUE';
      INPUT_LOAD='(-0.01,0.01)';
      OUTPUT_LOAD='(1.0,-1.0)';
    'RSVD'<13>:
      PIN_NUMBER='(0,0,0,0,0,0,0,0,0,0,0,0,0,0,0,0,0,0,0,0,0,EC44,0,0,0,0,0,0,0,0)';
      BIDIRECTIONAL='TRUE';
      INPUT_LOAD='(-0.01,0.01)';
      OUTPUT_LOAD='(1.0,-1.0)';
    'RSVD'<12>:
      PIN_NUMBER='(0,0,0,0,0,0,0,0,0,0,0,0,0,0,0,0,0,0,0,0,0,EC84,0,0,0,0,0,0,0,0)';
      BIDIRECTIONAL='TRUE';
      INPUT_LOAD='(-0.01,0.01)';
      OUTPUT_LOAD='(1.0,-1.0)';
    'RSVD'<11>:
      PIN_NUMBER='(0,0,0,0,0,0,0,0,0,0,0,0,0,0,0,0,0,0,0,0,0,ED45,0,0,0,0,0,0,0,0)';
      BIDIRECTIONAL='TRUE';
      INPUT_LOAD='(-0.01,0.01)';
      OUTPUT_LOAD='(1.0,-1.0)';
    'RSVD'<10>:
      PIN_NUMBER='(0,0,0,0,0,0,0,0,0,0,0,0,0,0,0,0,0,0,0,0,0,ED5,0,0,0,0,0,0,0,0)';
      BIDIRECTIONAL='TRUE';
      INPUT_LOAD='(-0.01,0.01)';
      OUTPUT_LOAD='(1.0,-1.0)';
    'RSVD'<9>:
      PIN_NUMBER='(0,0,0,0,0,0,0,0,0,0,0,0,0,0,0,0,0,0,0,0,0,ED83,0,0,0,0,0,0,0,0)';
      BIDIRECTIONAL='TRUE';
      INPUT_LOAD='(-0.01,0.01)';
      OUTPUT_LOAD='(1.0,-1.0)';
    'RSVD'<8>:
      PIN_NUMBER='(0,0,0,0,0,0,0,0,0,0,0,0,0,0,0,0,0,0,0,0,0,EE16,0,0,0,0,0,0,0,0)';
      BIDIRECTIONAL='TRUE';
      INPUT_LOAD='(-0.01,0.01)';
      OUTPUT_LOAD='(1.0,-1.0)';
    'RSVD'<7>:
      PIN_NUMBER='(0,0,0,0,0,0,0,0,0,0,0,0,0,0,0,0,0,0,0,0,0,EE46,0,0,0,0,0,0,0,0)';
      BIDIRECTIONAL='TRUE';
      INPUT_LOAD='(-0.01,0.01)';
      OUTPUT_LOAD='(1.0,-1.0)';
    'RSVD'<6>:
      PIN_NUMBER='(0,0,0,0,0,0,0,0,0,0,0,0,0,0,0,0,0,0,0,0,0,EE6,0,0,0,0,0,0,0,0)';
      BIDIRECTIONAL='TRUE';
      INPUT_LOAD='(-0.01,0.01)';
      OUTPUT_LOAD='(1.0,-1.0)';
    'RSVD'<5>:
      PIN_NUMBER='(0,0,0,0,0,0,0,0,0,0,0,0,0,0,0,0,0,0,0,0,0,EE82,0,0,0,0,0,0,0,0)';
      BIDIRECTIONAL='TRUE';
      INPUT_LOAD='(-0.01,0.01)';
      OUTPUT_LOAD='(1.0,-1.0)';
    'RSVD'<4>:
      PIN_NUMBER='(0,0,0,0,0,0,0,0,0,0,0,0,0,0,0,0,0,0,0,0,0,EE84,0,0,0,0,0,0,0,0)';
      BIDIRECTIONAL='TRUE';
      INPUT_LOAD='(-0.01,0.01)';
      OUTPUT_LOAD='(1.0,-1.0)';
    'RSVD'<3>:
      PIN_NUMBER='(0,0,0,0,0,0,0,0,0,0,0,0,0,0,0,0,0,0,0,0,0,EF47,0,0,0,0,0,0,0,0)';
      BIDIRECTIONAL='TRUE';
      INPUT_LOAD='(-0.01,0.01)';
      OUTPUT_LOAD='(1.0,-1.0)';
    'RSVD'<2>:
      PIN_NUMBER='(0,0,0,0,0,0,0,0,0,0,0,0,0,0,0,0,0,0,0,0,0,EF77,0,0,0,0,0,0,0,0)';
      BIDIRECTIONAL='TRUE';
      INPUT_LOAD='(-0.01,0.01)';
      OUTPUT_LOAD='(1.0,-1.0)';
    'RSVD'<1>:
      PIN_NUMBER='(0,0,0,0,0,0,0,0,0,0,0,0,0,0,0,0,0,0,0,0,0,EF81,0,0,0,0,0,0,0,0)';
      BIDIRECTIONAL='TRUE';
      INPUT_LOAD='(-0.01,0.01)';
      OUTPUT_LOAD='(1.0,-1.0)';
    'RSVD'<0>:
      PIN_NUMBER='(0,0,0,0,0,0,0,0,0,0,0,0,0,0,0,0,0,0,0,0,0,EF83,0,0,0,0,0,0,0,0)';
      BIDIRECTIONAL='TRUE';
      INPUT_LOAD='(-0.01,0.01)';
      OUTPUT_LOAD='(1.0,-1.0)';
    'SAFE_MODE_BOOT':
      PIN_NUMBER='(AR18,0,0,0,0,0,0,0,0,0,0,0,0,0,0,0,0,0,0,0,0,0,0,0,0,0,0,0,0,0)';
      INPUT_LOAD='(-0.01,0.01)';
    'SKTOCC_N':
      PIN_NUMBER='(AB13,0,0,0,0,0,0,0,0,0,0,0,0,0,0,0,0,0,0,0,0,0,0,0,0,0,0,0,0,0)';
      OUTPUT_LOAD='(1.0,-1.0)';
    'SMBCLK':
      PIN_NUMBER='(CT59,0,0,0,0,0,0,0,0,0,0,0,0,0,0,0,0,0,0,0,0,0,0,0,0,0,0,0,0,0)';
      BIDIRECTIONAL='TRUE';
      INPUT_LOAD='(-0.01,0.01)';
      OUTPUT_LOAD='(1.0,-1.0)';
    'SMBDAT':
      PIN_NUMBER='(CW58,0,0,0,0,0,0,0,0,0,0,0,0,0,0,0,0,0,0,0,0,0,0,0,0,0,0,0,0,0)';
      BIDIRECTIONAL='TRUE';
      INPUT_LOAD='(-0.01,0.01)';
      OUTPUT_LOAD='(1.0,-1.0)';
    'SM_WP':
      PIN_NUMBER='(CV59,0,0,0,0,0,0,0,0,0,0,0,0,0,0,0,0,0,0,0,0,0,0,0,0,0,0,0,0,0)';
      INPUT_LOAD='(-0.01,0.01)';
    'SOCKET_ID'<2>:
      PIN_NUMBER='(AU20,0,0,0,0,0,0,0,0,0,0,0,0,0,0,0,0,0,0,0,0,0,0,0,0,0,0,0,0,0)';
      INPUT_LOAD='(-0.01,0.01)';
    'SOCKET_ID'<1>:
      PIN_NUMBER='(AU16,0,0,0,0,0,0,0,0,0,0,0,0,0,0,0,0,0,0,0,0,0,0,0,0,0,0,0,0,0)';
      INPUT_LOAD='(-0.01,0.01)';
    'SOCKET_ID'<0>:
      PIN_NUMBER='(AU22,0,0,0,0,0,0,0,0,0,0,0,0,0,0,0,0,0,0,0,0,0,0,0,0,0,0,0,0,0)';
      INPUT_LOAD='(-0.01,0.01)';
    'SVIDALERT_N'<1>:
      PIN_NUMBER='(DL44,0,0,0,0,0,0,0,0,0,0,0,0,0,0,0,0,0,0,0,0,0,0,0,0,0,0,0,0,0)';
      INPUT_LOAD='(-0.01,0.01)';
    'SVIDALERT_N'<0>:
      PIN_NUMBER='(DE44,0,0,0,0,0,0,0,0,0,0,0,0,0,0,0,0,0,0,0,0,0,0,0,0,0,0,0,0,0)';
      INPUT_LOAD='(-0.01,0.01)';
    'SVIDCLK'<1>:
      PIN_NUMBER='(DG44,0,0,0,0,0,0,0,0,0,0,0,0,0,0,0,0,0,0,0,0,0,0,0,0,0,0,0,0,0)';
      OUTPUT_LOAD='(1.0,-1.0)';
    'SVIDCLK'<0>:
      PIN_NUMBER='(DC44,0,0,0,0,0,0,0,0,0,0,0,0,0,0,0,0,0,0,0,0,0,0,0,0,0,0,0,0,0)';
      OUTPUT_LOAD='(1.0,-1.0)';
    'SVIDDATA'<1>:
      PIN_NUMBER='(DJ44,0,0,0,0,0,0,0,0,0,0,0,0,0,0,0,0,0,0,0,0,0,0,0,0,0,0,0,0,0)';
      BIDIRECTIONAL='TRUE';
      INPUT_LOAD='(-0.01,0.01)';
      OUTPUT_LOAD='(1.0,-1.0)';
    'SVIDDATA'<0>:
      PIN_NUMBER='(DB45,0,0,0,0,0,0,0,0,0,0,0,0,0,0,0,0,0,0,0,0,0,0,0,0,0,0,0,0,0)';
      BIDIRECTIONAL='TRUE';
      INPUT_LOAD='(-0.01,0.01)';
      OUTPUT_LOAD='(1.0,-1.0)';
    'TCK':
      PIN_NUMBER='(AA14,0,0,0,0,0,0,0,0,0,0,0,0,0,0,0,0,0,0,0,0,0,0,0,0,0,0,0,0,0)';
      INPUT_LOAD='(-0.01,0.01)';
    'TDI':
      PIN_NUMBER='(AC14,0,0,0,0,0,0,0,0,0,0,0,0,0,0,0,0,0,0,0,0,0,0,0,0,0,0,0,0,0)';
      INPUT_LOAD='(-0.01,0.01)';
    'TDO':
      PIN_NUMBER='(AE14,0,0,0,0,0,0,0,0,0,0,0,0,0,0,0,0,0,0,0,0,0,0,0,0,0,0,0,0,0)';
      OUTPUT_LOAD='(1.0,-1.0)';
    'TEST_1':
      PIN_NUMBER='(0,AF45,0,0,0,0,0,0,0,0,0,0,0,0,0,0,0,0,0,0,0,0,0,0,0,0,0,0,0,0)';
      BIDIRECTIONAL='TRUE';
      INPUT_LOAD='(-0.01,0.01)';
      OUTPUT_LOAD='(1.0,-1.0)';
    'TEST_10':
      PIN_NUMBER='(0,0,0,0,0,0,0,0,0,0,0,0,0,0,0,0,AW22,0,0,0,0,0,0,0,0,0,0,0,0,0)';
      BIDIRECTIONAL='TRUE';
      INPUT_LOAD='(-0.01,0.01)';
      OUTPUT_LOAD='(1.0,-1.0)';
    'TEST_11':
      PIN_NUMBER='(0,AY13,0,0,0,0,0,0,0,0,0,0,0,0,0,0,0,0,0,0,0,0,0,0,0,0,0,0,0,0)';
      BIDIRECTIONAL='TRUE';
      INPUT_LOAD='(-0.01,0.01)';
      OUTPUT_LOAD='(1.0,-1.0)';
    'TEST_12':
      PIN_NUMBER='(AY19,0,0,0,0,0,0,0,0,0,0,0,0,0,0,0,0,0,0,0,0,0,0,0,0,0,0,0,0,0)';
      BIDIRECTIONAL='TRUE';
      INPUT_LOAD='(-0.01,0.01)';
      OUTPUT_LOAD='(1.0,-1.0)';
    'TEST_13':
      PIN_NUMBER='(DB51,0,0,0,0,0,0,0,0,0,0,0,0,0,0,0,0,0,0,0,0,0,0,0,0,0,0,0,0,0)';
      BIDIRECTIONAL='TRUE';
      INPUT_LOAD='(-0.01,0.01)';
      OUTPUT_LOAD='(1.0,-1.0)';
    'TEST_14':
      PIN_NUMBER='(DC50,0,0,0,0,0,0,0,0,0,0,0,0,0,0,0,0,0,0,0,0,0,0,0,0,0,0,0,0,0)';
      BIDIRECTIONAL='TRUE';
      INPUT_LOAD='(-0.01,0.01)';
      OUTPUT_LOAD='(1.0,-1.0)';
    'TEST_15':
      PIN_NUMBER='(AW14,0,0,0,0,0,0,0,0,0,0,0,0,0,0,0,0,0,0,0,0,0,0,0,0,0,0,0,0,0)';
      BIDIRECTIONAL='TRUE';
      INPUT_LOAD='(-0.01,0.01)';
      OUTPUT_LOAD='(1.0,-1.0)';
    'TEST_2':
      PIN_NUMBER='(0,AG46,0,0,0,0,0,0,0,0,0,0,0,0,0,0,0,0,0,0,0,0,0,0,0,0,0,0,0,0)';
      BIDIRECTIONAL='TRUE';
      INPUT_LOAD='(-0.01,0.01)';
      OUTPUT_LOAD='(1.0,-1.0)';
    'TEST_3':
      PIN_NUMBER='(0,AM13,0,0,0,0,0,0,0,0,0,0,0,0,0,0,0,0,0,0,0,0,0,0,0,0,0,0,0,0)';
      BIDIRECTIONAL='TRUE';
      INPUT_LOAD='(-0.01,0.01)';
      OUTPUT_LOAD='(1.0,-1.0)';
    'TEST_4':
      PIN_NUMBER='(0,AN12,0,0,0,0,0,0,0,0,0,0,0,0,0,0,0,0,0,0,0,0,0,0,0,0,0,0,0,0)';
      BIDIRECTIONAL='TRUE';
      INPUT_LOAD='(-0.01,0.01)';
      OUTPUT_LOAD='(1.0,-1.0)';
    'TEST_5':
      PIN_NUMBER='(0,AN14,0,0,0,0,0,0,0,0,0,0,0,0,0,0,0,0,0,0,0,0,0,0,0,0,0,0,0,0)';
      BIDIRECTIONAL='TRUE';
      INPUT_LOAD='(-0.01,0.01)';
      OUTPUT_LOAD='(1.0,-1.0)';
    'TEST_6':
      PIN_NUMBER='(0,0,0,0,0,0,0,0,0,0,0,0,0,0,0,0,AR16,0,0,0,0,0,0,0,0,0,0,0,0,0)';
      BIDIRECTIONAL='TRUE';
      INPUT_LOAD='(-0.01,0.01)';
      OUTPUT_LOAD='(1.0,-1.0)';
    'TEST_7':
      PIN_NUMBER='(0,0,0,0,0,0,0,0,0,0,0,0,0,0,0,0,AU18,0,0,0,0,0,0,0,0,0,0,0,0,0)';
      BIDIRECTIONAL='TRUE';
      INPUT_LOAD='(-0.01,0.01)';
      OUTPUT_LOAD='(1.0,-1.0)';
    'TEST_8':
      PIN_NUMBER='(0,0,0,0,0,0,0,0,0,0,0,0,0,0,0,0,AW16,0,0,0,0,0,0,0,0,0,0,0,0,0)';
      BIDIRECTIONAL='TRUE';
      INPUT_LOAD='(-0.01,0.01)';
      OUTPUT_LOAD='(1.0,-1.0)';
    'TEST_9':
      PIN_NUMBER='(0,0,0,0,0,0,0,0,0,0,0,0,0,0,0,0,AW20,0,0,0,0,0,0,0,0,0,0,0,0,0)';
      BIDIRECTIONAL='TRUE';
      INPUT_LOAD='(-0.01,0.01)';
      OUTPUT_LOAD='(1.0,-1.0)';
    'THERMTRIP_N':
      PIN_NUMBER='(AB15,0,0,0,0,0,0,0,0,0,0,0,0,0,0,0,0,0,0,0,0,0,0,0,0,0,0,0,0,0)';
      OUTPUT_LOAD='(1.0,-1.0)';
    'TMS':
      PIN_NUMBER='(W14,0,0,0,0,0,0,0,0,0,0,0,0,0,0,0,0,0,0,0,0,0,0,0,0,0,0,0,0,0)';
      INPUT_LOAD='(-0.01,0.01)';
    'TRST_N':
      PIN_NUMBER='(Y13,0,0,0,0,0,0,0,0,0,0,0,0,0,0,0,0,0,0,0,0,0,0,0,0,0,0,0,0,0)';
      INPUT_LOAD='(-0.01,0.01)';
    'TSC_SYNC':
      PIN_NUMBER='(AM11,0,0,0,0,0,0,0,0,0,0,0,0,0,0,0,0,0,0,0,0,0,0,0,0,0,0,0,0,0)';
      BIDIRECTIONAL='TRUE';
      INPUT_LOAD='(-0.01,0.01)';
      OUTPUT_LOAD='(1.0,-1.0)';
    'TXT_AGENT':
      PIN_NUMBER='(AW18,0,0,0,0,0,0,0,0,0,0,0,0,0,0,0,0,0,0,0,0,0,0,0,0,0,0,0,0,0)';
      INPUT_LOAD='(-0.01,0.01)';
    'TXT_PLTEN':
      PIN_NUMBER='(AV15,0,0,0,0,0,0,0,0,0,0,0,0,0,0,0,0,0,0,0,0,0,0,0,0,0,0,0,0,0)';
      INPUT_LOAD='(-0.01,0.01)';
    'UPI01_RBIAS'<1>:
      PIN_NUMBER='(AP29,0,0,0,0,0,0,0,0,0,0,0,0,0,0,0,0,0,0,0,0,0,0,0,0,0,0,0,0,0)';
      INPUT_LOAD='(-0.01,0.01)';
    'UPI01_RBIAS'<0>:
      PIN_NUMBER='(AT29,0,0,0,0,0,0,0,0,0,0,0,0,0,0,0,0,0,0,0,0,0,0,0,0,0,0,0,0,0)';
      INPUT_LOAD='(-0.01,0.01)';
    'UPI0_RX_DN'<19>:
      PIN_NUMBER='(0,0,0,0,0,0,0,0,0,0,0,0,BB11,0,0,0,0,0,0,0,0,0,0,0,0,0,0,0,0,0)';
      INPUT_LOAD='(-0.01,0.01)';
    'UPI0_RX_DN'<18>:
      PIN_NUMBER='(0,0,0,0,0,0,0,0,0,0,0,0,BD9,0,0,0,0,0,0,0,0,0,0,0,0,0,0,0,0,0)';
      INPUT_LOAD='(-0.01,0.01)';
    'UPI0_RX_DN'<17>:
      PIN_NUMBER='(0,0,0,0,0,0,0,0,0,0,0,0,AY9,0,0,0,0,0,0,0,0,0,0,0,0,0,0,0,0,0)';
      INPUT_LOAD='(-0.01,0.01)';
    'UPI0_RX_DN'<16>:
      PIN_NUMBER='(0,0,0,0,0,0,0,0,0,0,0,0,AW8,0,0,0,0,0,0,0,0,0,0,0,0,0,0,0,0,0)';
      INPUT_LOAD='(-0.01,0.01)';
    'UPI0_RX_DN'<15>:
      PIN_NUMBER='(0,0,0,0,0,0,0,0,0,0,0,0,BD7,0,0,0,0,0,0,0,0,0,0,0,0,0,0,0,0,0)';
      INPUT_LOAD='(-0.01,0.01)';
    'UPI0_RX_DN'<14>:
      PIN_NUMBER='(0,0,0,0,0,0,0,0,0,0,0,0,BC6,0,0,0,0,0,0,0,0,0,0,0,0,0,0,0,0,0)';
      INPUT_LOAD='(-0.01,0.01)';
    'UPI0_RX_DN'<13>:
      PIN_NUMBER='(0,0,0,0,0,0,0,0,0,0,0,0,BA8,0,0,0,0,0,0,0,0,0,0,0,0,0,0,0,0,0)';
      INPUT_LOAD='(-0.01,0.01)';
    'UPI0_RX_DN'<12>:
      PIN_NUMBER='(0,0,0,0,0,0,0,0,0,0,0,0,AU10,0,0,0,0,0,0,0,0,0,0,0,0,0,0,0,0,0)';
      INPUT_LOAD='(-0.01,0.01)';
    'UPI0_RX_DN'<11>:
      PIN_NUMBER='(0,0,0,0,0,0,0,0,0,0,0,0,AR8,0,0,0,0,0,0,0,0,0,0,0,0,0,0,0,0,0)';
      INPUT_LOAD='(-0.01,0.01)';
    'UPI0_RX_DN'<10>:
      PIN_NUMBER='(0,0,0,0,0,0,0,0,0,0,0,0,AP7,0,0,0,0,0,0,0,0,0,0,0,0,0,0,0,0,0)';
      INPUT_LOAD='(-0.01,0.01)';
    'UPI0_RX_DN'<9>:
      PIN_NUMBER='(0,0,0,0,0,0,0,0,0,0,0,0,AM9,0,0,0,0,0,0,0,0,0,0,0,0,0,0,0,0,0)';
      INPUT_LOAD='(-0.01,0.01)';
    'UPI0_RX_DN'<8>:
      PIN_NUMBER='(0,0,0,0,0,0,0,0,0,0,0,0,AK7,0,0,0,0,0,0,0,0,0,0,0,0,0,0,0,0,0)';
      INPUT_LOAD='(-0.01,0.01)';
    'UPI0_RX_DN'<7>:
      PIN_NUMBER='(0,0,0,0,0,0,0,0,0,0,0,0,AL6,0,0,0,0,0,0,0,0,0,0,0,0,0,0,0,0,0)';
      INPUT_LOAD='(-0.01,0.01)';
    'UPI0_RX_DN'<6>:
      PIN_NUMBER='(0,0,0,0,0,0,0,0,0,0,0,0,AJ6,0,0,0,0,0,0,0,0,0,0,0,0,0,0,0,0,0)';
      INPUT_LOAD='(-0.01,0.01)';
    'UPI0_RX_DN'<5>:
      PIN_NUMBER='(0,0,0,0,0,0,0,0,0,0,0,0,AG8,0,0,0,0,0,0,0,0,0,0,0,0,0,0,0,0,0)';
      INPUT_LOAD='(-0.01,0.01)';
    'UPI0_RX_DN'<4>:
      PIN_NUMBER='(0,0,0,0,0,0,0,0,0,0,0,0,AE6,0,0,0,0,0,0,0,0,0,0,0,0,0,0,0,0,0)';
      INPUT_LOAD='(-0.01,0.01)';
    'UPI0_RX_DN'<3>:
      PIN_NUMBER='(0,0,0,0,0,0,0,0,0,0,0,0,AD5,0,0,0,0,0,0,0,0,0,0,0,0,0,0,0,0,0)';
      INPUT_LOAD='(-0.01,0.01)';
    'UPI0_RX_DN'<2>:
      PIN_NUMBER='(0,0,0,0,0,0,0,0,0,0,0,0,AB7,0,0,0,0,0,0,0,0,0,0,0,0,0,0,0,0,0)';
      INPUT_LOAD='(-0.01,0.01)';
    'UPI0_RX_DN'<1>:
      PIN_NUMBER='(0,0,0,0,0,0,0,0,0,0,0,0,AA8,0,0,0,0,0,0,0,0,0,0,0,0,0,0,0,0,0)';
      INPUT_LOAD='(-0.01,0.01)';
    'UPI0_RX_DN'<0>:
      PIN_NUMBER='(0,0,0,0,0,0,0,0,0,0,0,0,AC10,0,0,0,0,0,0,0,0,0,0,0,0,0,0,0,0,0)';
      INPUT_LOAD='(-0.01,0.01)';
    'UPI0_RX_DP'<19>:
      PIN_NUMBER='(0,0,0,0,0,0,0,0,0,0,0,0,BA10,0,0,0,0,0,0,0,0,0,0,0,0,0,0,0,0,0)';
      INPUT_LOAD='(-0.01,0.01)';
    'UPI0_RX_DP'<18>:
      PIN_NUMBER='(0,0,0,0,0,0,0,0,0,0,0,0,BC10,0,0,0,0,0,0,0,0,0,0,0,0,0,0,0,0,0)';
      INPUT_LOAD='(-0.01,0.01)';
    'UPI0_RX_DP'<17>:
      PIN_NUMBER='(0,0,0,0,0,0,0,0,0,0,0,0,BB9,0,0,0,0,0,0,0,0,0,0,0,0,0,0,0,0,0)';
      INPUT_LOAD='(-0.01,0.01)';
    'UPI0_RX_DP'<16>:
      PIN_NUMBER='(0,0,0,0,0,0,0,0,0,0,0,0,AV9,0,0,0,0,0,0,0,0,0,0,0,0,0,0,0,0,0)';
      INPUT_LOAD='(-0.01,0.01)';
    'UPI0_RX_DP'<15>:
      PIN_NUMBER='(0,0,0,0,0,0,0,0,0,0,0,0,BF7,0,0,0,0,0,0,0,0,0,0,0,0,0,0,0,0,0)';
      INPUT_LOAD='(-0.01,0.01)';
    'UPI0_RX_DP'<14>:
      PIN_NUMBER='(0,0,0,0,0,0,0,0,0,0,0,0,BB7,0,0,0,0,0,0,0,0,0,0,0,0,0,0,0,0,0)';
      INPUT_LOAD='(-0.01,0.01)';
    'UPI0_RX_DP'<13>:
      PIN_NUMBER='(0,0,0,0,0,0,0,0,0,0,0,0,AY7,0,0,0,0,0,0,0,0,0,0,0,0,0,0,0,0,0)';
      INPUT_LOAD='(-0.01,0.01)';
    'UPI0_RX_DP'<12>:
      PIN_NUMBER='(0,0,0,0,0,0,0,0,0,0,0,0,AT9,0,0,0,0,0,0,0,0,0,0,0,0,0,0,0,0,0)';
      INPUT_LOAD='(-0.01,0.01)';
    'UPI0_RX_DP'<11>:
      PIN_NUMBER='(0,0,0,0,0,0,0,0,0,0,0,0,AU8,0,0,0,0,0,0,0,0,0,0,0,0,0,0,0,0,0)';
      INPUT_LOAD='(-0.01,0.01)';
    'UPI0_RX_DP'<10>:
      PIN_NUMBER='(0,0,0,0,0,0,0,0,0,0,0,0,AN8,0,0,0,0,0,0,0,0,0,0,0,0,0,0,0,0,0)';
      INPUT_LOAD='(-0.01,0.01)';
    'UPI0_RX_DP'<9>:
      PIN_NUMBER='(0,0,0,0,0,0,0,0,0,0,0,0,AL8,0,0,0,0,0,0,0,0,0,0,0,0,0,0,0,0,0)';
      INPUT_LOAD='(-0.01,0.01)';
    'UPI0_RX_DP'<8>:
      PIN_NUMBER='(0,0,0,0,0,0,0,0,0,0,0,0,AM7,0,0,0,0,0,0,0,0,0,0,0,0,0,0,0,0,0)';
      INPUT_LOAD='(-0.01,0.01)';
    'UPI0_RX_DP'<7>:
      PIN_NUMBER='(0,0,0,0,0,0,0,0,0,0,0,0,AK5,0,0,0,0,0,0,0,0,0,0,0,0,0,0,0,0,0)';
      INPUT_LOAD='(-0.01,0.01)';
    'UPI0_RX_DP'<6>:
      PIN_NUMBER='(0,0,0,0,0,0,0,0,0,0,0,0,AH7,0,0,0,0,0,0,0,0,0,0,0,0,0,0,0,0,0)';
      INPUT_LOAD='(-0.01,0.01)';
    'UPI0_RX_DP'<5>:
      PIN_NUMBER='(0,0,0,0,0,0,0,0,0,0,0,0,AF7,0,0,0,0,0,0,0,0,0,0,0,0,0,0,0,0,0)';
      INPUT_LOAD='(-0.01,0.01)';
    'UPI0_RX_DP'<4>:
      PIN_NUMBER='(0,0,0,0,0,0,0,0,0,0,0,0,AG6,0,0,0,0,0,0,0,0,0,0,0,0,0,0,0,0,0)';
      INPUT_LOAD='(-0.01,0.01)';
    'UPI0_RX_DP'<3>:
      PIN_NUMBER='(0,0,0,0,0,0,0,0,0,0,0,0,AC6,0,0,0,0,0,0,0,0,0,0,0,0,0,0,0,0,0)';
      INPUT_LOAD='(-0.01,0.01)';
    'UPI0_RX_DP'<2>:
      PIN_NUMBER='(0,0,0,0,0,0,0,0,0,0,0,0,AA6,0,0,0,0,0,0,0,0,0,0,0,0,0,0,0,0,0)';
      INPUT_LOAD='(-0.01,0.01)';
    'UPI0_RX_DP'<1>:
      PIN_NUMBER='(0,0,0,0,0,0,0,0,0,0,0,0,AC8,0,0,0,0,0,0,0,0,0,0,0,0,0,0,0,0,0)';
      INPUT_LOAD='(-0.01,0.01)';
    'UPI0_RX_DP'<0>:
      PIN_NUMBER='(0,0,0,0,0,0,0,0,0,0,0,0,AB9,0,0,0,0,0,0,0,0,0,0,0,0,0,0,0,0,0)';
      INPUT_LOAD='(-0.01,0.01)';
    'UPI0_TX_DN'<19>:
      PIN_NUMBER='(0,0,0,0,0,0,0,0,0,0,0,0,BG4,0,0,0,0,0,0,0,0,0,0,0,0,0,0,0,0,0)';
      OUTPUT_LOAD='(1.0,-1.0)';
    'UPI0_TX_DN'<18>:
      PIN_NUMBER='(0,0,0,0,0,0,0,0,0,0,0,0,BF3,0,0,0,0,0,0,0,0,0,0,0,0,0,0,0,0,0)';
      OUTPUT_LOAD='(1.0,-1.0)';
    'UPI0_TX_DN'<17>:
      PIN_NUMBER='(0,0,0,0,0,0,0,0,0,0,0,0,BB3,0,0,0,0,0,0,0,0,0,0,0,0,0,0,0,0,0)';
      OUTPUT_LOAD='(1.0,-1.0)';
    'UPI0_TX_DN'<16>:
      PIN_NUMBER='(0,0,0,0,0,0,0,0,0,0,0,0,BA4,0,0,0,0,0,0,0,0,0,0,0,0,0,0,0,0,0)';
      OUTPUT_LOAD='(1.0,-1.0)';
    'UPI0_TX_DN'<15>:
      PIN_NUMBER='(0,0,0,0,0,0,0,0,0,0,0,0,AV5,0,0,0,0,0,0,0,0,0,0,0,0,0,0,0,0,0)';
      OUTPUT_LOAD='(1.0,-1.0)';
    'UPI0_TX_DN'<14>:
      PIN_NUMBER='(0,0,0,0,0,0,0,0,0,0,0,0,AU4,0,0,0,0,0,0,0,0,0,0,0,0,0,0,0,0,0)';
      OUTPUT_LOAD='(1.0,-1.0)';
    'UPI0_TX_DN'<13>:
      PIN_NUMBER='(0,0,0,0,0,0,0,0,0,0,0,0,AT3,0,0,0,0,0,0,0,0,0,0,0,0,0,0,0,0,0)';
      OUTPUT_LOAD='(1.0,-1.0)';
    'UPI0_TX_DN'<12>:
      PIN_NUMBER='(0,0,0,0,0,0,0,0,0,0,0,0,AT1,0,0,0,0,0,0,0,0,0,0,0,0,0,0,0,0,0)';
      OUTPUT_LOAD='(1.0,-1.0)';
    'UPI0_TX_DN'<11>:
      PIN_NUMBER='(0,0,0,0,0,0,0,0,0,0,0,0,AN4,0,0,0,0,0,0,0,0,0,0,0,0,0,0,0,0,0)';
      OUTPUT_LOAD='(1.0,-1.0)';
    'UPI0_TX_DN'<10>:
      PIN_NUMBER='(0,0,0,0,0,0,0,0,0,0,0,0,AM3,0,0,0,0,0,0,0,0,0,0,0,0,0,0,0,0,0)';
      OUTPUT_LOAD='(1.0,-1.0)';
    'UPI0_TX_DN'<9>:
      PIN_NUMBER='(0,0,0,0,0,0,0,0,0,0,0,0,AL2,0,0,0,0,0,0,0,0,0,0,0,0,0,0,0,0,0)';
      OUTPUT_LOAD='(1.0,-1.0)';
    'UPI0_TX_DN'<8>:
      PIN_NUMBER='(0,0,0,0,0,0,0,0,0,0,0,0,AH3,0,0,0,0,0,0,0,0,0,0,0,0,0,0,0,0,0)';
      OUTPUT_LOAD='(1.0,-1.0)';
    'UPI0_TX_DN'<7>:
      PIN_NUMBER='(0,0,0,0,0,0,0,0,0,0,0,0,AE2,0,0,0,0,0,0,0,0,0,0,0,0,0,0,0,0,0)';
      OUTPUT_LOAD='(1.0,-1.0)';
    'UPI0_TX_DN'<6>:
      PIN_NUMBER='(0,0,0,0,0,0,0,0,0,0,0,0,AG4,0,0,0,0,0,0,0,0,0,0,0,0,0,0,0,0,0)';
      OUTPUT_LOAD='(1.0,-1.0)';
    'UPI0_TX_DN'<5>:
      PIN_NUMBER='(0,0,0,0,0,0,0,0,0,0,0,0,AC2,0,0,0,0,0,0,0,0,0,0,0,0,0,0,0,0,0)';
      OUTPUT_LOAD='(1.0,-1.0)';
    'UPI0_TX_DN'<4>:
      PIN_NUMBER='(0,0,0,0,0,0,0,0,0,0,0,0,AB3,0,0,0,0,0,0,0,0,0,0,0,0,0,0,0,0,0)';
      OUTPUT_LOAD='(1.0,-1.0)';
    'UPI0_TX_DN'<3>:
      PIN_NUMBER='(0,0,0,0,0,0,0,0,0,0,0,0,Y1,0,0,0,0,0,0,0,0,0,0,0,0,0,0,0,0,0)';
      OUTPUT_LOAD='(1.0,-1.0)';
    'UPI0_TX_DN'<2>:
      PIN_NUMBER='(0,0,0,0,0,0,0,0,0,0,0,0,V3,0,0,0,0,0,0,0,0,0,0,0,0,0,0,0,0,0)';
      OUTPUT_LOAD='(1.0,-1.0)';
    'UPI0_TX_DN'<1>:
      PIN_NUMBER='(0,0,0,0,0,0,0,0,0,0,0,0,P1,0,0,0,0,0,0,0,0,0,0,0,0,0,0,0,0,0)';
      OUTPUT_LOAD='(1.0,-1.0)';
    'UPI0_TX_DN'<0>:
      PIN_NUMBER='(0,0,0,0,0,0,0,0,0,0,0,0,N2,0,0,0,0,0,0,0,0,0,0,0,0,0,0,0,0,0)';
      OUTPUT_LOAD='(1.0,-1.0)';
    'UPI0_TX_DP'<19>:
      PIN_NUMBER='(0,0,0,0,0,0,0,0,0,0,0,0,BH3,0,0,0,0,0,0,0,0,0,0,0,0,0,0,0,0,0)';
      OUTPUT_LOAD='(1.0,-1.0)';
    'UPI0_TX_DP'<18>:
      PIN_NUMBER='(0,0,0,0,0,0,0,0,0,0,0,0,BD3,0,0,0,0,0,0,0,0,0,0,0,0,0,0,0,0,0)';
      OUTPUT_LOAD='(1.0,-1.0)';
    'UPI0_TX_DP'<17>:
      PIN_NUMBER='(0,0,0,0,0,0,0,0,0,0,0,0,BC2,0,0,0,0,0,0,0,0,0,0,0,0,0,0,0,0,0)';
      OUTPUT_LOAD='(1.0,-1.0)';
    'UPI0_TX_DP'<16>:
      PIN_NUMBER='(0,0,0,0,0,0,0,0,0,0,0,0,AY3,0,0,0,0,0,0,0,0,0,0,0,0,0,0,0,0,0)';
      OUTPUT_LOAD='(1.0,-1.0)';
    'UPI0_TX_DP'<15>:
      PIN_NUMBER='(0,0,0,0,0,0,0,0,0,0,0,0,AW4,0,0,0,0,0,0,0,0,0,0,0,0,0,0,0,0,0)';
      OUTPUT_LOAD='(1.0,-1.0)';
    'UPI0_TX_DP'<14>:
      PIN_NUMBER='(0,0,0,0,0,0,0,0,0,0,0,0,AR4,0,0,0,0,0,0,0,0,0,0,0,0,0,0,0,0,0)';
      OUTPUT_LOAD='(1.0,-1.0)';
    'UPI0_TX_DP'<13>:
      PIN_NUMBER='(0,0,0,0,0,0,0,0,0,0,0,0,AR2,0,0,0,0,0,0,0,0,0,0,0,0,0,0,0,0,0)';
      OUTPUT_LOAD='(1.0,-1.0)';
    'UPI0_TX_DP'<12>:
      PIN_NUMBER='(0,0,0,0,0,0,0,0,0,0,0,0,AP1,0,0,0,0,0,0,0,0,0,0,0,0,0,0,0,0,0)';
      OUTPUT_LOAD='(1.0,-1.0)';
    'UPI0_TX_DP'<11>:
      PIN_NUMBER='(0,0,0,0,0,0,0,0,0,0,0,0,AP3,0,0,0,0,0,0,0,0,0,0,0,0,0,0,0,0,0)';
      OUTPUT_LOAD='(1.0,-1.0)';
    'UPI0_TX_DP'<10>:
      PIN_NUMBER='(0,0,0,0,0,0,0,0,0,0,0,0,AK3,0,0,0,0,0,0,0,0,0,0,0,0,0,0,0,0,0)';
      OUTPUT_LOAD='(1.0,-1.0)';
    'UPI0_TX_DP'<9>:
      PIN_NUMBER='(0,0,0,0,0,0,0,0,0,0,0,0,AK1,0,0,0,0,0,0,0,0,0,0,0,0,0,0,0,0,0)';
      OUTPUT_LOAD='(1.0,-1.0)';
    'UPI0_TX_DP'<8>:
      PIN_NUMBER='(0,0,0,0,0,0,0,0,0,0,0,0,AJ2,0,0,0,0,0,0,0,0,0,0,0,0,0,0,0,0,0)';
      OUTPUT_LOAD='(1.0,-1.0)';
    'UPI0_TX_DP'<7>:
      PIN_NUMBER='(0,0,0,0,0,0,0,0,0,0,0,0,AG2,0,0,0,0,0,0,0,0,0,0,0,0,0,0,0,0,0)';
      OUTPUT_LOAD='(1.0,-1.0)';
    'UPI0_TX_DP'<6>:
      PIN_NUMBER='(0,0,0,0,0,0,0,0,0,0,0,0,AF3,0,0,0,0,0,0,0,0,0,0,0,0,0,0,0,0,0)';
      OUTPUT_LOAD='(1.0,-1.0)';
    'UPI0_TX_DP'<5>:
      PIN_NUMBER='(0,0,0,0,0,0,0,0,0,0,0,0,AD1,0,0,0,0,0,0,0,0,0,0,0,0,0,0,0,0,0)';
      OUTPUT_LOAD='(1.0,-1.0)';
    'UPI0_TX_DP'<4>:
      PIN_NUMBER='(0,0,0,0,0,0,0,0,0,0,0,0,AA2,0,0,0,0,0,0,0,0,0,0,0,0,0,0,0,0,0)';
      OUTPUT_LOAD='(1.0,-1.0)';
    'UPI0_TX_DP'<3>:
      PIN_NUMBER='(0,0,0,0,0,0,0,0,0,0,0,0,W2,0,0,0,0,0,0,0,0,0,0,0,0,0,0,0,0,0)';
      OUTPUT_LOAD='(1.0,-1.0)';
    'UPI0_TX_DP'<2>:
      PIN_NUMBER='(0,0,0,0,0,0,0,0,0,0,0,0,Y3,0,0,0,0,0,0,0,0,0,0,0,0,0,0,0,0,0)';
      OUTPUT_LOAD='(1.0,-1.0)';
    'UPI0_TX_DP'<1>:
      PIN_NUMBER='(0,0,0,0,0,0,0,0,0,0,0,0,T1,0,0,0,0,0,0,0,0,0,0,0,0,0,0,0,0,0)';
      OUTPUT_LOAD='(1.0,-1.0)';
    'UPI0_TX_DP'<0>:
      PIN_NUMBER='(0,0,0,0,0,0,0,0,0,0,0,0,M1,0,0,0,0,0,0,0,0,0,0,0,0,0,0,0,0,0)';
      OUTPUT_LOAD='(1.0,-1.0)';
    'UPI1_RX_DN'<19>:
      PIN_NUMBER='(0,0,0,0,0,0,0,0,0,0,0,0,0,AB19,0,0,0,0,0,0,0,0,0,0,0,0,0,0,0,0)';
      INPUT_LOAD='(-0.01,0.01)';
    'UPI1_RX_DN'<18>:
      PIN_NUMBER='(0,0,0,0,0,0,0,0,0,0,0,0,0,Y21,0,0,0,0,0,0,0,0,0,0,0,0,0,0,0,0)';
      INPUT_LOAD='(-0.01,0.01)';
    'UPI1_RX_DN'<17>:
      PIN_NUMBER='(0,0,0,0,0,0,0,0,0,0,0,0,0,V19,0,0,0,0,0,0,0,0,0,0,0,0,0,0,0,0)';
      INPUT_LOAD='(-0.01,0.01)';
    'UPI1_RX_DN'<16>:
      PIN_NUMBER='(0,0,0,0,0,0,0,0,0,0,0,0,0,P21,0,0,0,0,0,0,0,0,0,0,0,0,0,0,0,0)';
      INPUT_LOAD='(-0.01,0.01)';
    'UPI1_RX_DN'<15>:
      PIN_NUMBER='(0,0,0,0,0,0,0,0,0,0,0,0,0,U18,0,0,0,0,0,0,0,0,0,0,0,0,0,0,0,0)';
      INPUT_LOAD='(-0.01,0.01)';
    'UPI1_RX_DN'<14>:
      PIN_NUMBER='(0,0,0,0,0,0,0,0,0,0,0,0,0,R20,0,0,0,0,0,0,0,0,0,0,0,0,0,0,0,0)';
      INPUT_LOAD='(-0.01,0.01)';
    'UPI1_RX_DN'<13>:
      PIN_NUMBER='(0,0,0,0,0,0,0,0,0,0,0,0,0,W18,0,0,0,0,0,0,0,0,0,0,0,0,0,0,0,0)';
      INPUT_LOAD='(-0.01,0.01)';
    'UPI1_RX_DN'<12>:
      PIN_NUMBER='(0,0,0,0,0,0,0,0,0,0,0,0,0,U16,0,0,0,0,0,0,0,0,0,0,0,0,0,0,0,0)';
      INPUT_LOAD='(-0.01,0.01)';
    'UPI1_RX_DN'<11>:
      PIN_NUMBER='(0,0,0,0,0,0,0,0,0,0,0,0,0,P17,0,0,0,0,0,0,0,0,0,0,0,0,0,0,0,0)';
      INPUT_LOAD='(-0.01,0.01)';
    'UPI1_RX_DN'<10>:
      PIN_NUMBER='(0,0,0,0,0,0,0,0,0,0,0,0,0,R16,0,0,0,0,0,0,0,0,0,0,0,0,0,0,0,0)';
      INPUT_LOAD='(-0.01,0.01)';
    'UPI1_RX_DN'<9>:
      PIN_NUMBER='(0,0,0,0,0,0,0,0,0,0,0,0,0,R12,0,0,0,0,0,0,0,0,0,0,0,0,0,0,0,0)';
      INPUT_LOAD='(-0.01,0.01)';
    'UPI1_RX_DN'<8>:
      PIN_NUMBER='(0,0,0,0,0,0,0,0,0,0,0,0,0,N14,0,0,0,0,0,0,0,0,0,0,0,0,0,0,0,0)';
      INPUT_LOAD='(-0.01,0.01)';
    'UPI1_RX_DN'<7>:
      PIN_NUMBER='(0,0,0,0,0,0,0,0,0,0,0,0,0,L12,0,0,0,0,0,0,0,0,0,0,0,0,0,0,0,0)';
      INPUT_LOAD='(-0.01,0.01)';
    'UPI1_RX_DN'<6>:
      PIN_NUMBER='(0,0,0,0,0,0,0,0,0,0,0,0,0,U12,0,0,0,0,0,0,0,0,0,0,0,0,0,0,0,0)';
      INPUT_LOAD='(-0.01,0.01)';
    'UPI1_RX_DN'<5>:
      PIN_NUMBER='(0,0,0,0,0,0,0,0,0,0,0,0,0,R10,0,0,0,0,0,0,0,0,0,0,0,0,0,0,0,0)';
      INPUT_LOAD='(-0.01,0.01)';
    'UPI1_RX_DN'<4>:
      PIN_NUMBER='(0,0,0,0,0,0,0,0,0,0,0,0,0,P9,0,0,0,0,0,0,0,0,0,0,0,0,0,0,0,0)';
      INPUT_LOAD='(-0.01,0.01)';
    'UPI1_RX_DN'<3>:
      PIN_NUMBER='(0,0,0,0,0,0,0,0,0,0,0,0,0,T9,0,0,0,0,0,0,0,0,0,0,0,0,0,0,0,0)';
      INPUT_LOAD='(-0.01,0.01)';
    'UPI1_RX_DN'<2>:
      PIN_NUMBER='(0,0,0,0,0,0,0,0,0,0,0,0,0,V7,0,0,0,0,0,0,0,0,0,0,0,0,0,0,0,0)';
      INPUT_LOAD='(-0.01,0.01)';
    'UPI1_RX_DN'<1>:
      PIN_NUMBER='(0,0,0,0,0,0,0,0,0,0,0,0,0,P7,0,0,0,0,0,0,0,0,0,0,0,0,0,0,0,0)';
      INPUT_LOAD='(-0.01,0.01)';
    'UPI1_RX_DN'<0>:
      PIN_NUMBER='(0,0,0,0,0,0,0,0,0,0,0,0,0,T5,0,0,0,0,0,0,0,0,0,0,0,0,0,0,0,0)';
      INPUT_LOAD='(-0.01,0.01)';
    'UPI1_RX_DP'<19>:
      PIN_NUMBER='(0,0,0,0,0,0,0,0,0,0,0,0,0,AA20,0,0,0,0,0,0,0,0,0,0,0,0,0,0,0,0)';
      INPUT_LOAD='(-0.01,0.01)';
    'UPI1_RX_DP'<18>:
      PIN_NUMBER='(0,0,0,0,0,0,0,0,0,0,0,0,0,W20,0,0,0,0,0,0,0,0,0,0,0,0,0,0,0,0)';
      INPUT_LOAD='(-0.01,0.01)';
    'UPI1_RX_DP'<17>:
      PIN_NUMBER='(0,0,0,0,0,0,0,0,0,0,0,0,0,Y19,0,0,0,0,0,0,0,0,0,0,0,0,0,0,0,0)';
      INPUT_LOAD='(-0.01,0.01)';
    'UPI1_RX_DP'<16>:
      PIN_NUMBER='(0,0,0,0,0,0,0,0,0,0,0,0,0,T21,0,0,0,0,0,0,0,0,0,0,0,0,0,0,0,0)';
      INPUT_LOAD='(-0.01,0.01)';
    'UPI1_RX_DP'<15>:
      PIN_NUMBER='(0,0,0,0,0,0,0,0,0,0,0,0,0,T19,0,0,0,0,0,0,0,0,0,0,0,0,0,0,0,0)';
      INPUT_LOAD='(-0.01,0.01)';
    'UPI1_RX_DP'<14>:
      PIN_NUMBER='(0,0,0,0,0,0,0,0,0,0,0,0,0,P19,0,0,0,0,0,0,0,0,0,0,0,0,0,0,0,0)';
      INPUT_LOAD='(-0.01,0.01)';
    'UPI1_RX_DP'<13>:
      PIN_NUMBER='(0,0,0,0,0,0,0,0,0,0,0,0,0,V17,0,0,0,0,0,0,0,0,0,0,0,0,0,0,0,0)';
      INPUT_LOAD='(-0.01,0.01)';
    'UPI1_RX_DP'<12>:
      PIN_NUMBER='(0,0,0,0,0,0,0,0,0,0,0,0,0,W16,0,0,0,0,0,0,0,0,0,0,0,0,0,0,0,0)';
      INPUT_LOAD='(-0.01,0.01)';
    'UPI1_RX_DP'<11>:
      PIN_NUMBER='(0,0,0,0,0,0,0,0,0,0,0,0,0,N16,0,0,0,0,0,0,0,0,0,0,0,0,0,0,0,0)';
      INPUT_LOAD='(-0.01,0.01)';
    'UPI1_RX_DP'<10>:
      PIN_NUMBER='(0,0,0,0,0,0,0,0,0,0,0,0,0,T15,0,0,0,0,0,0,0,0,0,0,0,0,0,0,0,0)';
      INPUT_LOAD='(-0.01,0.01)';
    'UPI1_RX_DP'<9>:
      PIN_NUMBER='(0,0,0,0,0,0,0,0,0,0,0,0,0,P13,0,0,0,0,0,0,0,0,0,0,0,0,0,0,0,0)';
      INPUT_LOAD='(-0.01,0.01)';
    'UPI1_RX_DP'<8>:
      PIN_NUMBER='(0,0,0,0,0,0,0,0,0,0,0,0,0,M13,0,0,0,0,0,0,0,0,0,0,0,0,0,0,0,0)';
      INPUT_LOAD='(-0.01,0.01)';
    'UPI1_RX_DP'<7>:
      PIN_NUMBER='(0,0,0,0,0,0,0,0,0,0,0,0,0,N12,0,0,0,0,0,0,0,0,0,0,0,0,0,0,0,0)';
      INPUT_LOAD='(-0.01,0.01)';
    'UPI1_RX_DP'<6>:
      PIN_NUMBER='(0,0,0,0,0,0,0,0,0,0,0,0,0,T11,0,0,0,0,0,0,0,0,0,0,0,0,0,0,0,0)';
      INPUT_LOAD='(-0.01,0.01)';
    'UPI1_RX_DP'<5>:
      PIN_NUMBER='(0,0,0,0,0,0,0,0,0,0,0,0,0,U10,0,0,0,0,0,0,0,0,0,0,0,0,0,0,0,0)';
      INPUT_LOAD='(-0.01,0.01)';
    'UPI1_RX_DP'<4>:
      PIN_NUMBER='(0,0,0,0,0,0,0,0,0,0,0,0,0,N10,0,0,0,0,0,0,0,0,0,0,0,0,0,0,0,0)';
      INPUT_LOAD='(-0.01,0.01)';
    'UPI1_RX_DP'<3>:
      PIN_NUMBER='(0,0,0,0,0,0,0,0,0,0,0,0,0,R8,0,0,0,0,0,0,0,0,0,0,0,0,0,0,0,0)';
      INPUT_LOAD='(-0.01,0.01)';
    'UPI1_RX_DP'<2>:
      PIN_NUMBER='(0,0,0,0,0,0,0,0,0,0,0,0,0,U8,0,0,0,0,0,0,0,0,0,0,0,0,0,0,0,0)';
      INPUT_LOAD='(-0.01,0.01)';
    'UPI1_RX_DP'<1>:
      PIN_NUMBER='(0,0,0,0,0,0,0,0,0,0,0,0,0,T7,0,0,0,0,0,0,0,0,0,0,0,0,0,0,0,0)';
      INPUT_LOAD='(-0.01,0.01)';
    'UPI1_RX_DP'<0>:
      PIN_NUMBER='(0,0,0,0,0,0,0,0,0,0,0,0,0,R6,0,0,0,0,0,0,0,0,0,0,0,0,0,0,0,0)';
      INPUT_LOAD='(-0.01,0.01)';
    'UPI1_TX_DN'<19>:
      PIN_NUMBER='(0,0,0,0,0,0,0,0,0,0,0,0,0,H21,0,0,0,0,0,0,0,0,0,0,0,0,0,0,0,0)';
      OUTPUT_LOAD='(1.0,-1.0)';
    'UPI1_TX_DN'<18>:
      PIN_NUMBER='(0,0,0,0,0,0,0,0,0,0,0,0,0,F21,0,0,0,0,0,0,0,0,0,0,0,0,0,0,0,0)';
      OUTPUT_LOAD='(1.0,-1.0)';
    'UPI1_TX_DN'<17>:
      PIN_NUMBER='(0,0,0,0,0,0,0,0,0,0,0,0,0,J20,0,0,0,0,0,0,0,0,0,0,0,0,0,0,0,0)';
      OUTPUT_LOAD='(1.0,-1.0)';
    'UPI1_TX_DN'<16>:
      PIN_NUMBER='(0,0,0,0,0,0,0,0,0,0,0,0,0,G18,0,0,0,0,0,0,0,0,0,0,0,0,0,0,0,0)';
      OUTPUT_LOAD='(1.0,-1.0)';
    'UPI1_TX_DN'<15>:
      PIN_NUMBER='(0,0,0,0,0,0,0,0,0,0,0,0,0,K19,0,0,0,0,0,0,0,0,0,0,0,0,0,0,0,0)';
      OUTPUT_LOAD='(1.0,-1.0)';
    'UPI1_TX_DN'<14>:
      PIN_NUMBER='(0,0,0,0,0,0,0,0,0,0,0,0,0,H17,0,0,0,0,0,0,0,0,0,0,0,0,0,0,0,0)';
      OUTPUT_LOAD='(1.0,-1.0)';
    'UPI1_TX_DN'<13>:
      PIN_NUMBER='(0,0,0,0,0,0,0,0,0,0,0,0,0,F15,0,0,0,0,0,0,0,0,0,0,0,0,0,0,0,0)';
      OUTPUT_LOAD='(1.0,-1.0)';
    'UPI1_TX_DN'<12>:
      PIN_NUMBER='(0,0,0,0,0,0,0,0,0,0,0,0,0,D15,0,0,0,0,0,0,0,0,0,0,0,0,0,0,0,0)';
      OUTPUT_LOAD='(1.0,-1.0)';
    'UPI1_TX_DN'<11>:
      PIN_NUMBER='(0,0,0,0,0,0,0,0,0,0,0,0,0,G14,0,0,0,0,0,0,0,0,0,0,0,0,0,0,0,0)';
      OUTPUT_LOAD='(1.0,-1.0)';
    'UPI1_TX_DN'<10>:
      PIN_NUMBER='(0,0,0,0,0,0,0,0,0,0,0,0,0,E12,0,0,0,0,0,0,0,0,0,0,0,0,0,0,0,0)';
      OUTPUT_LOAD='(1.0,-1.0)';
    'UPI1_TX_DN'<9>:
      PIN_NUMBER='(0,0,0,0,0,0,0,0,0,0,0,0,0,G10,0,0,0,0,0,0,0,0,0,0,0,0,0,0,0,0)';
      OUTPUT_LOAD='(1.0,-1.0)';
    'UPI1_TX_DN'<8>:
      PIN_NUMBER='(0,0,0,0,0,0,0,0,0,0,0,0,0,F11,0,0,0,0,0,0,0,0,0,0,0,0,0,0,0,0)';
      OUTPUT_LOAD='(1.0,-1.0)';
    'UPI1_TX_DN'<7>:
      PIN_NUMBER='(0,0,0,0,0,0,0,0,0,0,0,0,0,D9,0,0,0,0,0,0,0,0,0,0,0,0,0,0,0,0)';
      OUTPUT_LOAD='(1.0,-1.0)';
    'UPI1_TX_DN'<6>:
      PIN_NUMBER='(0,0,0,0,0,0,0,0,0,0,0,0,0,K9,0,0,0,0,0,0,0,0,0,0,0,0,0,0,0,0)';
      OUTPUT_LOAD='(1.0,-1.0)';
    'UPI1_TX_DN'<5>:
      PIN_NUMBER='(0,0,0,0,0,0,0,0,0,0,0,0,0,H7,0,0,0,0,0,0,0,0,0,0,0,0,0,0,0,0)';
      OUTPUT_LOAD='(1.0,-1.0)';
    'UPI1_TX_DN'<4>:
      PIN_NUMBER='(0,0,0,0,0,0,0,0,0,0,0,0,0,G6,0,0,0,0,0,0,0,0,0,0,0,0,0,0,0,0)';
      OUTPUT_LOAD='(1.0,-1.0)';
    'UPI1_TX_DN'<3>:
      PIN_NUMBER='(0,0,0,0,0,0,0,0,0,0,0,0,0,J6,0,0,0,0,0,0,0,0,0,0,0,0,0,0,0,0)';
      OUTPUT_LOAD='(1.0,-1.0)';
    'UPI1_TX_DN'<2>:
      PIN_NUMBER='(0,0,0,0,0,0,0,0,0,0,0,0,0,K5,0,0,0,0,0,0,0,0,0,0,0,0,0,0,0,0)';
      OUTPUT_LOAD='(1.0,-1.0)';
    'UPI1_TX_DN'<1>:
      PIN_NUMBER='(0,0,0,0,0,0,0,0,0,0,0,0,0,L4,0,0,0,0,0,0,0,0,0,0,0,0,0,0,0,0)';
      OUTPUT_LOAD='(1.0,-1.0)';
    'UPI1_TX_DN'<0>:
      PIN_NUMBER='(0,0,0,0,0,0,0,0,0,0,0,0,0,M3,0,0,0,0,0,0,0,0,0,0,0,0,0,0,0,0)';
      OUTPUT_LOAD='(1.0,-1.0)';
    'UPI1_TX_DP'<19>:
      PIN_NUMBER='(0,0,0,0,0,0,0,0,0,0,0,0,0,K21,0,0,0,0,0,0,0,0,0,0,0,0,0,0,0,0)';
      OUTPUT_LOAD='(1.0,-1.0)';
    'UPI1_TX_DP'<18>:
      PIN_NUMBER='(0,0,0,0,0,0,0,0,0,0,0,0,0,G20,0,0,0,0,0,0,0,0,0,0,0,0,0,0,0,0)';
      OUTPUT_LOAD='(1.0,-1.0)';
    'UPI1_TX_DP'<17>:
      PIN_NUMBER='(0,0,0,0,0,0,0,0,0,0,0,0,0,H19,0,0,0,0,0,0,0,0,0,0,0,0,0,0,0,0)';
      OUTPUT_LOAD='(1.0,-1.0)';
    'UPI1_TX_DP'<16>:
      PIN_NUMBER='(0,0,0,0,0,0,0,0,0,0,0,0,0,J18,0,0,0,0,0,0,0,0,0,0,0,0,0,0,0,0)';
      OUTPUT_LOAD='(1.0,-1.0)';
    'UPI1_TX_DP'<15>:
      PIN_NUMBER='(0,0,0,0,0,0,0,0,0,0,0,0,0,L18,0,0,0,0,0,0,0,0,0,0,0,0,0,0,0,0)';
      OUTPUT_LOAD='(1.0,-1.0)';
    'UPI1_TX_DP'<14>:
      PIN_NUMBER='(0,0,0,0,0,0,0,0,0,0,0,0,0,G16,0,0,0,0,0,0,0,0,0,0,0,0,0,0,0,0)';
      OUTPUT_LOAD='(1.0,-1.0)';
    'UPI1_TX_DP'<13>:
      PIN_NUMBER='(0,0,0,0,0,0,0,0,0,0,0,0,0,H15,0,0,0,0,0,0,0,0,0,0,0,0,0,0,0,0)';
      OUTPUT_LOAD='(1.0,-1.0)';
    'UPI1_TX_DP'<12>:
      PIN_NUMBER='(0,0,0,0,0,0,0,0,0,0,0,0,0,E14,0,0,0,0,0,0,0,0,0,0,0,0,0,0,0,0)';
      OUTPUT_LOAD='(1.0,-1.0)';
    'UPI1_TX_DP'<11>:
      PIN_NUMBER='(0,0,0,0,0,0,0,0,0,0,0,0,0,F13,0,0,0,0,0,0,0,0,0,0,0,0,0,0,0,0)';
      OUTPUT_LOAD='(1.0,-1.0)';
    'UPI1_TX_DP'<10>:
      PIN_NUMBER='(0,0,0,0,0,0,0,0,0,0,0,0,0,G12,0,0,0,0,0,0,0,0,0,0,0,0,0,0,0,0)';
      OUTPUT_LOAD='(1.0,-1.0)';
    'UPI1_TX_DP'<9>:
      PIN_NUMBER='(0,0,0,0,0,0,0,0,0,0,0,0,0,H9,0,0,0,0,0,0,0,0,0,0,0,0,0,0,0,0)';
      OUTPUT_LOAD='(1.0,-1.0)';
    'UPI1_TX_DP'<8>:
      PIN_NUMBER='(0,0,0,0,0,0,0,0,0,0,0,0,0,E10,0,0,0,0,0,0,0,0,0,0,0,0,0,0,0,0)';
      OUTPUT_LOAD='(1.0,-1.0)';
    'UPI1_TX_DP'<7>:
      PIN_NUMBER='(0,0,0,0,0,0,0,0,0,0,0,0,0,F9,0,0,0,0,0,0,0,0,0,0,0,0,0,0,0,0)';
      OUTPUT_LOAD='(1.0,-1.0)';
    'UPI1_TX_DP'<6>:
      PIN_NUMBER='(0,0,0,0,0,0,0,0,0,0,0,0,0,J8,0,0,0,0,0,0,0,0,0,0,0,0,0,0,0,0)';
      OUTPUT_LOAD='(1.0,-1.0)';
    'UPI1_TX_DP'<5>:
      PIN_NUMBER='(0,0,0,0,0,0,0,0,0,0,0,0,0,K7,0,0,0,0,0,0,0,0,0,0,0,0,0,0,0,0)';
      OUTPUT_LOAD='(1.0,-1.0)';
    'UPI1_TX_DP'<4>:
      PIN_NUMBER='(0,0,0,0,0,0,0,0,0,0,0,0,0,F7,0,0,0,0,0,0,0,0,0,0,0,0,0,0,0,0)';
      OUTPUT_LOAD='(1.0,-1.0)';
    'UPI1_TX_DP'<3>:
      PIN_NUMBER='(0,0,0,0,0,0,0,0,0,0,0,0,0,H5,0,0,0,0,0,0,0,0,0,0,0,0,0,0,0,0)';
      OUTPUT_LOAD='(1.0,-1.0)';
    'UPI1_TX_DP'<2>:
      PIN_NUMBER='(0,0,0,0,0,0,0,0,0,0,0,0,0,M5,0,0,0,0,0,0,0,0,0,0,0,0,0,0,0,0)';
      OUTPUT_LOAD='(1.0,-1.0)';
    'UPI1_TX_DP'<1>:
      PIN_NUMBER='(0,0,0,0,0,0,0,0,0,0,0,0,0,K3,0,0,0,0,0,0,0,0,0,0,0,0,0,0,0,0)';
      OUTPUT_LOAD='(1.0,-1.0)';
    'UPI1_TX_DP'<0>:
      PIN_NUMBER='(0,0,0,0,0,0,0,0,0,0,0,0,0,P3,0,0,0,0,0,0,0,0,0,0,0,0,0,0,0,0)';
      OUTPUT_LOAD='(1.0,-1.0)';
    'UPI2_RBIAS'<1>:
      PIN_NUMBER='(CK29,0,0,0,0,0,0,0,0,0,0,0,0,0,0,0,0,0,0,0,0,0,0,0,0,0,0,0,0,0)';
      INPUT_LOAD='(-0.01,0.01)';
    'UPI2_RBIAS'<0>:
      PIN_NUMBER='(CL28,0,0,0,0,0,0,0,0,0,0,0,0,0,0,0,0,0,0,0,0,0,0,0,0,0,0,0,0,0)';
      INPUT_LOAD='(-0.01,0.01)';
    'UPI2_RX_DN'<19>:
      PIN_NUMBER='(0,0,0,0,0,0,0,0,0,0,0,0,0,0,BY17,0,0,0,0,0,0,0,0,0,0,0,0,0,0,0)';
      INPUT_LOAD='(-0.01,0.01)';
    'UPI2_RX_DN'<18>:
      PIN_NUMBER='(0,0,0,0,0,0,0,0,0,0,0,0,0,0,CB15,0,0,0,0,0,0,0,0,0,0,0,0,0,0,0)';
      INPUT_LOAD='(-0.01,0.01)';
    'UPI2_RX_DN'<17>:
      PIN_NUMBER='(0,0,0,0,0,0,0,0,0,0,0,0,0,0,CF17,0,0,0,0,0,0,0,0,0,0,0,0,0,0,0)';
      INPUT_LOAD='(-0.01,0.01)';
    'UPI2_RX_DN'<16>:
      PIN_NUMBER='(0,0,0,0,0,0,0,0,0,0,0,0,0,0,CD15,0,0,0,0,0,0,0,0,0,0,0,0,0,0,0)';
      INPUT_LOAD='(-0.01,0.01)';
    'UPI2_RX_DN'<15>:
      PIN_NUMBER='(0,0,0,0,0,0,0,0,0,0,0,0,0,0,CE16,0,0,0,0,0,0,0,0,0,0,0,0,0,0,0)';
      INPUT_LOAD='(-0.01,0.01)';
    'UPI2_RX_DN'<14>:
      PIN_NUMBER='(0,0,0,0,0,0,0,0,0,0,0,0,0,0,CH17,0,0,0,0,0,0,0,0,0,0,0,0,0,0,0)';
      INPUT_LOAD='(-0.01,0.01)';
    'UPI2_RX_DN'<13>:
      PIN_NUMBER='(0,0,0,0,0,0,0,0,0,0,0,0,0,0,CJ18,0,0,0,0,0,0,0,0,0,0,0,0,0,0,0)';
      INPUT_LOAD='(-0.01,0.01)';
    'UPI2_RX_DN'<12>:
      PIN_NUMBER='(0,0,0,0,0,0,0,0,0,0,0,0,0,0,CL16,0,0,0,0,0,0,0,0,0,0,0,0,0,0,0)';
      INPUT_LOAD='(-0.01,0.01)';
    'UPI2_RX_DN'<11>:
      PIN_NUMBER='(0,0,0,0,0,0,0,0,0,0,0,0,0,0,CP21,0,0,0,0,0,0,0,0,0,0,0,0,0,0,0)';
      INPUT_LOAD='(-0.01,0.01)';
    'UPI2_RX_DN'<10>:
      PIN_NUMBER='(0,0,0,0,0,0,0,0,0,0,0,0,0,0,CN20,0,0,0,0,0,0,0,0,0,0,0,0,0,0,0)';
      INPUT_LOAD='(-0.01,0.01)';
    'UPI2_RX_DN'<9>:
      PIN_NUMBER='(0,0,0,0,0,0,0,0,0,0,0,0,0,0,CR18,0,0,0,0,0,0,0,0,0,0,0,0,0,0,0)';
      INPUT_LOAD='(-0.01,0.01)';
    'UPI2_RX_DN'<8>:
      PIN_NUMBER='(0,0,0,0,0,0,0,0,0,0,0,0,0,0,CT21,0,0,0,0,0,0,0,0,0,0,0,0,0,0,0)';
      INPUT_LOAD='(-0.01,0.01)';
    'UPI2_RX_DN'<7>:
      PIN_NUMBER='(0,0,0,0,0,0,0,0,0,0,0,0,0,0,CV19,0,0,0,0,0,0,0,0,0,0,0,0,0,0,0)';
      INPUT_LOAD='(-0.01,0.01)';
    'UPI2_RX_DN'<6>:
      PIN_NUMBER='(0,0,0,0,0,0,0,0,0,0,0,0,0,0,CW20,0,0,0,0,0,0,0,0,0,0,0,0,0,0,0)';
      INPUT_LOAD='(-0.01,0.01)';
    'UPI2_RX_DN'<5>:
      PIN_NUMBER='(0,0,0,0,0,0,0,0,0,0,0,0,0,0,DA20,0,0,0,0,0,0,0,0,0,0,0,0,0,0,0)';
      INPUT_LOAD='(-0.01,0.01)';
    'UPI2_RX_DN'<4>:
      PIN_NUMBER='(0,0,0,0,0,0,0,0,0,0,0,0,0,0,DD19,0,0,0,0,0,0,0,0,0,0,0,0,0,0,0)';
      INPUT_LOAD='(-0.01,0.01)';
    'UPI2_RX_DN'<3>:
      PIN_NUMBER='(0,0,0,0,0,0,0,0,0,0,0,0,0,0,DB21,0,0,0,0,0,0,0,0,0,0,0,0,0,0,0)';
      INPUT_LOAD='(-0.01,0.01)';
    'UPI2_RX_DN'<2>:
      PIN_NUMBER='(0,0,0,0,0,0,0,0,0,0,0,0,0,0,DC22,0,0,0,0,0,0,0,0,0,0,0,0,0,0,0)';
      INPUT_LOAD='(-0.01,0.01)';
    'UPI2_RX_DN'<1>:
      PIN_NUMBER='(0,0,0,0,0,0,0,0,0,0,0,0,0,0,DE22,0,0,0,0,0,0,0,0,0,0,0,0,0,0,0)';
      INPUT_LOAD='(-0.01,0.01)';
    'UPI2_RX_DN'<0>:
      PIN_NUMBER='(0,0,0,0,0,0,0,0,0,0,0,0,0,0,DF23,0,0,0,0,0,0,0,0,0,0,0,0,0,0,0)';
      INPUT_LOAD='(-0.01,0.01)';
    'UPI2_RX_DP'<19>:
      PIN_NUMBER='(0,0,0,0,0,0,0,0,0,0,0,0,0,0,CA16,0,0,0,0,0,0,0,0,0,0,0,0,0,0,0)';
      INPUT_LOAD='(-0.01,0.01)';
    'UPI2_RX_DP'<18>:
      PIN_NUMBER='(0,0,0,0,0,0,0,0,0,0,0,0,0,0,BY15,0,0,0,0,0,0,0,0,0,0,0,0,0,0,0)';
      INPUT_LOAD='(-0.01,0.01)';
    'UPI2_RX_DP'<17>:
      PIN_NUMBER='(0,0,0,0,0,0,0,0,0,0,0,0,0,0,CD17,0,0,0,0,0,0,0,0,0,0,0,0,0,0,0)';
      INPUT_LOAD='(-0.01,0.01)';
    'UPI2_RX_DP'<16>:
      PIN_NUMBER='(0,0,0,0,0,0,0,0,0,0,0,0,0,0,CC14,0,0,0,0,0,0,0,0,0,0,0,0,0,0,0)';
      INPUT_LOAD='(-0.01,0.01)';
    'UPI2_RX_DP'<15>:
      PIN_NUMBER='(0,0,0,0,0,0,0,0,0,0,0,0,0,0,CF15,0,0,0,0,0,0,0,0,0,0,0,0,0,0,0)';
      INPUT_LOAD='(-0.01,0.01)';
    'UPI2_RX_DP'<14>:
      PIN_NUMBER='(0,0,0,0,0,0,0,0,0,0,0,0,0,0,CG16,0,0,0,0,0,0,0,0,0,0,0,0,0,0,0)';
      INPUT_LOAD='(-0.01,0.01)';
    'UPI2_RX_DP'<13>:
      PIN_NUMBER='(0,0,0,0,0,0,0,0,0,0,0,0,0,0,CK17,0,0,0,0,0,0,0,0,0,0,0,0,0,0,0)';
      INPUT_LOAD='(-0.01,0.01)';
    'UPI2_RX_DP'<12>:
      PIN_NUMBER='(0,0,0,0,0,0,0,0,0,0,0,0,0,0,CJ16,0,0,0,0,0,0,0,0,0,0,0,0,0,0,0)';
      INPUT_LOAD='(-0.01,0.01)';
    'UPI2_RX_DP'<11>:
      PIN_NUMBER='(0,0,0,0,0,0,0,0,0,0,0,0,0,0,CM21,0,0,0,0,0,0,0,0,0,0,0,0,0,0,0)';
      INPUT_LOAD='(-0.01,0.01)';
    'UPI2_RX_DP'<10>:
      PIN_NUMBER='(0,0,0,0,0,0,0,0,0,0,0,0,0,0,CP19,0,0,0,0,0,0,0,0,0,0,0,0,0,0,0)';
      INPUT_LOAD='(-0.01,0.01)';
    'UPI2_RX_DP'<9>:
      PIN_NUMBER='(0,0,0,0,0,0,0,0,0,0,0,0,0,0,CN18,0,0,0,0,0,0,0,0,0,0,0,0,0,0,0)';
      INPUT_LOAD='(-0.01,0.01)';
    'UPI2_RX_DP'<8>:
      PIN_NUMBER='(0,0,0,0,0,0,0,0,0,0,0,0,0,0,CR20,0,0,0,0,0,0,0,0,0,0,0,0,0,0,0)';
      INPUT_LOAD='(-0.01,0.01)';
    'UPI2_RX_DP'<7>:
      PIN_NUMBER='(0,0,0,0,0,0,0,0,0,0,0,0,0,0,CW18,0,0,0,0,0,0,0,0,0,0,0,0,0,0,0)';
      INPUT_LOAD='(-0.01,0.01)';
    'UPI2_RX_DP'<6>:
      PIN_NUMBER='(0,0,0,0,0,0,0,0,0,0,0,0,0,0,CU20,0,0,0,0,0,0,0,0,0,0,0,0,0,0,0)';
      INPUT_LOAD='(-0.01,0.01)';
    'UPI2_RX_DP'<5>:
      PIN_NUMBER='(0,0,0,0,0,0,0,0,0,0,0,0,0,0,CY19,0,0,0,0,0,0,0,0,0,0,0,0,0,0,0)';
      INPUT_LOAD='(-0.01,0.01)';
    'UPI2_RX_DP'<4>:
      PIN_NUMBER='(0,0,0,0,0,0,0,0,0,0,0,0,0,0,DB19,0,0,0,0,0,0,0,0,0,0,0,0,0,0,0)';
      INPUT_LOAD='(-0.01,0.01)';
    'UPI2_RX_DP'<3>:
      PIN_NUMBER='(0,0,0,0,0,0,0,0,0,0,0,0,0,0,DC20,0,0,0,0,0,0,0,0,0,0,0,0,0,0,0)';
      INPUT_LOAD='(-0.01,0.01)';
    'UPI2_RX_DP'<2>:
      PIN_NUMBER='(0,0,0,0,0,0,0,0,0,0,0,0,0,0,DA22,0,0,0,0,0,0,0,0,0,0,0,0,0,0,0)';
      INPUT_LOAD='(-0.01,0.01)';
    'UPI2_RX_DP'<1>:
      PIN_NUMBER='(0,0,0,0,0,0,0,0,0,0,0,0,0,0,DD21,0,0,0,0,0,0,0,0,0,0,0,0,0,0,0)';
      INPUT_LOAD='(-0.01,0.01)';
    'UPI2_RX_DP'<0>:
      PIN_NUMBER='(0,0,0,0,0,0,0,0,0,0,0,0,0,0,DG22,0,0,0,0,0,0,0,0,0,0,0,0,0,0,0)';
      INPUT_LOAD='(-0.01,0.01)';
    'UPI2_TX_DN'<19>:
      PIN_NUMBER='(0,0,0,0,0,0,0,0,0,0,0,0,0,0,CC12,0,0,0,0,0,0,0,0,0,0,0,0,0,0,0)';
      OUTPUT_LOAD='(1.0,-1.0)';
    'UPI2_TX_DN'<18>:
      PIN_NUMBER='(0,0,0,0,0,0,0,0,0,0,0,0,0,0,CC10,0,0,0,0,0,0,0,0,0,0,0,0,0,0,0)';
      OUTPUT_LOAD='(1.0,-1.0)';
    'UPI2_TX_DN'<17>:
      PIN_NUMBER='(0,0,0,0,0,0,0,0,0,0,0,0,0,0,CE12,0,0,0,0,0,0,0,0,0,0,0,0,0,0,0)';
      OUTPUT_LOAD='(1.0,-1.0)';
    'UPI2_TX_DN'<16>:
      PIN_NUMBER='(0,0,0,0,0,0,0,0,0,0,0,0,0,0,CH11,0,0,0,0,0,0,0,0,0,0,0,0,0,0,0)';
      OUTPUT_LOAD='(1.0,-1.0)';
    'UPI2_TX_DN'<15>:
      PIN_NUMBER='(0,0,0,0,0,0,0,0,0,0,0,0,0,0,CF13,0,0,0,0,0,0,0,0,0,0,0,0,0,0,0)';
      OUTPUT_LOAD='(1.0,-1.0)';
    'UPI2_TX_DN'<14>:
      PIN_NUMBER='(0,0,0,0,0,0,0,0,0,0,0,0,0,0,CJ14,0,0,0,0,0,0,0,0,0,0,0,0,0,0,0)';
      OUTPUT_LOAD='(1.0,-1.0)';
    'UPI2_TX_DN'<13>:
      PIN_NUMBER='(0,0,0,0,0,0,0,0,0,0,0,0,0,0,CM13,0,0,0,0,0,0,0,0,0,0,0,0,0,0,0)';
      OUTPUT_LOAD='(1.0,-1.0)';
    'UPI2_TX_DN'<12>:
      PIN_NUMBER='(0,0,0,0,0,0,0,0,0,0,0,0,0,0,CU14,0,0,0,0,0,0,0,0,0,0,0,0,0,0,0)';
      OUTPUT_LOAD='(1.0,-1.0)';
    'UPI2_TX_DN'<11>:
      PIN_NUMBER='(0,0,0,0,0,0,0,0,0,0,0,0,0,0,CW14,0,0,0,0,0,0,0,0,0,0,0,0,0,0,0)';
      OUTPUT_LOAD='(1.0,-1.0)';
    'UPI2_TX_DN'<10>:
      PIN_NUMBER='(0,0,0,0,0,0,0,0,0,0,0,0,0,0,DA16,0,0,0,0,0,0,0,0,0,0,0,0,0,0,0)';
      OUTPUT_LOAD='(1.0,-1.0)';
    'UPI2_TX_DN'<9>:
      PIN_NUMBER='(0,0,0,0,0,0,0,0,0,0,0,0,0,0,DC16,0,0,0,0,0,0,0,0,0,0,0,0,0,0,0)';
      OUTPUT_LOAD='(1.0,-1.0)';
    'UPI2_TX_DN'<8>:
      PIN_NUMBER='(0,0,0,0,0,0,0,0,0,0,0,0,0,0,DF15,0,0,0,0,0,0,0,0,0,0,0,0,0,0,0)';
      OUTPUT_LOAD='(1.0,-1.0)';
    'UPI2_TX_DN'<7>:
      PIN_NUMBER='(0,0,0,0,0,0,0,0,0,0,0,0,0,0,DD17,0,0,0,0,0,0,0,0,0,0,0,0,0,0,0)';
      OUTPUT_LOAD='(1.0,-1.0)';
    'UPI2_TX_DN'<6>:
      PIN_NUMBER='(0,0,0,0,0,0,0,0,0,0,0,0,0,0,DG18,0,0,0,0,0,0,0,0,0,0,0,0,0,0,0)';
      OUTPUT_LOAD='(1.0,-1.0)';
    'UPI2_TX_DN'<5>:
      PIN_NUMBER='(0,0,0,0,0,0,0,0,0,0,0,0,0,0,DK17,0,0,0,0,0,0,0,0,0,0,0,0,0,0,0)';
      OUTPUT_LOAD='(1.0,-1.0)';
    'UPI2_TX_DN'<4>:
      PIN_NUMBER='(0,0,0,0,0,0,0,0,0,0,0,0,0,0,DH19,0,0,0,0,0,0,0,0,0,0,0,0,0,0,0)';
      OUTPUT_LOAD='(1.0,-1.0)';
    'UPI2_TX_DN'<3>:
      PIN_NUMBER='(0,0,0,0,0,0,0,0,0,0,0,0,0,0,DG20,0,0,0,0,0,0,0,0,0,0,0,0,0,0,0)';
      OUTPUT_LOAD='(1.0,-1.0)';
    'UPI2_TX_DN'<2>:
      PIN_NUMBER='(0,0,0,0,0,0,0,0,0,0,0,0,0,0,DL20,0,0,0,0,0,0,0,0,0,0,0,0,0,0,0)';
      OUTPUT_LOAD='(1.0,-1.0)';
    'UPI2_TX_DN'<1>:
      PIN_NUMBER='(0,0,0,0,0,0,0,0,0,0,0,0,0,0,DM21,0,0,0,0,0,0,0,0,0,0,0,0,0,0,0)';
      OUTPUT_LOAD='(1.0,-1.0)';
    'UPI2_TX_DN'<0>:
      PIN_NUMBER='(0,0,0,0,0,0,0,0,0,0,0,0,0,0,DT21,0,0,0,0,0,0,0,0,0,0,0,0,0,0,0)';
      OUTPUT_LOAD='(1.0,-1.0)';
    'UPI2_TX_DP'<19>:
      PIN_NUMBER='(0,0,0,0,0,0,0,0,0,0,0,0,0,0,CA12,0,0,0,0,0,0,0,0,0,0,0,0,0,0,0)';
      OUTPUT_LOAD='(1.0,-1.0)';
    'UPI2_TX_DP'<18>:
      PIN_NUMBER='(0,0,0,0,0,0,0,0,0,0,0,0,0,0,CB11,0,0,0,0,0,0,0,0,0,0,0,0,0,0,0)';
      OUTPUT_LOAD='(1.0,-1.0)';
    'UPI2_TX_DP'<17>:
      PIN_NUMBER='(0,0,0,0,0,0,0,0,0,0,0,0,0,0,CD11,0,0,0,0,0,0,0,0,0,0,0,0,0,0,0)';
      OUTPUT_LOAD='(1.0,-1.0)';
    'UPI2_TX_DP'<16>:
      PIN_NUMBER='(0,0,0,0,0,0,0,0,0,0,0,0,0,0,CF11,0,0,0,0,0,0,0,0,0,0,0,0,0,0,0)';
      OUTPUT_LOAD='(1.0,-1.0)';
    'UPI2_TX_DP'<15>:
      PIN_NUMBER='(0,0,0,0,0,0,0,0,0,0,0,0,0,0,CG12,0,0,0,0,0,0,0,0,0,0,0,0,0,0,0)';
      OUTPUT_LOAD='(1.0,-1.0)';
    'UPI2_TX_DP'<14>:
      PIN_NUMBER='(0,0,0,0,0,0,0,0,0,0,0,0,0,0,CH13,0,0,0,0,0,0,0,0,0,0,0,0,0,0,0)';
      OUTPUT_LOAD='(1.0,-1.0)';
    'UPI2_TX_DP'<13>:
      PIN_NUMBER='(0,0,0,0,0,0,0,0,0,0,0,0,0,0,CK13,0,0,0,0,0,0,0,0,0,0,0,0,0,0,0)';
      OUTPUT_LOAD='(1.0,-1.0)';
    'UPI2_TX_DP'<12>:
      PIN_NUMBER='(0,0,0,0,0,0,0,0,0,0,0,0,0,0,CR14,0,0,0,0,0,0,0,0,0,0,0,0,0,0,0)';
      OUTPUT_LOAD='(1.0,-1.0)';
    'UPI2_TX_DP'<11>:
      PIN_NUMBER='(0,0,0,0,0,0,0,0,0,0,0,0,0,0,CV13,0,0,0,0,0,0,0,0,0,0,0,0,0,0,0)';
      OUTPUT_LOAD='(1.0,-1.0)';
    'UPI2_TX_DP'<10>:
      PIN_NUMBER='(0,0,0,0,0,0,0,0,0,0,0,0,0,0,CW16,0,0,0,0,0,0,0,0,0,0,0,0,0,0,0)';
      OUTPUT_LOAD='(1.0,-1.0)';
    'UPI2_TX_DP'<9>:
      PIN_NUMBER='(0,0,0,0,0,0,0,0,0,0,0,0,0,0,DB15,0,0,0,0,0,0,0,0,0,0,0,0,0,0,0)';
      OUTPUT_LOAD='(1.0,-1.0)';
    'UPI2_TX_DP'<8>:
      PIN_NUMBER='(0,0,0,0,0,0,0,0,0,0,0,0,0,0,DD15,0,0,0,0,0,0,0,0,0,0,0,0,0,0,0)';
      OUTPUT_LOAD='(1.0,-1.0)';
    'UPI2_TX_DP'<7>:
      PIN_NUMBER='(0,0,0,0,0,0,0,0,0,0,0,0,0,0,DE16,0,0,0,0,0,0,0,0,0,0,0,0,0,0,0)';
      OUTPUT_LOAD='(1.0,-1.0)';
    'UPI2_TX_DP'<6>:
      PIN_NUMBER='(0,0,0,0,0,0,0,0,0,0,0,0,0,0,DF17,0,0,0,0,0,0,0,0,0,0,0,0,0,0,0)';
      OUTPUT_LOAD='(1.0,-1.0)';
    'UPI2_TX_DP'<5>:
      PIN_NUMBER='(0,0,0,0,0,0,0,0,0,0,0,0,0,0,DH17,0,0,0,0,0,0,0,0,0,0,0,0,0,0,0)';
      OUTPUT_LOAD='(1.0,-1.0)';
    'UPI2_TX_DP'<4>:
      PIN_NUMBER='(0,0,0,0,0,0,0,0,0,0,0,0,0,0,DJ18,0,0,0,0,0,0,0,0,0,0,0,0,0,0,0)';
      OUTPUT_LOAD='(1.0,-1.0)';
    'UPI2_TX_DP'<3>:
      PIN_NUMBER='(0,0,0,0,0,0,0,0,0,0,0,0,0,0,DJ20,0,0,0,0,0,0,0,0,0,0,0,0,0,0,0)';
      OUTPUT_LOAD='(1.0,-1.0)';
    'UPI2_TX_DP'<2>:
      PIN_NUMBER='(0,0,0,0,0,0,0,0,0,0,0,0,0,0,DK19,0,0,0,0,0,0,0,0,0,0,0,0,0,0,0)';
      OUTPUT_LOAD='(1.0,-1.0)';
    'UPI2_TX_DP'<1>:
      PIN_NUMBER='(0,0,0,0,0,0,0,0,0,0,0,0,0,0,DN20,0,0,0,0,0,0,0,0,0,0,0,0,0,0,0)';
      OUTPUT_LOAD='(1.0,-1.0)';
    'UPI2_TX_DP'<0>:
      PIN_NUMBER='(0,0,0,0,0,0,0,0,0,0,0,0,0,0,DP21,0,0,0,0,0,0,0,0,0,0,0,0,0,0,0)';
      OUTPUT_LOAD='(1.0,-1.0)';
    'VCC33':
      PIN_NUMBER='(0,0,0,0,0,0,0,0,0,0,0,0,0,0,0,0,0,0,0,0,CY55,0,0,0,0,0,0,0,0,0)';
      PINUSE='POWER';
      NO_LOAD_CHECK='Both';
      NO_IO_CHECK='Both';
      NO_ASSERT_CHECK='TRUE';
      NO_DIR_CHECK='TRUE';
      ALLOW_CONNECT='TRUE';
    'VCCD012'<51>:
      PIN_NUMBER='(0,0,0,0,0,0,0,0,0,0,0,0,0,0,0,0,0,0,0,B47,0,0,0,0,0,0,0,0,0,0)';
      PINUSE='POWER';
      NO_LOAD_CHECK='Both';
      NO_IO_CHECK='Both';
      NO_ASSERT_CHECK='TRUE';
      NO_DIR_CHECK='TRUE';
      ALLOW_CONNECT='TRUE';
    'VCCD012'<50>:
      PIN_NUMBER='(0,0,0,0,0,0,0,0,0,0,0,0,0,0,0,0,0,0,0,C46,0,0,0,0,0,0,0,0,0,0)';
      PINUSE='POWER';
      NO_LOAD_CHECK='Both';
      NO_IO_CHECK='Both';
      NO_ASSERT_CHECK='TRUE';
      NO_DIR_CHECK='TRUE';
      ALLOW_CONNECT='TRUE';
    'VCCD012'<49>:
      PIN_NUMBER='(0,0,0,0,0,0,0,0,0,0,0,0,0,0,0,0,0,0,0,D45,0,0,0,0,0,0,0,0,0,0)';
      PINUSE='POWER';
      NO_LOAD_CHECK='Both';
      NO_IO_CHECK='Both';
      NO_ASSERT_CHECK='TRUE';
      NO_DIR_CHECK='TRUE';
      ALLOW_CONNECT='TRUE';
    'VCCD012'<48>:
      PIN_NUMBER='(0,0,0,0,0,0,0,0,0,0,0,0,0,0,0,0,0,0,0,AF63,0,0,0,0,0,0,0,0,0,0)';
      PINUSE='POWER';
      NO_LOAD_CHECK='Both';
      NO_IO_CHECK='Both';
      NO_ASSERT_CHECK='TRUE';
      NO_DIR_CHECK='TRUE';
      ALLOW_CONNECT='TRUE';
    'VCCD012'<47>:
      PIN_NUMBER='(0,0,0,0,0,0,0,0,0,0,0,0,0,0,0,0,0,0,0,AF61,0,0,0,0,0,0,0,0,0,0)';
      PINUSE='POWER';
      NO_LOAD_CHECK='Both';
      NO_IO_CHECK='Both';
      NO_ASSERT_CHECK='TRUE';
      NO_DIR_CHECK='TRUE';
      ALLOW_CONNECT='TRUE';
    'VCCD012'<46>:
      PIN_NUMBER='(0,0,0,0,0,0,0,0,0,0,0,0,0,0,0,0,0,0,0,AF59,0,0,0,0,0,0,0,0,0,0)';
      PINUSE='POWER';
      NO_LOAD_CHECK='Both';
      NO_IO_CHECK='Both';
      NO_ASSERT_CHECK='TRUE';
      NO_DIR_CHECK='TRUE';
      ALLOW_CONNECT='TRUE';
    'VCCD012'<45>:
      PIN_NUMBER='(0,0,0,0,0,0,0,0,0,0,0,0,0,0,0,0,0,0,0,AF57,0,0,0,0,0,0,0,0,0,0)';
      PINUSE='POWER';
      NO_LOAD_CHECK='Both';
      NO_IO_CHECK='Both';
      NO_ASSERT_CHECK='TRUE';
      NO_DIR_CHECK='TRUE';
      ALLOW_CONNECT='TRUE';
    'VCCD012'<44>:
      PIN_NUMBER='(0,0,0,0,0,0,0,0,0,0,0,0,0,0,0,0,0,0,0,AF55,0,0,0,0,0,0,0,0,0,0)';
      PINUSE='POWER';
      NO_LOAD_CHECK='Both';
      NO_IO_CHECK='Both';
      NO_ASSERT_CHECK='TRUE';
      NO_DIR_CHECK='TRUE';
      ALLOW_CONNECT='TRUE';
    'VCCD012'<43>:
      PIN_NUMBER='(0,0,0,0,0,0,0,0,0,0,0,0,0,0,0,0,0,0,0,AD45,0,0,0,0,0,0,0,0,0,0)';
      PINUSE='POWER';
      NO_LOAD_CHECK='Both';
      NO_IO_CHECK='Both';
      NO_ASSERT_CHECK='TRUE';
      NO_DIR_CHECK='TRUE';
      ALLOW_CONNECT='TRUE';
    'VCCD012'<42>:
      PIN_NUMBER='(0,0,0,0,0,0,0,0,0,0,0,0,0,0,0,0,0,0,0,Y63,0,0,0,0,0,0,0,0,0,0)';
      PINUSE='POWER';
      NO_LOAD_CHECK='Both';
      NO_IO_CHECK='Both';
      NO_ASSERT_CHECK='TRUE';
      NO_DIR_CHECK='TRUE';
      ALLOW_CONNECT='TRUE';
    'VCCD012'<41>:
      PIN_NUMBER='(0,0,0,0,0,0,0,0,0,0,0,0,0,0,0,0,0,0,0,Y61,0,0,0,0,0,0,0,0,0,0)';
      PINUSE='POWER';
      NO_LOAD_CHECK='Both';
      NO_IO_CHECK='Both';
      NO_ASSERT_CHECK='TRUE';
      NO_DIR_CHECK='TRUE';
      ALLOW_CONNECT='TRUE';
    'VCCD012'<40>:
      PIN_NUMBER='(0,0,0,0,0,0,0,0,0,0,0,0,0,0,0,0,0,0,0,Y59,0,0,0,0,0,0,0,0,0,0)';
      PINUSE='POWER';
      NO_LOAD_CHECK='Both';
      NO_IO_CHECK='Both';
      NO_ASSERT_CHECK='TRUE';
      NO_DIR_CHECK='TRUE';
      ALLOW_CONNECT='TRUE';
    'VCCD012'<39>:
      PIN_NUMBER='(0,0,0,0,0,0,0,0,0,0,0,0,0,0,0,0,0,0,0,Y57,0,0,0,0,0,0,0,0,0,0)';
      PINUSE='POWER';
      NO_LOAD_CHECK='Both';
      NO_IO_CHECK='Both';
      NO_ASSERT_CHECK='TRUE';
      NO_DIR_CHECK='TRUE';
      ALLOW_CONNECT='TRUE';
    'VCCD012'<38>:
      PIN_NUMBER='(0,0,0,0,0,0,0,0,0,0,0,0,0,0,0,0,0,0,0,Y55,0,0,0,0,0,0,0,0,0,0)';
      PINUSE='POWER';
      NO_LOAD_CHECK='Both';
      NO_IO_CHECK='Both';
      NO_ASSERT_CHECK='TRUE';
      NO_DIR_CHECK='TRUE';
      ALLOW_CONNECT='TRUE';
    'VCCD012'<37>:
      PIN_NUMBER='(0,0,0,0,0,0,0,0,0,0,0,0,0,0,0,0,0,0,0,Y53,0,0,0,0,0,0,0,0,0,0)';
      PINUSE='POWER';
      NO_LOAD_CHECK='Both';
      NO_IO_CHECK='Both';
      NO_ASSERT_CHECK='TRUE';
      NO_DIR_CHECK='TRUE';
      ALLOW_CONNECT='TRUE';
    'VCCD012'<36>:
      PIN_NUMBER='(0,0,0,0,0,0,0,0,0,0,0,0,0,0,0,0,0,0,0,Y51,0,0,0,0,0,0,0,0,0,0)';
      PINUSE='POWER';
      NO_LOAD_CHECK='Both';
      NO_IO_CHECK='Both';
      NO_ASSERT_CHECK='TRUE';
      NO_DIR_CHECK='TRUE';
      ALLOW_CONNECT='TRUE';
    'VCCD012'<35>:
      PIN_NUMBER='(0,0,0,0,0,0,0,0,0,0,0,0,0,0,0,0,0,0,0,Y49,0,0,0,0,0,0,0,0,0,0)';
      PINUSE='POWER';
      NO_LOAD_CHECK='Both';
      NO_IO_CHECK='Both';
      NO_ASSERT_CHECK='TRUE';
      NO_DIR_CHECK='TRUE';
      ALLOW_CONNECT='TRUE';
    'VCCD012'<34>:
      PIN_NUMBER='(0,0,0,0,0,0,0,0,0,0,0,0,0,0,0,0,0,0,0,Y47,0,0,0,0,0,0,0,0,0,0)';
      PINUSE='POWER';
      NO_LOAD_CHECK='Both';
      NO_IO_CHECK='Both';
      NO_ASSERT_CHECK='TRUE';
      NO_DIR_CHECK='TRUE';
      ALLOW_CONNECT='TRUE';
    'VCCD012'<33>:
      PIN_NUMBER='(0,0,0,0,0,0,0,0,0,0,0,0,0,0,0,0,0,0,0,Y45,0,0,0,0,0,0,0,0,0,0)';
      PINUSE='POWER';
      NO_LOAD_CHECK='Both';
      NO_IO_CHECK='Both';
      NO_ASSERT_CHECK='TRUE';
      NO_DIR_CHECK='TRUE';
      ALLOW_CONNECT='TRUE';
    'VCCD012'<32>:
      PIN_NUMBER='(0,0,0,0,0,0,0,0,0,0,0,0,0,0,0,0,0,0,0,W64,0,0,0,0,0,0,0,0,0,0)';
      PINUSE='POWER';
      NO_LOAD_CHECK='Both';
      NO_IO_CHECK='Both';
      NO_ASSERT_CHECK='TRUE';
      NO_DIR_CHECK='TRUE';
      ALLOW_CONNECT='TRUE';
    'VCCD012'<31>:
      PIN_NUMBER='(0,0,0,0,0,0,0,0,0,0,0,0,0,0,0,0,0,0,0,U62,0,0,0,0,0,0,0,0,0,0)';
      PINUSE='POWER';
      NO_LOAD_CHECK='Both';
      NO_IO_CHECK='Both';
      NO_ASSERT_CHECK='TRUE';
      NO_DIR_CHECK='TRUE';
      ALLOW_CONNECT='TRUE';
    'VCCD012'<30>:
      PIN_NUMBER='(0,0,0,0,0,0,0,0,0,0,0,0,0,0,0,0,0,0,0,U60,0,0,0,0,0,0,0,0,0,0)';
      PINUSE='POWER';
      NO_LOAD_CHECK='Both';
      NO_IO_CHECK='Both';
      NO_ASSERT_CHECK='TRUE';
      NO_DIR_CHECK='TRUE';
      ALLOW_CONNECT='TRUE';
    'VCCD012'<29>:
      PIN_NUMBER='(0,0,0,0,0,0,0,0,0,0,0,0,0,0,0,0,0,0,0,U58,0,0,0,0,0,0,0,0,0,0)';
      PINUSE='POWER';
      NO_LOAD_CHECK='Both';
      NO_IO_CHECK='Both';
      NO_ASSERT_CHECK='TRUE';
      NO_DIR_CHECK='TRUE';
      ALLOW_CONNECT='TRUE';
    'VCCD012'<28>:
      PIN_NUMBER='(0,0,0,0,0,0,0,0,0,0,0,0,0,0,0,0,0,0,0,U56,0,0,0,0,0,0,0,0,0,0)';
      PINUSE='POWER';
      NO_LOAD_CHECK='Both';
      NO_IO_CHECK='Both';
      NO_ASSERT_CHECK='TRUE';
      NO_DIR_CHECK='TRUE';
      ALLOW_CONNECT='TRUE';
    'VCCD012'<27>:
      PIN_NUMBER='(0,0,0,0,0,0,0,0,0,0,0,0,0,0,0,0,0,0,0,U54,0,0,0,0,0,0,0,0,0,0)';
      PINUSE='POWER';
      NO_LOAD_CHECK='Both';
      NO_IO_CHECK='Both';
      NO_ASSERT_CHECK='TRUE';
      NO_DIR_CHECK='TRUE';
      ALLOW_CONNECT='TRUE';
    'VCCD012'<26>:
      PIN_NUMBER='(0,0,0,0,0,0,0,0,0,0,0,0,0,0,0,0,0,0,0,U52,0,0,0,0,0,0,0,0,0,0)';
      PINUSE='POWER';
      NO_LOAD_CHECK='Both';
      NO_IO_CHECK='Both';
      NO_ASSERT_CHECK='TRUE';
      NO_DIR_CHECK='TRUE';
      ALLOW_CONNECT='TRUE';
    'VCCD012'<25>:
      PIN_NUMBER='(0,0,0,0,0,0,0,0,0,0,0,0,0,0,0,0,0,0,0,U50,0,0,0,0,0,0,0,0,0,0)';
      PINUSE='POWER';
      NO_LOAD_CHECK='Both';
      NO_IO_CHECK='Both';
      NO_ASSERT_CHECK='TRUE';
      NO_DIR_CHECK='TRUE';
      ALLOW_CONNECT='TRUE';
    'VCCD012'<24>:
      PIN_NUMBER='(0,0,0,0,0,0,0,0,0,0,0,0,0,0,0,0,0,0,0,U48,0,0,0,0,0,0,0,0,0,0)';
      PINUSE='POWER';
      NO_LOAD_CHECK='Both';
      NO_IO_CHECK='Both';
      NO_ASSERT_CHECK='TRUE';
      NO_DIR_CHECK='TRUE';
      ALLOW_CONNECT='TRUE';
    'VCCD012'<23>:
      PIN_NUMBER='(0,0,0,0,0,0,0,0,0,0,0,0,0,0,0,0,0,0,0,U46,0,0,0,0,0,0,0,0,0,0)';
      PINUSE='POWER';
      NO_LOAD_CHECK='Both';
      NO_IO_CHECK='Both';
      NO_ASSERT_CHECK='TRUE';
      NO_DIR_CHECK='TRUE';
      ALLOW_CONNECT='TRUE';
    'VCCD012'<22>:
      PIN_NUMBER='(0,0,0,0,0,0,0,0,0,0,0,0,0,0,0,0,0,0,0,N64,0,0,0,0,0,0,0,0,0,0)';
      PINUSE='POWER';
      NO_LOAD_CHECK='Both';
      NO_IO_CHECK='Both';
      NO_ASSERT_CHECK='TRUE';
      NO_DIR_CHECK='TRUE';
      ALLOW_CONNECT='TRUE';
    'VCCD012'<21>:
      PIN_NUMBER='(0,0,0,0,0,0,0,0,0,0,0,0,0,0,0,0,0,0,0,L62,0,0,0,0,0,0,0,0,0,0)';
      PINUSE='POWER';
      NO_LOAD_CHECK='Both';
      NO_IO_CHECK='Both';
      NO_ASSERT_CHECK='TRUE';
      NO_DIR_CHECK='TRUE';
      ALLOW_CONNECT='TRUE';
    'VCCD012'<20>:
      PIN_NUMBER='(0,0,0,0,0,0,0,0,0,0,0,0,0,0,0,0,0,0,0,L60,0,0,0,0,0,0,0,0,0,0)';
      PINUSE='POWER';
      NO_LOAD_CHECK='Both';
      NO_IO_CHECK='Both';
      NO_ASSERT_CHECK='TRUE';
      NO_DIR_CHECK='TRUE';
      ALLOW_CONNECT='TRUE';
    'VCCD012'<19>:
      PIN_NUMBER='(0,0,0,0,0,0,0,0,0,0,0,0,0,0,0,0,0,0,0,L58,0,0,0,0,0,0,0,0,0,0)';
      PINUSE='POWER';
      NO_LOAD_CHECK='Both';
      NO_IO_CHECK='Both';
      NO_ASSERT_CHECK='TRUE';
      NO_DIR_CHECK='TRUE';
      ALLOW_CONNECT='TRUE';
    'VCCD012'<18>:
      PIN_NUMBER='(0,0,0,0,0,0,0,0,0,0,0,0,0,0,0,0,0,0,0,L56,0,0,0,0,0,0,0,0,0,0)';
      PINUSE='POWER';
      NO_LOAD_CHECK='Both';
      NO_IO_CHECK='Both';
      NO_ASSERT_CHECK='TRUE';
      NO_DIR_CHECK='TRUE';
      ALLOW_CONNECT='TRUE';
    'VCCD012'<17>:
      PIN_NUMBER='(0,0,0,0,0,0,0,0,0,0,0,0,0,0,0,0,0,0,0,L54,0,0,0,0,0,0,0,0,0,0)';
      PINUSE='POWER';
      NO_LOAD_CHECK='Both';
      NO_IO_CHECK='Both';
      NO_ASSERT_CHECK='TRUE';
      NO_DIR_CHECK='TRUE';
      ALLOW_CONNECT='TRUE';
    'VCCD012'<16>:
      PIN_NUMBER='(0,0,0,0,0,0,0,0,0,0,0,0,0,0,0,0,0,0,0,L52,0,0,0,0,0,0,0,0,0,0)';
      PINUSE='POWER';
      NO_LOAD_CHECK='Both';
      NO_IO_CHECK='Both';
      NO_ASSERT_CHECK='TRUE';
      NO_DIR_CHECK='TRUE';
      ALLOW_CONNECT='TRUE';
    'VCCD012'<15>:
      PIN_NUMBER='(0,0,0,0,0,0,0,0,0,0,0,0,0,0,0,0,0,0,0,L50,0,0,0,0,0,0,0,0,0,0)';
      PINUSE='POWER';
      NO_LOAD_CHECK='Both';
      NO_IO_CHECK='Both';
      NO_ASSERT_CHECK='TRUE';
      NO_DIR_CHECK='TRUE';
      ALLOW_CONNECT='TRUE';
    'VCCD012'<14>:
      PIN_NUMBER='(0,0,0,0,0,0,0,0,0,0,0,0,0,0,0,0,0,0,0,L48,0,0,0,0,0,0,0,0,0,0)';
      PINUSE='POWER';
      NO_LOAD_CHECK='Both';
      NO_IO_CHECK='Both';
      NO_ASSERT_CHECK='TRUE';
      NO_DIR_CHECK='TRUE';
      ALLOW_CONNECT='TRUE';
    'VCCD012'<13>:
      PIN_NUMBER='(0,0,0,0,0,0,0,0,0,0,0,0,0,0,0,0,0,0,0,L46,0,0,0,0,0,0,0,0,0,0)';
      PINUSE='POWER';
      NO_LOAD_CHECK='Both';
      NO_IO_CHECK='Both';
      NO_ASSERT_CHECK='TRUE';
      NO_DIR_CHECK='TRUE';
      ALLOW_CONNECT='TRUE';
    'VCCD012'<12>:
      PIN_NUMBER='(0,0,0,0,0,0,0,0,0,0,0,0,0,0,0,0,0,0,0,E64,0,0,0,0,0,0,0,0,0,0)';
      PINUSE='POWER';
      NO_LOAD_CHECK='Both';
      NO_IO_CHECK='Both';
      NO_ASSERT_CHECK='TRUE';
      NO_DIR_CHECK='TRUE';
      ALLOW_CONNECT='TRUE';
    'VCCD012'<11>:
      PIN_NUMBER='(0,0,0,0,0,0,0,0,0,0,0,0,0,0,0,0,0,0,0,E62,0,0,0,0,0,0,0,0,0,0)';
      PINUSE='POWER';
      NO_LOAD_CHECK='Both';
      NO_IO_CHECK='Both';
      NO_ASSERT_CHECK='TRUE';
      NO_DIR_CHECK='TRUE';
      ALLOW_CONNECT='TRUE';
    'VCCD012'<10>:
      PIN_NUMBER='(0,0,0,0,0,0,0,0,0,0,0,0,0,0,0,0,0,0,0,E60,0,0,0,0,0,0,0,0,0,0)';
      PINUSE='POWER';
      NO_LOAD_CHECK='Both';
      NO_IO_CHECK='Both';
      NO_ASSERT_CHECK='TRUE';
      NO_DIR_CHECK='TRUE';
      ALLOW_CONNECT='TRUE';
    'VCCD012'<9>:
      PIN_NUMBER='(0,0,0,0,0,0,0,0,0,0,0,0,0,0,0,0,0,0,0,E58,0,0,0,0,0,0,0,0,0,0)';
      PINUSE='POWER';
      NO_LOAD_CHECK='Both';
      NO_IO_CHECK='Both';
      NO_ASSERT_CHECK='TRUE';
      NO_DIR_CHECK='TRUE';
      ALLOW_CONNECT='TRUE';
    'VCCD012'<8>:
      PIN_NUMBER='(0,0,0,0,0,0,0,0,0,0,0,0,0,0,0,0,0,0,0,E56,0,0,0,0,0,0,0,0,0,0)';
      PINUSE='POWER';
      NO_LOAD_CHECK='Both';
      NO_IO_CHECK='Both';
      NO_ASSERT_CHECK='TRUE';
      NO_DIR_CHECK='TRUE';
      ALLOW_CONNECT='TRUE';
    'VCCD012'<7>:
      PIN_NUMBER='(0,0,0,0,0,0,0,0,0,0,0,0,0,0,0,0,0,0,0,E54,0,0,0,0,0,0,0,0,0,0)';
      PINUSE='POWER';
      NO_LOAD_CHECK='Both';
      NO_IO_CHECK='Both';
      NO_ASSERT_CHECK='TRUE';
      NO_DIR_CHECK='TRUE';
      ALLOW_CONNECT='TRUE';
    'VCCD012'<6>:
      PIN_NUMBER='(0,0,0,0,0,0,0,0,0,0,0,0,0,0,0,0,0,0,0,E52,0,0,0,0,0,0,0,0,0,0)';
      PINUSE='POWER';
      NO_LOAD_CHECK='Both';
      NO_IO_CHECK='Both';
      NO_ASSERT_CHECK='TRUE';
      NO_DIR_CHECK='TRUE';
      ALLOW_CONNECT='TRUE';
    'VCCD012'<5>:
      PIN_NUMBER='(0,0,0,0,0,0,0,0,0,0,0,0,0,0,0,0,0,0,0,E50,0,0,0,0,0,0,0,0,0,0)';
      PINUSE='POWER';
      NO_LOAD_CHECK='Both';
      NO_IO_CHECK='Both';
      NO_ASSERT_CHECK='TRUE';
      NO_DIR_CHECK='TRUE';
      ALLOW_CONNECT='TRUE';
    'VCCD012'<4>:
      PIN_NUMBER='(0,0,0,0,0,0,0,0,0,0,0,0,0,0,0,0,0,0,0,E48,0,0,0,0,0,0,0,0,0,0)';
      PINUSE='POWER';
      NO_LOAD_CHECK='Both';
      NO_IO_CHECK='Both';
      NO_ASSERT_CHECK='TRUE';
      NO_DIR_CHECK='TRUE';
      ALLOW_CONNECT='TRUE';
    'VCCD012'<3>:
      PIN_NUMBER='(0,0,0,0,0,0,0,0,0,0,0,0,0,0,0,0,0,0,0,E46,0,0,0,0,0,0,0,0,0,0)';
      PINUSE='POWER';
      NO_LOAD_CHECK='Both';
      NO_IO_CHECK='Both';
      NO_ASSERT_CHECK='TRUE';
      NO_DIR_CHECK='TRUE';
      ALLOW_CONNECT='TRUE';
    'VCCD012'<2>:
      PIN_NUMBER='(0,0,0,0,0,0,0,0,0,0,0,0,0,0,0,0,0,0,0,B59,0,0,0,0,0,0,0,0,0,0)';
      PINUSE='POWER';
      NO_LOAD_CHECK='Both';
      NO_IO_CHECK='Both';
      NO_ASSERT_CHECK='TRUE';
      NO_DIR_CHECK='TRUE';
      ALLOW_CONNECT='TRUE';
    'VCCD012'<1>:
      PIN_NUMBER='(0,0,0,0,0,0,0,0,0,0,0,0,0,0,0,0,0,0,0,B53,0,0,0,0,0,0,0,0,0,0)';
      PINUSE='POWER';
      NO_LOAD_CHECK='Both';
      NO_IO_CHECK='Both';
      NO_ASSERT_CHECK='TRUE';
      NO_DIR_CHECK='TRUE';
      ALLOW_CONNECT='TRUE';
    'VCCD012'<0>:
      PIN_NUMBER='(0,0,0,0,0,0,0,0,0,0,0,0,0,0,0,0,0,0,0,B49,0,0,0,0,0,0,0,0,0,0)';
      PINUSE='POWER';
      NO_LOAD_CHECK='Both';
      NO_IO_CHECK='Both';
      NO_ASSERT_CHECK='TRUE';
      NO_DIR_CHECK='TRUE';
      ALLOW_CONNECT='TRUE';
    'VCCD345'<50>:
      PIN_NUMBER='(0,0,0,0,0,0,0,0,0,0,0,0,0,0,0,0,0,0,0,EE44,0,0,0,0,0,0,0,0,0,0)';
      PINUSE='POWER';
      NO_LOAD_CHECK='Both';
      NO_IO_CHECK='Both';
      NO_ASSERT_CHECK='TRUE';
      NO_DIR_CHECK='TRUE';
      ALLOW_CONNECT='TRUE';
    'VCCD345'<49>:
      PIN_NUMBER='(0,0,0,0,0,0,0,0,0,0,0,0,0,0,0,0,0,0,0,EF45,0,0,0,0,0,0,0,0,0,0)';
      PINUSE='POWER';
      NO_LOAD_CHECK='Both';
      NO_IO_CHECK='Both';
      NO_ASSERT_CHECK='TRUE';
      NO_DIR_CHECK='TRUE';
      ALLOW_CONNECT='TRUE';
    'VCCD345'<48>:
      PIN_NUMBER='(0,0,0,0,0,0,0,0,0,0,0,0,0,0,0,0,0,0,0,DB53,0,0,0,0,0,0,0,0,0,0)';
      PINUSE='POWER';
      NO_LOAD_CHECK='Both';
      NO_IO_CHECK='Both';
      NO_ASSERT_CHECK='TRUE';
      NO_DIR_CHECK='TRUE';
      ALLOW_CONNECT='TRUE';
    'VCCD345'<47>:
      PIN_NUMBER='(0,0,0,0,0,0,0,0,0,0,0,0,0,0,0,0,0,0,0,DB55,0,0,0,0,0,0,0,0,0,0)';
      PINUSE='POWER';
      NO_LOAD_CHECK='Both';
      NO_IO_CHECK='Both';
      NO_ASSERT_CHECK='TRUE';
      NO_DIR_CHECK='TRUE';
      ALLOW_CONNECT='TRUE';
    'VCCD345'<46>:
      PIN_NUMBER='(0,0,0,0,0,0,0,0,0,0,0,0,0,0,0,0,0,0,0,DB57,0,0,0,0,0,0,0,0,0,0)';
      PINUSE='POWER';
      NO_LOAD_CHECK='Both';
      NO_IO_CHECK='Both';
      NO_ASSERT_CHECK='TRUE';
      NO_DIR_CHECK='TRUE';
      ALLOW_CONNECT='TRUE';
    'VCCD345'<45>:
      PIN_NUMBER='(0,0,0,0,0,0,0,0,0,0,0,0,0,0,0,0,0,0,0,DB59,0,0,0,0,0,0,0,0,0,0)';
      PINUSE='POWER';
      NO_LOAD_CHECK='Both';
      NO_IO_CHECK='Both';
      NO_ASSERT_CHECK='TRUE';
      NO_DIR_CHECK='TRUE';
      ALLOW_CONNECT='TRUE';
    'VCCD345'<44>:
      PIN_NUMBER='(0,0,0,0,0,0,0,0,0,0,0,0,0,0,0,0,0,0,0,DB61,0,0,0,0,0,0,0,0,0,0)';
      PINUSE='POWER';
      NO_LOAD_CHECK='Both';
      NO_IO_CHECK='Both';
      NO_ASSERT_CHECK='TRUE';
      NO_DIR_CHECK='TRUE';
      ALLOW_CONNECT='TRUE';
    'VCCD345'<43>:
      PIN_NUMBER='(0,0,0,0,0,0,0,0,0,0,0,0,0,0,0,0,0,0,0,DB63,0,0,0,0,0,0,0,0,0,0)';
      PINUSE='POWER';
      NO_LOAD_CHECK='Both';
      NO_IO_CHECK='Both';
      NO_ASSERT_CHECK='TRUE';
      NO_DIR_CHECK='TRUE';
      ALLOW_CONNECT='TRUE';
    'VCCD345'<42>:
      PIN_NUMBER='(0,0,0,0,0,0,0,0,0,0,0,0,0,0,0,0,0,0,0,DD45,0,0,0,0,0,0,0,0,0,0)';
      PINUSE='POWER';
      NO_LOAD_CHECK='Both';
      NO_IO_CHECK='Both';
      NO_ASSERT_CHECK='TRUE';
      NO_DIR_CHECK='TRUE';
      ALLOW_CONNECT='TRUE';
    'VCCD345'<41>:
      PIN_NUMBER='(0,0,0,0,0,0,0,0,0,0,0,0,0,0,0,0,0,0,0,DH45,0,0,0,0,0,0,0,0,0,0)';
      PINUSE='POWER';
      NO_LOAD_CHECK='Both';
      NO_IO_CHECK='Both';
      NO_ASSERT_CHECK='TRUE';
      NO_DIR_CHECK='TRUE';
      ALLOW_CONNECT='TRUE';
    'VCCD345'<40>:
      PIN_NUMBER='(0,0,0,0,0,0,0,0,0,0,0,0,0,0,0,0,0,0,0,DH47,0,0,0,0,0,0,0,0,0,0)';
      PINUSE='POWER';
      NO_LOAD_CHECK='Both';
      NO_IO_CHECK='Both';
      NO_ASSERT_CHECK='TRUE';
      NO_DIR_CHECK='TRUE';
      ALLOW_CONNECT='TRUE';
    'VCCD345'<39>:
      PIN_NUMBER='(0,0,0,0,0,0,0,0,0,0,0,0,0,0,0,0,0,0,0,DH49,0,0,0,0,0,0,0,0,0,0)';
      PINUSE='POWER';
      NO_LOAD_CHECK='Both';
      NO_IO_CHECK='Both';
      NO_ASSERT_CHECK='TRUE';
      NO_DIR_CHECK='TRUE';
      ALLOW_CONNECT='TRUE';
    'VCCD345'<38>:
      PIN_NUMBER='(0,0,0,0,0,0,0,0,0,0,0,0,0,0,0,0,0,0,0,DH51,0,0,0,0,0,0,0,0,0,0)';
      PINUSE='POWER';
      NO_LOAD_CHECK='Both';
      NO_IO_CHECK='Both';
      NO_ASSERT_CHECK='TRUE';
      NO_DIR_CHECK='TRUE';
      ALLOW_CONNECT='TRUE';
    'VCCD345'<37>:
      PIN_NUMBER='(0,0,0,0,0,0,0,0,0,0,0,0,0,0,0,0,0,0,0,DH53,0,0,0,0,0,0,0,0,0,0)';
      PINUSE='POWER';
      NO_LOAD_CHECK='Both';
      NO_IO_CHECK='Both';
      NO_ASSERT_CHECK='TRUE';
      NO_DIR_CHECK='TRUE';
      ALLOW_CONNECT='TRUE';
    'VCCD345'<36>:
      PIN_NUMBER='(0,0,0,0,0,0,0,0,0,0,0,0,0,0,0,0,0,0,0,DH55,0,0,0,0,0,0,0,0,0,0)';
      PINUSE='POWER';
      NO_LOAD_CHECK='Both';
      NO_IO_CHECK='Both';
      NO_ASSERT_CHECK='TRUE';
      NO_DIR_CHECK='TRUE';
      ALLOW_CONNECT='TRUE';
    'VCCD345'<35>:
      PIN_NUMBER='(0,0,0,0,0,0,0,0,0,0,0,0,0,0,0,0,0,0,0,DH57,0,0,0,0,0,0,0,0,0,0)';
      PINUSE='POWER';
      NO_LOAD_CHECK='Both';
      NO_IO_CHECK='Both';
      NO_ASSERT_CHECK='TRUE';
      NO_DIR_CHECK='TRUE';
      ALLOW_CONNECT='TRUE';
    'VCCD345'<34>:
      PIN_NUMBER='(0,0,0,0,0,0,0,0,0,0,0,0,0,0,0,0,0,0,0,DH59,0,0,0,0,0,0,0,0,0,0)';
      PINUSE='POWER';
      NO_LOAD_CHECK='Both';
      NO_IO_CHECK='Both';
      NO_ASSERT_CHECK='TRUE';
      NO_DIR_CHECK='TRUE';
      ALLOW_CONNECT='TRUE';
    'VCCD345'<33>:
      PIN_NUMBER='(0,0,0,0,0,0,0,0,0,0,0,0,0,0,0,0,0,0,0,DH61,0,0,0,0,0,0,0,0,0,0)';
      PINUSE='POWER';
      NO_LOAD_CHECK='Both';
      NO_IO_CHECK='Both';
      NO_ASSERT_CHECK='TRUE';
      NO_DIR_CHECK='TRUE';
      ALLOW_CONNECT='TRUE';
    'VCCD345'<32>:
      PIN_NUMBER='(0,0,0,0,0,0,0,0,0,0,0,0,0,0,0,0,0,0,0,DH63,0,0,0,0,0,0,0,0,0,0)';
      PINUSE='POWER';
      NO_LOAD_CHECK='Both';
      NO_IO_CHECK='Both';
      NO_ASSERT_CHECK='TRUE';
      NO_DIR_CHECK='TRUE';
      ALLOW_CONNECT='TRUE';
    'VCCD345'<31>:
      PIN_NUMBER='(0,0,0,0,0,0,0,0,0,0,0,0,0,0,0,0,0,0,0,DJ64,0,0,0,0,0,0,0,0,0,0)';
      PINUSE='POWER';
      NO_LOAD_CHECK='Both';
      NO_IO_CHECK='Both';
      NO_ASSERT_CHECK='TRUE';
      NO_DIR_CHECK='TRUE';
      ALLOW_CONNECT='TRUE';
    'VCCD345'<30>:
      PIN_NUMBER='(0,0,0,0,0,0,0,0,0,0,0,0,0,0,0,0,0,0,0,DL46,0,0,0,0,0,0,0,0,0,0)';
      PINUSE='POWER';
      NO_LOAD_CHECK='Both';
      NO_IO_CHECK='Both';
      NO_ASSERT_CHECK='TRUE';
      NO_DIR_CHECK='TRUE';
      ALLOW_CONNECT='TRUE';
    'VCCD345'<29>:
      PIN_NUMBER='(0,0,0,0,0,0,0,0,0,0,0,0,0,0,0,0,0,0,0,DL48,0,0,0,0,0,0,0,0,0,0)';
      PINUSE='POWER';
      NO_LOAD_CHECK='Both';
      NO_IO_CHECK='Both';
      NO_ASSERT_CHECK='TRUE';
      NO_DIR_CHECK='TRUE';
      ALLOW_CONNECT='TRUE';
    'VCCD345'<28>:
      PIN_NUMBER='(0,0,0,0,0,0,0,0,0,0,0,0,0,0,0,0,0,0,0,DL50,0,0,0,0,0,0,0,0,0,0)';
      PINUSE='POWER';
      NO_LOAD_CHECK='Both';
      NO_IO_CHECK='Both';
      NO_ASSERT_CHECK='TRUE';
      NO_DIR_CHECK='TRUE';
      ALLOW_CONNECT='TRUE';
    'VCCD345'<27>:
      PIN_NUMBER='(0,0,0,0,0,0,0,0,0,0,0,0,0,0,0,0,0,0,0,DL52,0,0,0,0,0,0,0,0,0,0)';
      PINUSE='POWER';
      NO_LOAD_CHECK='Both';
      NO_IO_CHECK='Both';
      NO_ASSERT_CHECK='TRUE';
      NO_DIR_CHECK='TRUE';
      ALLOW_CONNECT='TRUE';
    'VCCD345'<26>:
      PIN_NUMBER='(0,0,0,0,0,0,0,0,0,0,0,0,0,0,0,0,0,0,0,DL54,0,0,0,0,0,0,0,0,0,0)';
      PINUSE='POWER';
      NO_LOAD_CHECK='Both';
      NO_IO_CHECK='Both';
      NO_ASSERT_CHECK='TRUE';
      NO_DIR_CHECK='TRUE';
      ALLOW_CONNECT='TRUE';
    'VCCD345'<25>:
      PIN_NUMBER='(0,0,0,0,0,0,0,0,0,0,0,0,0,0,0,0,0,0,0,DL56,0,0,0,0,0,0,0,0,0,0)';
      PINUSE='POWER';
      NO_LOAD_CHECK='Both';
      NO_IO_CHECK='Both';
      NO_ASSERT_CHECK='TRUE';
      NO_DIR_CHECK='TRUE';
      ALLOW_CONNECT='TRUE';
    'VCCD345'<24>:
      PIN_NUMBER='(0,0,0,0,0,0,0,0,0,0,0,0,0,0,0,0,0,0,0,DL58,0,0,0,0,0,0,0,0,0,0)';
      PINUSE='POWER';
      NO_LOAD_CHECK='Both';
      NO_IO_CHECK='Both';
      NO_ASSERT_CHECK='TRUE';
      NO_DIR_CHECK='TRUE';
      ALLOW_CONNECT='TRUE';
    'VCCD345'<23>:
      PIN_NUMBER='(0,0,0,0,0,0,0,0,0,0,0,0,0,0,0,0,0,0,0,DL60,0,0,0,0,0,0,0,0,0,0)';
      PINUSE='POWER';
      NO_LOAD_CHECK='Both';
      NO_IO_CHECK='Both';
      NO_ASSERT_CHECK='TRUE';
      NO_DIR_CHECK='TRUE';
      ALLOW_CONNECT='TRUE';
    'VCCD345'<22>:
      PIN_NUMBER='(0,0,0,0,0,0,0,0,0,0,0,0,0,0,0,0,0,0,0,DL62,0,0,0,0,0,0,0,0,0,0)';
      PINUSE='POWER';
      NO_LOAD_CHECK='Both';
      NO_IO_CHECK='Both';
      NO_ASSERT_CHECK='TRUE';
      NO_DIR_CHECK='TRUE';
      ALLOW_CONNECT='TRUE';
    'VCCD345'<21>:
      PIN_NUMBER='(0,0,0,0,0,0,0,0,0,0,0,0,0,0,0,0,0,0,0,DU46,0,0,0,0,0,0,0,0,0,0)';
      PINUSE='POWER';
      NO_LOAD_CHECK='Both';
      NO_IO_CHECK='Both';
      NO_ASSERT_CHECK='TRUE';
      NO_DIR_CHECK='TRUE';
      ALLOW_CONNECT='TRUE';
    'VCCD345'<20>:
      PIN_NUMBER='(0,0,0,0,0,0,0,0,0,0,0,0,0,0,0,0,0,0,0,DU48,0,0,0,0,0,0,0,0,0,0)';
      PINUSE='POWER';
      NO_LOAD_CHECK='Both';
      NO_IO_CHECK='Both';
      NO_ASSERT_CHECK='TRUE';
      NO_DIR_CHECK='TRUE';
      ALLOW_CONNECT='TRUE';
    'VCCD345'<19>:
      PIN_NUMBER='(0,0,0,0,0,0,0,0,0,0,0,0,0,0,0,0,0,0,0,DU50,0,0,0,0,0,0,0,0,0,0)';
      PINUSE='POWER';
      NO_LOAD_CHECK='Both';
      NO_IO_CHECK='Both';
      NO_ASSERT_CHECK='TRUE';
      NO_DIR_CHECK='TRUE';
      ALLOW_CONNECT='TRUE';
    'VCCD345'<18>:
      PIN_NUMBER='(0,0,0,0,0,0,0,0,0,0,0,0,0,0,0,0,0,0,0,DU52,0,0,0,0,0,0,0,0,0,0)';
      PINUSE='POWER';
      NO_LOAD_CHECK='Both';
      NO_IO_CHECK='Both';
      NO_ASSERT_CHECK='TRUE';
      NO_DIR_CHECK='TRUE';
      ALLOW_CONNECT='TRUE';
    'VCCD345'<17>:
      PIN_NUMBER='(0,0,0,0,0,0,0,0,0,0,0,0,0,0,0,0,0,0,0,DU54,0,0,0,0,0,0,0,0,0,0)';
      PINUSE='POWER';
      NO_LOAD_CHECK='Both';
      NO_IO_CHECK='Both';
      NO_ASSERT_CHECK='TRUE';
      NO_DIR_CHECK='TRUE';
      ALLOW_CONNECT='TRUE';
    'VCCD345'<16>:
      PIN_NUMBER='(0,0,0,0,0,0,0,0,0,0,0,0,0,0,0,0,0,0,0,DU56,0,0,0,0,0,0,0,0,0,0)';
      PINUSE='POWER';
      NO_LOAD_CHECK='Both';
      NO_IO_CHECK='Both';
      NO_ASSERT_CHECK='TRUE';
      NO_DIR_CHECK='TRUE';
      ALLOW_CONNECT='TRUE';
    'VCCD345'<15>:
      PIN_NUMBER='(0,0,0,0,0,0,0,0,0,0,0,0,0,0,0,0,0,0,0,DU58,0,0,0,0,0,0,0,0,0,0)';
      PINUSE='POWER';
      NO_LOAD_CHECK='Both';
      NO_IO_CHECK='Both';
      NO_ASSERT_CHECK='TRUE';
      NO_DIR_CHECK='TRUE';
      ALLOW_CONNECT='TRUE';
    'VCCD345'<14>:
      PIN_NUMBER='(0,0,0,0,0,0,0,0,0,0,0,0,0,0,0,0,0,0,0,DU60,0,0,0,0,0,0,0,0,0,0)';
      PINUSE='POWER';
      NO_LOAD_CHECK='Both';
      NO_IO_CHECK='Both';
      NO_ASSERT_CHECK='TRUE';
      NO_DIR_CHECK='TRUE';
      ALLOW_CONNECT='TRUE';
    'VCCD345'<13>:
      PIN_NUMBER='(0,0,0,0,0,0,0,0,0,0,0,0,0,0,0,0,0,0,0,DU62,0,0,0,0,0,0,0,0,0,0)';
      PINUSE='POWER';
      NO_LOAD_CHECK='Both';
      NO_IO_CHECK='Both';
      NO_ASSERT_CHECK='TRUE';
      NO_DIR_CHECK='TRUE';
      ALLOW_CONNECT='TRUE';
    'VCCD345'<12>:
      PIN_NUMBER='(0,0,0,0,0,0,0,0,0,0,0,0,0,0,0,0,0,0,0,DU64,0,0,0,0,0,0,0,0,0,0)';
      PINUSE='POWER';
      NO_LOAD_CHECK='Both';
      NO_IO_CHECK='Both';
      NO_ASSERT_CHECK='TRUE';
      NO_DIR_CHECK='TRUE';
      ALLOW_CONNECT='TRUE';
    'VCCD345'<11>:
      PIN_NUMBER='(0,0,0,0,0,0,0,0,0,0,0,0,0,0,0,0,0,0,0,EC46,0,0,0,0,0,0,0,0,0,0)';
      PINUSE='POWER';
      NO_LOAD_CHECK='Both';
      NO_IO_CHECK='Both';
      NO_ASSERT_CHECK='TRUE';
      NO_DIR_CHECK='TRUE';
      ALLOW_CONNECT='TRUE';
    'VCCD345'<10>:
      PIN_NUMBER='(0,0,0,0,0,0,0,0,0,0,0,0,0,0,0,0,0,0,0,EC48,0,0,0,0,0,0,0,0,0,0)';
      PINUSE='POWER';
      NO_LOAD_CHECK='Both';
      NO_IO_CHECK='Both';
      NO_ASSERT_CHECK='TRUE';
      NO_DIR_CHECK='TRUE';
      ALLOW_CONNECT='TRUE';
    'VCCD345'<9>:
      PIN_NUMBER='(0,0,0,0,0,0,0,0,0,0,0,0,0,0,0,0,0,0,0,EC50,0,0,0,0,0,0,0,0,0,0)';
      PINUSE='POWER';
      NO_LOAD_CHECK='Both';
      NO_IO_CHECK='Both';
      NO_ASSERT_CHECK='TRUE';
      NO_DIR_CHECK='TRUE';
      ALLOW_CONNECT='TRUE';
    'VCCD345'<8>:
      PIN_NUMBER='(0,0,0,0,0,0,0,0,0,0,0,0,0,0,0,0,0,0,0,EC52,0,0,0,0,0,0,0,0,0,0)';
      PINUSE='POWER';
      NO_LOAD_CHECK='Both';
      NO_IO_CHECK='Both';
      NO_ASSERT_CHECK='TRUE';
      NO_DIR_CHECK='TRUE';
      ALLOW_CONNECT='TRUE';
    'VCCD345'<7>:
      PIN_NUMBER='(0,0,0,0,0,0,0,0,0,0,0,0,0,0,0,0,0,0,0,EC54,0,0,0,0,0,0,0,0,0,0)';
      PINUSE='POWER';
      NO_LOAD_CHECK='Both';
      NO_IO_CHECK='Both';
      NO_ASSERT_CHECK='TRUE';
      NO_DIR_CHECK='TRUE';
      ALLOW_CONNECT='TRUE';
    'VCCD345'<6>:
      PIN_NUMBER='(0,0,0,0,0,0,0,0,0,0,0,0,0,0,0,0,0,0,0,EC56,0,0,0,0,0,0,0,0,0,0)';
      PINUSE='POWER';
      NO_LOAD_CHECK='Both';
      NO_IO_CHECK='Both';
      NO_ASSERT_CHECK='TRUE';
      NO_DIR_CHECK='TRUE';
      ALLOW_CONNECT='TRUE';
    'VCCD345'<5>:
      PIN_NUMBER='(0,0,0,0,0,0,0,0,0,0,0,0,0,0,0,0,0,0,0,EC58,0,0,0,0,0,0,0,0,0,0)';
      PINUSE='POWER';
      NO_LOAD_CHECK='Both';
      NO_IO_CHECK='Both';
      NO_ASSERT_CHECK='TRUE';
      NO_DIR_CHECK='TRUE';
      ALLOW_CONNECT='TRUE';
    'VCCD345'<4>:
      PIN_NUMBER='(0,0,0,0,0,0,0,0,0,0,0,0,0,0,0,0,0,0,0,EC60,0,0,0,0,0,0,0,0,0,0)';
      PINUSE='POWER';
      NO_LOAD_CHECK='Both';
      NO_IO_CHECK='Both';
      NO_ASSERT_CHECK='TRUE';
      NO_DIR_CHECK='TRUE';
      ALLOW_CONNECT='TRUE';
    'VCCD345'<3>:
      PIN_NUMBER='(0,0,0,0,0,0,0,0,0,0,0,0,0,0,0,0,0,0,0,EC62,0,0,0,0,0,0,0,0,0,0)';
      PINUSE='POWER';
      NO_LOAD_CHECK='Both';
      NO_IO_CHECK='Both';
      NO_ASSERT_CHECK='TRUE';
      NO_DIR_CHECK='TRUE';
      ALLOW_CONNECT='TRUE';
    'VCCD345'<2>:
      PIN_NUMBER='(0,0,0,0,0,0,0,0,0,0,0,0,0,0,0,0,0,0,0,EF49,0,0,0,0,0,0,0,0,0,0)';
      PINUSE='POWER';
      NO_LOAD_CHECK='Both';
      NO_IO_CHECK='Both';
      NO_ASSERT_CHECK='TRUE';
      NO_DIR_CHECK='TRUE';
      ALLOW_CONNECT='TRUE';
    'VCCD345'<1>:
      PIN_NUMBER='(0,0,0,0,0,0,0,0,0,0,0,0,0,0,0,0,0,0,0,EF53,0,0,0,0,0,0,0,0,0,0)';
      PINUSE='POWER';
      NO_LOAD_CHECK='Both';
      NO_IO_CHECK='Both';
      NO_ASSERT_CHECK='TRUE';
      NO_DIR_CHECK='TRUE';
      ALLOW_CONNECT='TRUE';
    'VCCD345'<0>:
      PIN_NUMBER='(0,0,0,0,0,0,0,0,0,0,0,0,0,0,0,0,0,0,0,EF59,0,0,0,0,0,0,0,0,0,0)';
      PINUSE='POWER';
      NO_LOAD_CHECK='Both';
      NO_IO_CHECK='Both';
      NO_ASSERT_CHECK='TRUE';
      NO_DIR_CHECK='TRUE';
      ALLOW_CONNECT='TRUE';
    'VCCIN'<267>:
      PIN_NUMBER='(0,0,0,0,0,0,0,0,0,0,0,0,0,0,0,0,0,AF43,0,0,0,0,0,0,0,0,0,0,0,0)';
      PINUSE='POWER';
      NO_LOAD_CHECK='Both';
      NO_IO_CHECK='Both';
      NO_ASSERT_CHECK='TRUE';
      NO_DIR_CHECK='TRUE';
      ALLOW_CONNECT='TRUE';
    'VCCIN'<266>:
      PIN_NUMBER='(0,0,0,0,0,0,0,0,0,0,0,0,0,0,0,0,0,AG38,0,0,0,0,0,0,0,0,0,0,0,0)';
      PINUSE='POWER';
      NO_LOAD_CHECK='Both';
      NO_IO_CHECK='Both';
      NO_ASSERT_CHECK='TRUE';
      NO_DIR_CHECK='TRUE';
      ALLOW_CONNECT='TRUE';
    'VCCIN'<265>:
      PIN_NUMBER='(0,0,0,0,0,0,0,0,0,0,0,0,0,0,0,0,0,AG40,0,0,0,0,0,0,0,0,0,0,0,0)';
      PINUSE='POWER';
      NO_LOAD_CHECK='Both';
      NO_IO_CHECK='Both';
      NO_ASSERT_CHECK='TRUE';
      NO_DIR_CHECK='TRUE';
      ALLOW_CONNECT='TRUE';
    'VCCIN'<264>:
      PIN_NUMBER='(0,0,0,0,0,0,0,0,0,0,0,0,0,0,0,0,0,AG42,0,0,0,0,0,0,0,0,0,0,0,0)';
      PINUSE='POWER';
      NO_LOAD_CHECK='Both';
      NO_IO_CHECK='Both';
      NO_ASSERT_CHECK='TRUE';
      NO_DIR_CHECK='TRUE';
      ALLOW_CONNECT='TRUE';
    'VCCIN'<263>:
      PIN_NUMBER='(0,0,0,0,0,0,0,0,0,0,0,0,0,0,0,0,0,AH37,0,0,0,0,0,0,0,0,0,0,0,0)';
      PINUSE='POWER';
      NO_LOAD_CHECK='Both';
      NO_IO_CHECK='Both';
      NO_ASSERT_CHECK='TRUE';
      NO_DIR_CHECK='TRUE';
      ALLOW_CONNECT='TRUE';
    'VCCIN'<262>:
      PIN_NUMBER='(0,0,0,0,0,0,0,0,0,0,0,0,0,0,0,0,0,AH39,0,0,0,0,0,0,0,0,0,0,0,0)';
      PINUSE='POWER';
      NO_LOAD_CHECK='Both';
      NO_IO_CHECK='Both';
      NO_ASSERT_CHECK='TRUE';
      NO_DIR_CHECK='TRUE';
      ALLOW_CONNECT='TRUE';
    'VCCIN'<261>:
      PIN_NUMBER='(0,0,0,0,0,0,0,0,0,0,0,0,0,0,0,0,0,AH41,0,0,0,0,0,0,0,0,0,0,0,0)';
      PINUSE='POWER';
      NO_LOAD_CHECK='Both';
      NO_IO_CHECK='Both';
      NO_ASSERT_CHECK='TRUE';
      NO_DIR_CHECK='TRUE';
      ALLOW_CONNECT='TRUE';
    'VCCIN'<260>:
      PIN_NUMBER='(0,0,0,0,0,0,0,0,0,0,0,0,0,0,0,0,0,AJ36,0,0,0,0,0,0,0,0,0,0,0,0)';
      PINUSE='POWER';
      NO_LOAD_CHECK='Both';
      NO_IO_CHECK='Both';
      NO_ASSERT_CHECK='TRUE';
      NO_DIR_CHECK='TRUE';
      ALLOW_CONNECT='TRUE';
    'VCCIN'<259>:
      PIN_NUMBER='(0,0,0,0,0,0,0,0,0,0,0,0,0,0,0,0,0,AK35,0,0,0,0,0,0,0,0,0,0,0,0)';
      PINUSE='POWER';
      NO_LOAD_CHECK='Both';
      NO_IO_CHECK='Both';
      NO_ASSERT_CHECK='TRUE';
      NO_DIR_CHECK='TRUE';
      ALLOW_CONNECT='TRUE';
    'VCCIN'<258>:
      PIN_NUMBER='(0,0,0,0,0,0,0,0,0,0,0,0,0,0,0,0,0,AK45,0,0,0,0,0,0,0,0,0,0,0,0)';
      PINUSE='POWER';
      NO_LOAD_CHECK='Both';
      NO_IO_CHECK='Both';
      NO_ASSERT_CHECK='TRUE';
      NO_DIR_CHECK='TRUE';
      ALLOW_CONNECT='TRUE';
    'VCCIN'<257>:
      PIN_NUMBER='(0,0,0,0,0,0,0,0,0,0,0,0,0,0,0,0,0,AK47,0,0,0,0,0,0,0,0,0,0,0,0)';
      PINUSE='POWER';
      NO_LOAD_CHECK='Both';
      NO_IO_CHECK='Both';
      NO_ASSERT_CHECK='TRUE';
      NO_DIR_CHECK='TRUE';
      ALLOW_CONNECT='TRUE';
    'VCCIN'<256>:
      PIN_NUMBER='(0,0,0,0,0,0,0,0,0,0,0,0,0,0,0,0,0,AK49,0,0,0,0,0,0,0,0,0,0,0,0)';
      PINUSE='POWER';
      NO_LOAD_CHECK='Both';
      NO_IO_CHECK='Both';
      NO_ASSERT_CHECK='TRUE';
      NO_DIR_CHECK='TRUE';
      ALLOW_CONNECT='TRUE';
    'VCCIN'<255>:
      PIN_NUMBER='(0,0,0,0,0,0,0,0,0,0,0,0,0,0,0,0,0,AK51,0,0,0,0,0,0,0,0,0,0,0,0)';
      PINUSE='POWER';
      NO_LOAD_CHECK='Both';
      NO_IO_CHECK='Both';
      NO_ASSERT_CHECK='TRUE';
      NO_DIR_CHECK='TRUE';
      ALLOW_CONNECT='TRUE';
    'VCCIN'<254>:
      PIN_NUMBER='(0,0,0,0,0,0,0,0,0,0,0,0,0,0,0,0,0,AK53,0,0,0,0,0,0,0,0,0,0,0,0)';
      PINUSE='POWER';
      NO_LOAD_CHECK='Both';
      NO_IO_CHECK='Both';
      NO_ASSERT_CHECK='TRUE';
      NO_DIR_CHECK='TRUE';
      ALLOW_CONNECT='TRUE';
    'VCCIN'<253>:
      PIN_NUMBER='(0,0,0,0,0,0,0,0,0,0,0,0,0,0,0,0,0,AL34,0,0,0,0,0,0,0,0,0,0,0,0)';
      PINUSE='POWER';
      NO_LOAD_CHECK='Both';
      NO_IO_CHECK='Both';
      NO_ASSERT_CHECK='TRUE';
      NO_DIR_CHECK='TRUE';
      ALLOW_CONNECT='TRUE';
    'VCCIN'<252>:
      PIN_NUMBER='(0,0,0,0,0,0,0,0,0,0,0,0,0,0,0,0,0,AL46,0,0,0,0,0,0,0,0,0,0,0,0)';
      PINUSE='POWER';
      NO_LOAD_CHECK='Both';
      NO_IO_CHECK='Both';
      NO_ASSERT_CHECK='TRUE';
      NO_DIR_CHECK='TRUE';
      ALLOW_CONNECT='TRUE';
    'VCCIN'<251>:
      PIN_NUMBER='(0,0,0,0,0,0,0,0,0,0,0,0,0,0,0,0,0,AL48,0,0,0,0,0,0,0,0,0,0,0,0)';
      PINUSE='POWER';
      NO_LOAD_CHECK='Both';
      NO_IO_CHECK='Both';
      NO_ASSERT_CHECK='TRUE';
      NO_DIR_CHECK='TRUE';
      ALLOW_CONNECT='TRUE';
    'VCCIN'<250>:
      PIN_NUMBER='(0,0,0,0,0,0,0,0,0,0,0,0,0,0,0,0,0,AL50,0,0,0,0,0,0,0,0,0,0,0,0)';
      PINUSE='POWER';
      NO_LOAD_CHECK='Both';
      NO_IO_CHECK='Both';
      NO_ASSERT_CHECK='TRUE';
      NO_DIR_CHECK='TRUE';
      ALLOW_CONNECT='TRUE';
    'VCCIN'<249>:
      PIN_NUMBER='(0,0,0,0,0,0,0,0,0,0,0,0,0,0,0,0,0,AL52,0,0,0,0,0,0,0,0,0,0,0,0)';
      PINUSE='POWER';
      NO_LOAD_CHECK='Both';
      NO_IO_CHECK='Both';
      NO_ASSERT_CHECK='TRUE';
      NO_DIR_CHECK='TRUE';
      ALLOW_CONNECT='TRUE';
    'VCCIN'<248>:
      PIN_NUMBER='(0,0,0,0,0,0,0,0,0,0,0,0,0,0,0,0,0,AL54,0,0,0,0,0,0,0,0,0,0,0,0)';
      PINUSE='POWER';
      NO_LOAD_CHECK='Both';
      NO_IO_CHECK='Both';
      NO_ASSERT_CHECK='TRUE';
      NO_DIR_CHECK='TRUE';
      ALLOW_CONNECT='TRUE';
    'VCCIN'<247>:
      PIN_NUMBER='(0,0,0,0,0,0,0,0,0,0,0,0,0,0,0,0,0,AM33,0,0,0,0,0,0,0,0,0,0,0,0)';
      PINUSE='POWER';
      NO_LOAD_CHECK='Both';
      NO_IO_CHECK='Both';
      NO_ASSERT_CHECK='TRUE';
      NO_DIR_CHECK='TRUE';
      ALLOW_CONNECT='TRUE';
    'VCCIN'<246>:
      PIN_NUMBER='(0,0,0,0,0,0,0,0,0,0,0,0,0,0,0,0,0,AM53,0,0,0,0,0,0,0,0,0,0,0,0)';
      PINUSE='POWER';
      NO_LOAD_CHECK='Both';
      NO_IO_CHECK='Both';
      NO_ASSERT_CHECK='TRUE';
      NO_DIR_CHECK='TRUE';
      ALLOW_CONNECT='TRUE';
    'VCCIN'<245>:
      PIN_NUMBER='(0,0,0,0,0,0,0,0,0,0,0,0,0,0,0,0,0,AM55,0,0,0,0,0,0,0,0,0,0,0,0)';
      PINUSE='POWER';
      NO_LOAD_CHECK='Both';
      NO_IO_CHECK='Both';
      NO_ASSERT_CHECK='TRUE';
      NO_DIR_CHECK='TRUE';
      ALLOW_CONNECT='TRUE';
    'VCCIN'<244>:
      PIN_NUMBER='(0,0,0,0,0,0,0,0,0,0,0,0,0,0,0,0,0,AN32,0,0,0,0,0,0,0,0,0,0,0,0)';
      PINUSE='POWER';
      NO_LOAD_CHECK='Both';
      NO_IO_CHECK='Both';
      NO_ASSERT_CHECK='TRUE';
      NO_DIR_CHECK='TRUE';
      ALLOW_CONNECT='TRUE';
    'VCCIN'<243>:
      PIN_NUMBER='(0,0,0,0,0,0,0,0,0,0,0,0,0,0,0,0,0,AN54,0,0,0,0,0,0,0,0,0,0,0,0)';
      PINUSE='POWER';
      NO_LOAD_CHECK='Both';
      NO_IO_CHECK='Both';
      NO_ASSERT_CHECK='TRUE';
      NO_DIR_CHECK='TRUE';
      ALLOW_CONNECT='TRUE';
    'VCCIN'<242>:
      PIN_NUMBER='(0,0,0,0,0,0,0,0,0,0,0,0,0,0,0,0,0,AN56,0,0,0,0,0,0,0,0,0,0,0,0)';
      PINUSE='POWER';
      NO_LOAD_CHECK='Both';
      NO_IO_CHECK='Both';
      NO_ASSERT_CHECK='TRUE';
      NO_DIR_CHECK='TRUE';
      ALLOW_CONNECT='TRUE';
    'VCCIN'<241>:
      PIN_NUMBER='(0,0,0,0,0,0,0,0,0,0,0,0,0,0,0,0,0,AP55,0,0,0,0,0,0,0,0,0,0,0,0)';
      PINUSE='POWER';
      NO_LOAD_CHECK='Both';
      NO_IO_CHECK='Both';
      NO_ASSERT_CHECK='TRUE';
      NO_DIR_CHECK='TRUE';
      ALLOW_CONNECT='TRUE';
    'VCCIN'<240>:
      PIN_NUMBER='(0,0,0,0,0,0,0,0,0,0,0,0,0,0,0,0,0,AP57,0,0,0,0,0,0,0,0,0,0,0,0)';
      PINUSE='POWER';
      NO_LOAD_CHECK='Both';
      NO_IO_CHECK='Both';
      NO_ASSERT_CHECK='TRUE';
      NO_DIR_CHECK='TRUE';
      ALLOW_CONNECT='TRUE';
    'VCCIN'<239>:
      PIN_NUMBER='(0,0,0,0,0,0,0,0,0,0,0,0,0,0,0,0,0,AR56,0,0,0,0,0,0,0,0,0,0,0,0)';
      PINUSE='POWER';
      NO_LOAD_CHECK='Both';
      NO_IO_CHECK='Both';
      NO_ASSERT_CHECK='TRUE';
      NO_DIR_CHECK='TRUE';
      ALLOW_CONNECT='TRUE';
    'VCCIN'<238>:
      PIN_NUMBER='(0,0,0,0,0,0,0,0,0,0,0,0,0,0,0,0,0,AR58,0,0,0,0,0,0,0,0,0,0,0,0)';
      PINUSE='POWER';
      NO_LOAD_CHECK='Both';
      NO_IO_CHECK='Both';
      NO_ASSERT_CHECK='TRUE';
      NO_DIR_CHECK='TRUE';
      ALLOW_CONNECT='TRUE';
    'VCCIN'<237>:
      PIN_NUMBER='(0,0,0,0,0,0,0,0,0,0,0,0,0,0,0,0,0,AT57,0,0,0,0,0,0,0,0,0,0,0,0)';
      PINUSE='POWER';
      NO_LOAD_CHECK='Both';
      NO_IO_CHECK='Both';
      NO_ASSERT_CHECK='TRUE';
      NO_DIR_CHECK='TRUE';
      ALLOW_CONNECT='TRUE';
    'VCCIN'<236>:
      PIN_NUMBER='(0,0,0,0,0,0,0,0,0,0,0,0,0,0,0,0,0,AT59,0,0,0,0,0,0,0,0,0,0,0,0)';
      PINUSE='POWER';
      NO_LOAD_CHECK='Both';
      NO_IO_CHECK='Both';
      NO_ASSERT_CHECK='TRUE';
      NO_DIR_CHECK='TRUE';
      ALLOW_CONNECT='TRUE';
    'VCCIN'<235>:
      PIN_NUMBER='(0,0,0,0,0,0,0,0,0,0,0,0,0,0,0,0,0,AU58,0,0,0,0,0,0,0,0,0,0,0,0)';
      PINUSE='POWER';
      NO_LOAD_CHECK='Both';
      NO_IO_CHECK='Both';
      NO_ASSERT_CHECK='TRUE';
      NO_DIR_CHECK='TRUE';
      ALLOW_CONNECT='TRUE';
    'VCCIN'<234>:
      PIN_NUMBER='(0,0,0,0,0,0,0,0,0,0,0,0,0,0,0,0,0,AU60,0,0,0,0,0,0,0,0,0,0,0,0)';
      PINUSE='POWER';
      NO_LOAD_CHECK='Both';
      NO_IO_CHECK='Both';
      NO_ASSERT_CHECK='TRUE';
      NO_DIR_CHECK='TRUE';
      ALLOW_CONNECT='TRUE';
    'VCCIN'<233>:
      PIN_NUMBER='(0,0,0,0,0,0,0,0,0,0,0,0,0,0,0,0,0,AV59,0,0,0,0,0,0,0,0,0,0,0,0)';
      PINUSE='POWER';
      NO_LOAD_CHECK='Both';
      NO_IO_CHECK='Both';
      NO_ASSERT_CHECK='TRUE';
      NO_DIR_CHECK='TRUE';
      ALLOW_CONNECT='TRUE';
    'VCCIN'<232>:
      PIN_NUMBER='(0,0,0,0,0,0,0,0,0,0,0,0,0,0,0,0,0,AV61,0,0,0,0,0,0,0,0,0,0,0,0)';
      PINUSE='POWER';
      NO_LOAD_CHECK='Both';
      NO_IO_CHECK='Both';
      NO_ASSERT_CHECK='TRUE';
      NO_DIR_CHECK='TRUE';
      ALLOW_CONNECT='TRUE';
    'VCCIN'<231>:
      PIN_NUMBER='(0,0,0,0,0,0,0,0,0,0,0,0,0,0,0,0,0,AW60,0,0,0,0,0,0,0,0,0,0,0,0)';
      PINUSE='POWER';
      NO_LOAD_CHECK='Both';
      NO_IO_CHECK='Both';
      NO_ASSERT_CHECK='TRUE';
      NO_DIR_CHECK='TRUE';
      ALLOW_CONNECT='TRUE';
    'VCCIN'<230>:
      PIN_NUMBER='(0,0,0,0,0,0,0,0,0,0,0,0,0,0,0,0,0,AY61,0,0,0,0,0,0,0,0,0,0,0,0)';
      PINUSE='POWER';
      NO_LOAD_CHECK='Both';
      NO_IO_CHECK='Both';
      NO_ASSERT_CHECK='TRUE';
      NO_DIR_CHECK='TRUE';
      ALLOW_CONNECT='TRUE';
    'VCCIN'<229>:
      PIN_NUMBER='(0,0,0,0,0,0,0,0,0,0,0,0,0,0,0,0,0,BA60,0,0,0,0,0,0,0,0,0,0,0,0)';
      PINUSE='POWER';
      NO_LOAD_CHECK='Both';
      NO_IO_CHECK='Both';
      NO_ASSERT_CHECK='TRUE';
      NO_DIR_CHECK='TRUE';
      ALLOW_CONNECT='TRUE';
    'VCCIN'<228>:
      PIN_NUMBER='(0,0,0,0,0,0,0,0,0,0,0,0,0,0,0,0,0,BB61,0,0,0,0,0,0,0,0,0,0,0,0)';
      PINUSE='POWER';
      NO_LOAD_CHECK='Both';
      NO_IO_CHECK='Both';
      NO_ASSERT_CHECK='TRUE';
      NO_DIR_CHECK='TRUE';
      ALLOW_CONNECT='TRUE';
    'VCCIN'<227>:
      PIN_NUMBER='(0,0,0,0,0,0,0,0,0,0,0,0,0,0,0,0,0,BB85,0,0,0,0,0,0,0,0,0,0,0,0)';
      PINUSE='POWER';
      NO_LOAD_CHECK='Both';
      NO_IO_CHECK='Both';
      NO_ASSERT_CHECK='TRUE';
      NO_DIR_CHECK='TRUE';
      ALLOW_CONNECT='TRUE';
    'VCCIN'<226>:
      PIN_NUMBER='(0,0,0,0,0,0,0,0,0,0,0,0,0,0,0,0,0,BC60,0,0,0,0,0,0,0,0,0,0,0,0)';
      PINUSE='POWER';
      NO_LOAD_CHECK='Both';
      NO_IO_CHECK='Both';
      NO_ASSERT_CHECK='TRUE';
      NO_DIR_CHECK='TRUE';
      ALLOW_CONNECT='TRUE';
    'VCCIN'<225>:
      PIN_NUMBER='(0,0,0,0,0,0,0,0,0,0,0,0,0,0,0,0,0,BC62,0,0,0,0,0,0,0,0,0,0,0,0)';
      PINUSE='POWER';
      NO_LOAD_CHECK='Both';
      NO_IO_CHECK='Both';
      NO_ASSERT_CHECK='TRUE';
      NO_DIR_CHECK='TRUE';
      ALLOW_CONNECT='TRUE';
    'VCCIN'<224>:
      PIN_NUMBER='(0,0,0,0,0,0,0,0,0,0,0,0,0,0,0,0,0,BC84,0,0,0,0,0,0,0,0,0,0,0,0)';
      PINUSE='POWER';
      NO_LOAD_CHECK='Both';
      NO_IO_CHECK='Both';
      NO_ASSERT_CHECK='TRUE';
      NO_DIR_CHECK='TRUE';
      ALLOW_CONNECT='TRUE';
    'VCCIN'<223>:
      PIN_NUMBER='(0,0,0,0,0,0,0,0,0,0,0,0,0,0,0,0,0,BD61,0,0,0,0,0,0,0,0,0,0,0,0)';
      PINUSE='POWER';
      NO_LOAD_CHECK='Both';
      NO_IO_CHECK='Both';
      NO_ASSERT_CHECK='TRUE';
      NO_DIR_CHECK='TRUE';
      ALLOW_CONNECT='TRUE';
    'VCCIN'<222>:
      PIN_NUMBER='(0,0,0,0,0,0,0,0,0,0,0,0,0,0,0,0,0,BD73,0,0,0,0,0,0,0,0,0,0,0,0)';
      PINUSE='POWER';
      NO_LOAD_CHECK='Both';
      NO_IO_CHECK='Both';
      NO_ASSERT_CHECK='TRUE';
      NO_DIR_CHECK='TRUE';
      ALLOW_CONNECT='TRUE';
    'VCCIN'<221>:
      PIN_NUMBER='(0,0,0,0,0,0,0,0,0,0,0,0,0,0,0,0,0,BD75,0,0,0,0,0,0,0,0,0,0,0,0)';
      PINUSE='POWER';
      NO_LOAD_CHECK='Both';
      NO_IO_CHECK='Both';
      NO_ASSERT_CHECK='TRUE';
      NO_DIR_CHECK='TRUE';
      ALLOW_CONNECT='TRUE';
    'VCCIN'<220>:
      PIN_NUMBER='(0,0,0,0,0,0,0,0,0,0,0,0,0,0,0,0,0,BD77,0,0,0,0,0,0,0,0,0,0,0,0)';
      PINUSE='POWER';
      NO_LOAD_CHECK='Both';
      NO_IO_CHECK='Both';
      NO_ASSERT_CHECK='TRUE';
      NO_DIR_CHECK='TRUE';
      ALLOW_CONNECT='TRUE';
    'VCCIN'<219>:
      PIN_NUMBER='(0,0,0,0,0,0,0,0,0,0,0,0,0,0,0,0,0,BD79,0,0,0,0,0,0,0,0,0,0,0,0)';
      PINUSE='POWER';
      NO_LOAD_CHECK='Both';
      NO_IO_CHECK='Both';
      NO_ASSERT_CHECK='TRUE';
      NO_DIR_CHECK='TRUE';
      ALLOW_CONNECT='TRUE';
    'VCCIN'<218>:
      PIN_NUMBER='(0,0,0,0,0,0,0,0,0,0,0,0,0,0,0,0,0,BD81,0,0,0,0,0,0,0,0,0,0,0,0)';
      PINUSE='POWER';
      NO_LOAD_CHECK='Both';
      NO_IO_CHECK='Both';
      NO_ASSERT_CHECK='TRUE';
      NO_DIR_CHECK='TRUE';
      ALLOW_CONNECT='TRUE';
    'VCCIN'<217>:
      PIN_NUMBER='(0,0,0,0,0,0,0,0,0,0,0,0,0,0,0,0,0,BD83,0,0,0,0,0,0,0,0,0,0,0,0)';
      PINUSE='POWER';
      NO_LOAD_CHECK='Both';
      NO_IO_CHECK='Both';
      NO_ASSERT_CHECK='TRUE';
      NO_DIR_CHECK='TRUE';
      ALLOW_CONNECT='TRUE';
    'VCCIN'<216>:
      PIN_NUMBER='(0,0,0,0,0,0,0,0,0,0,0,0,0,0,0,0,0,BD85,0,0,0,0,0,0,0,0,0,0,0,0)';
      PINUSE='POWER';
      NO_LOAD_CHECK='Both';
      NO_IO_CHECK='Both';
      NO_ASSERT_CHECK='TRUE';
      NO_DIR_CHECK='TRUE';
      ALLOW_CONNECT='TRUE';
    'VCCIN'<215>:
      PIN_NUMBER='(0,0,0,0,0,0,0,0,0,0,0,0,0,0,0,0,0,BE60,0,0,0,0,0,0,0,0,0,0,0,0)';
      PINUSE='POWER';
      NO_LOAD_CHECK='Both';
      NO_IO_CHECK='Both';
      NO_ASSERT_CHECK='TRUE';
      NO_DIR_CHECK='TRUE';
      ALLOW_CONNECT='TRUE';
    'VCCIN'<214>:
      PIN_NUMBER='(0,0,0,0,0,0,0,0,0,0,0,0,0,0,0,0,0,BE62,0,0,0,0,0,0,0,0,0,0,0,0)';
      PINUSE='POWER';
      NO_LOAD_CHECK='Both';
      NO_IO_CHECK='Both';
      NO_ASSERT_CHECK='TRUE';
      NO_DIR_CHECK='TRUE';
      ALLOW_CONNECT='TRUE';
    'VCCIN'<213>:
      PIN_NUMBER='(0,0,0,0,0,0,0,0,0,0,0,0,0,0,0,0,0,BE72,0,0,0,0,0,0,0,0,0,0,0,0)';
      PINUSE='POWER';
      NO_LOAD_CHECK='Both';
      NO_IO_CHECK='Both';
      NO_ASSERT_CHECK='TRUE';
      NO_DIR_CHECK='TRUE';
      ALLOW_CONNECT='TRUE';
    'VCCIN'<212>:
      PIN_NUMBER='(0,0,0,0,0,0,0,0,0,0,0,0,0,0,0,0,0,BE74,0,0,0,0,0,0,0,0,0,0,0,0)';
      PINUSE='POWER';
      NO_LOAD_CHECK='Both';
      NO_IO_CHECK='Both';
      NO_ASSERT_CHECK='TRUE';
      NO_DIR_CHECK='TRUE';
      ALLOW_CONNECT='TRUE';
    'VCCIN'<211>:
      PIN_NUMBER='(0,0,0,0,0,0,0,0,0,0,0,0,0,0,0,0,0,BE76,0,0,0,0,0,0,0,0,0,0,0,0)';
      PINUSE='POWER';
      NO_LOAD_CHECK='Both';
      NO_IO_CHECK='Both';
      NO_ASSERT_CHECK='TRUE';
      NO_DIR_CHECK='TRUE';
      ALLOW_CONNECT='TRUE';
    'VCCIN'<210>:
      PIN_NUMBER='(0,0,0,0,0,0,0,0,0,0,0,0,0,0,0,0,0,BE78,0,0,0,0,0,0,0,0,0,0,0,0)';
      PINUSE='POWER';
      NO_LOAD_CHECK='Both';
      NO_IO_CHECK='Both';
      NO_ASSERT_CHECK='TRUE';
      NO_DIR_CHECK='TRUE';
      ALLOW_CONNECT='TRUE';
    'VCCIN'<209>:
      PIN_NUMBER='(0,0,0,0,0,0,0,0,0,0,0,0,0,0,0,0,0,BE80,0,0,0,0,0,0,0,0,0,0,0,0)';
      PINUSE='POWER';
      NO_LOAD_CHECK='Both';
      NO_IO_CHECK='Both';
      NO_ASSERT_CHECK='TRUE';
      NO_DIR_CHECK='TRUE';
      ALLOW_CONNECT='TRUE';
    'VCCIN'<208>:
      PIN_NUMBER='(0,0,0,0,0,0,0,0,0,0,0,0,0,0,0,0,0,BE82,0,0,0,0,0,0,0,0,0,0,0,0)';
      PINUSE='POWER';
      NO_LOAD_CHECK='Both';
      NO_IO_CHECK='Both';
      NO_ASSERT_CHECK='TRUE';
      NO_DIR_CHECK='TRUE';
      ALLOW_CONNECT='TRUE';
    'VCCIN'<207>:
      PIN_NUMBER='(0,0,0,0,0,0,0,0,0,0,0,0,0,0,0,0,0,BE84,0,0,0,0,0,0,0,0,0,0,0,0)';
      PINUSE='POWER';
      NO_LOAD_CHECK='Both';
      NO_IO_CHECK='Both';
      NO_ASSERT_CHECK='TRUE';
      NO_DIR_CHECK='TRUE';
      ALLOW_CONNECT='TRUE';
    'VCCIN'<206>:
      PIN_NUMBER='(0,0,0,0,0,0,0,0,0,0,0,0,0,0,0,0,0,BF61,0,0,0,0,0,0,0,0,0,0,0,0)';
      PINUSE='POWER';
      NO_LOAD_CHECK='Both';
      NO_IO_CHECK='Both';
      NO_ASSERT_CHECK='TRUE';
      NO_DIR_CHECK='TRUE';
      ALLOW_CONNECT='TRUE';
    'VCCIN'<205>:
      PIN_NUMBER='(0,0,0,0,0,0,0,0,0,0,0,0,0,0,0,0,0,BF73,0,0,0,0,0,0,0,0,0,0,0,0)';
      PINUSE='POWER';
      NO_LOAD_CHECK='Both';
      NO_IO_CHECK='Both';
      NO_ASSERT_CHECK='TRUE';
      NO_DIR_CHECK='TRUE';
      ALLOW_CONNECT='TRUE';
    'VCCIN'<204>:
      PIN_NUMBER='(0,0,0,0,0,0,0,0,0,0,0,0,0,0,0,0,0,BF75,0,0,0,0,0,0,0,0,0,0,0,0)';
      PINUSE='POWER';
      NO_LOAD_CHECK='Both';
      NO_IO_CHECK='Both';
      NO_ASSERT_CHECK='TRUE';
      NO_DIR_CHECK='TRUE';
      ALLOW_CONNECT='TRUE';
    'VCCIN'<203>:
      PIN_NUMBER='(0,0,0,0,0,0,0,0,0,0,0,0,0,0,0,0,0,BF77,0,0,0,0,0,0,0,0,0,0,0,0)';
      PINUSE='POWER';
      NO_LOAD_CHECK='Both';
      NO_IO_CHECK='Both';
      NO_ASSERT_CHECK='TRUE';
      NO_DIR_CHECK='TRUE';
      ALLOW_CONNECT='TRUE';
    'VCCIN'<202>:
      PIN_NUMBER='(0,0,0,0,0,0,0,0,0,0,0,0,0,0,0,0,0,BF79,0,0,0,0,0,0,0,0,0,0,0,0)';
      PINUSE='POWER';
      NO_LOAD_CHECK='Both';
      NO_IO_CHECK='Both';
      NO_ASSERT_CHECK='TRUE';
      NO_DIR_CHECK='TRUE';
      ALLOW_CONNECT='TRUE';
    'VCCIN'<201>:
      PIN_NUMBER='(0,0,0,0,0,0,0,0,0,0,0,0,0,0,0,0,0,BF81,0,0,0,0,0,0,0,0,0,0,0,0)';
      PINUSE='POWER';
      NO_LOAD_CHECK='Both';
      NO_IO_CHECK='Both';
      NO_ASSERT_CHECK='TRUE';
      NO_DIR_CHECK='TRUE';
      ALLOW_CONNECT='TRUE';
    'VCCIN'<200>:
      PIN_NUMBER='(0,0,0,0,0,0,0,0,0,0,0,0,0,0,0,0,0,BF83,0,0,0,0,0,0,0,0,0,0,0,0)';
      PINUSE='POWER';
      NO_LOAD_CHECK='Both';
      NO_IO_CHECK='Both';
      NO_ASSERT_CHECK='TRUE';
      NO_DIR_CHECK='TRUE';
      ALLOW_CONNECT='TRUE';
    'VCCIN'<199>:
      PIN_NUMBER='(0,0,0,0,0,0,0,0,0,0,0,0,0,0,0,0,0,BF85,0,0,0,0,0,0,0,0,0,0,0,0)';
      PINUSE='POWER';
      NO_LOAD_CHECK='Both';
      NO_IO_CHECK='Both';
      NO_ASSERT_CHECK='TRUE';
      NO_DIR_CHECK='TRUE';
      ALLOW_CONNECT='TRUE';
    'VCCIN'<198>:
      PIN_NUMBER='(0,0,0,0,0,0,0,0,0,0,0,0,0,0,0,0,0,BG60,0,0,0,0,0,0,0,0,0,0,0,0)';
      PINUSE='POWER';
      NO_LOAD_CHECK='Both';
      NO_IO_CHECK='Both';
      NO_ASSERT_CHECK='TRUE';
      NO_DIR_CHECK='TRUE';
      ALLOW_CONNECT='TRUE';
    'VCCIN'<197>:
      PIN_NUMBER='(0,0,0,0,0,0,0,0,0,0,0,0,0,0,0,0,0,BG62,0,0,0,0,0,0,0,0,0,0,0,0)';
      PINUSE='POWER';
      NO_LOAD_CHECK='Both';
      NO_IO_CHECK='Both';
      NO_ASSERT_CHECK='TRUE';
      NO_DIR_CHECK='TRUE';
      ALLOW_CONNECT='TRUE';
    'VCCIN'<196>:
      PIN_NUMBER='(0,0,0,0,0,0,0,0,0,0,0,0,0,0,0,0,0,BG64,0,0,0,0,0,0,0,0,0,0,0,0)';
      PINUSE='POWER';
      NO_LOAD_CHECK='Both';
      NO_IO_CHECK='Both';
      NO_ASSERT_CHECK='TRUE';
      NO_DIR_CHECK='TRUE';
      ALLOW_CONNECT='TRUE';
    'VCCIN'<195>:
      PIN_NUMBER='(0,0,0,0,0,0,0,0,0,0,0,0,0,0,0,0,0,BG66,0,0,0,0,0,0,0,0,0,0,0,0)';
      PINUSE='POWER';
      NO_LOAD_CHECK='Both';
      NO_IO_CHECK='Both';
      NO_ASSERT_CHECK='TRUE';
      NO_DIR_CHECK='TRUE';
      ALLOW_CONNECT='TRUE';
    'VCCIN'<194>:
      PIN_NUMBER='(0,0,0,0,0,0,0,0,0,0,0,0,0,0,0,0,0,BG68,0,0,0,0,0,0,0,0,0,0,0,0)';
      PINUSE='POWER';
      NO_LOAD_CHECK='Both';
      NO_IO_CHECK='Both';
      NO_ASSERT_CHECK='TRUE';
      NO_DIR_CHECK='TRUE';
      ALLOW_CONNECT='TRUE';
    'VCCIN'<193>:
      PIN_NUMBER='(0,0,0,0,0,0,0,0,0,0,0,0,0,0,0,0,0,BG70,0,0,0,0,0,0,0,0,0,0,0,0)';
      PINUSE='POWER';
      NO_LOAD_CHECK='Both';
      NO_IO_CHECK='Both';
      NO_ASSERT_CHECK='TRUE';
      NO_DIR_CHECK='TRUE';
      ALLOW_CONNECT='TRUE';
    'VCCIN'<192>:
      PIN_NUMBER='(0,0,0,0,0,0,0,0,0,0,0,0,0,0,0,0,0,BG84,0,0,0,0,0,0,0,0,0,0,0,0)';
      PINUSE='POWER';
      NO_LOAD_CHECK='Both';
      NO_IO_CHECK='Both';
      NO_ASSERT_CHECK='TRUE';
      NO_DIR_CHECK='TRUE';
      ALLOW_CONNECT='TRUE';
    'VCCIN'<191>:
      PIN_NUMBER='(0,0,0,0,0,0,0,0,0,0,0,0,0,0,0,0,0,BH61,0,0,0,0,0,0,0,0,0,0,0,0)';
      PINUSE='POWER';
      NO_LOAD_CHECK='Both';
      NO_IO_CHECK='Both';
      NO_ASSERT_CHECK='TRUE';
      NO_DIR_CHECK='TRUE';
      ALLOW_CONNECT='TRUE';
    'VCCIN'<190>:
      PIN_NUMBER='(0,0,0,0,0,0,0,0,0,0,0,0,0,0,0,0,0,BH63,0,0,0,0,0,0,0,0,0,0,0,0)';
      PINUSE='POWER';
      NO_LOAD_CHECK='Both';
      NO_IO_CHECK='Both';
      NO_ASSERT_CHECK='TRUE';
      NO_DIR_CHECK='TRUE';
      ALLOW_CONNECT='TRUE';
    'VCCIN'<189>:
      PIN_NUMBER='(0,0,0,0,0,0,0,0,0,0,0,0,0,0,0,0,0,BH65,0,0,0,0,0,0,0,0,0,0,0,0)';
      PINUSE='POWER';
      NO_LOAD_CHECK='Both';
      NO_IO_CHECK='Both';
      NO_ASSERT_CHECK='TRUE';
      NO_DIR_CHECK='TRUE';
      ALLOW_CONNECT='TRUE';
    'VCCIN'<188>:
      PIN_NUMBER='(0,0,0,0,0,0,0,0,0,0,0,0,0,0,0,0,0,BH67,0,0,0,0,0,0,0,0,0,0,0,0)';
      PINUSE='POWER';
      NO_LOAD_CHECK='Both';
      NO_IO_CHECK='Both';
      NO_ASSERT_CHECK='TRUE';
      NO_DIR_CHECK='TRUE';
      ALLOW_CONNECT='TRUE';
    'VCCIN'<187>:
      PIN_NUMBER='(0,0,0,0,0,0,0,0,0,0,0,0,0,0,0,0,0,BH69,0,0,0,0,0,0,0,0,0,0,0,0)';
      PINUSE='POWER';
      NO_LOAD_CHECK='Both';
      NO_IO_CHECK='Both';
      NO_ASSERT_CHECK='TRUE';
      NO_DIR_CHECK='TRUE';
      ALLOW_CONNECT='TRUE';
    'VCCIN'<186>:
      PIN_NUMBER='(0,0,0,0,0,0,0,0,0,0,0,0,0,0,0,0,0,BH71,0,0,0,0,0,0,0,0,0,0,0,0)';
      PINUSE='POWER';
      NO_LOAD_CHECK='Both';
      NO_IO_CHECK='Both';
      NO_ASSERT_CHECK='TRUE';
      NO_DIR_CHECK='TRUE';
      ALLOW_CONNECT='TRUE';
    'VCCIN'<185>:
      PIN_NUMBER='(0,0,0,0,0,0,0,0,0,0,0,0,0,0,0,0,0,BH73,0,0,0,0,0,0,0,0,0,0,0,0)';
      PINUSE='POWER';
      NO_LOAD_CHECK='Both';
      NO_IO_CHECK='Both';
      NO_ASSERT_CHECK='TRUE';
      NO_DIR_CHECK='TRUE';
      ALLOW_CONNECT='TRUE';
    'VCCIN'<184>:
      PIN_NUMBER='(0,0,0,0,0,0,0,0,0,0,0,0,0,0,0,0,0,BH75,0,0,0,0,0,0,0,0,0,0,0,0)';
      PINUSE='POWER';
      NO_LOAD_CHECK='Both';
      NO_IO_CHECK='Both';
      NO_ASSERT_CHECK='TRUE';
      NO_DIR_CHECK='TRUE';
      ALLOW_CONNECT='TRUE';
    'VCCIN'<183>:
      PIN_NUMBER='(0,0,0,0,0,0,0,0,0,0,0,0,0,0,0,0,0,BH77,0,0,0,0,0,0,0,0,0,0,0,0)';
      PINUSE='POWER';
      NO_LOAD_CHECK='Both';
      NO_IO_CHECK='Both';
      NO_ASSERT_CHECK='TRUE';
      NO_DIR_CHECK='TRUE';
      ALLOW_CONNECT='TRUE';
    'VCCIN'<182>:
      PIN_NUMBER='(0,0,0,0,0,0,0,0,0,0,0,0,0,0,0,0,0,BH79,0,0,0,0,0,0,0,0,0,0,0,0)';
      PINUSE='POWER';
      NO_LOAD_CHECK='Both';
      NO_IO_CHECK='Both';
      NO_ASSERT_CHECK='TRUE';
      NO_DIR_CHECK='TRUE';
      ALLOW_CONNECT='TRUE';
    'VCCIN'<181>:
      PIN_NUMBER='(0,0,0,0,0,0,0,0,0,0,0,0,0,0,0,0,0,BH81,0,0,0,0,0,0,0,0,0,0,0,0)';
      PINUSE='POWER';
      NO_LOAD_CHECK='Both';
      NO_IO_CHECK='Both';
      NO_ASSERT_CHECK='TRUE';
      NO_DIR_CHECK='TRUE';
      ALLOW_CONNECT='TRUE';
    'VCCIN'<180>:
      PIN_NUMBER='(0,0,0,0,0,0,0,0,0,0,0,0,0,0,0,0,0,BH83,0,0,0,0,0,0,0,0,0,0,0,0)';
      PINUSE='POWER';
      NO_LOAD_CHECK='Both';
      NO_IO_CHECK='Both';
      NO_ASSERT_CHECK='TRUE';
      NO_DIR_CHECK='TRUE';
      ALLOW_CONNECT='TRUE';
    'VCCIN'<179>:
      PIN_NUMBER='(0,0,0,0,0,0,0,0,0,0,0,0,0,0,0,0,0,BJ60,0,0,0,0,0,0,0,0,0,0,0,0)';
      PINUSE='POWER';
      NO_LOAD_CHECK='Both';
      NO_IO_CHECK='Both';
      NO_ASSERT_CHECK='TRUE';
      NO_DIR_CHECK='TRUE';
      ALLOW_CONNECT='TRUE';
    'VCCIN'<178>:
      PIN_NUMBER='(0,0,0,0,0,0,0,0,0,0,0,0,0,0,0,0,0,BJ62,0,0,0,0,0,0,0,0,0,0,0,0)';
      PINUSE='POWER';
      NO_LOAD_CHECK='Both';
      NO_IO_CHECK='Both';
      NO_ASSERT_CHECK='TRUE';
      NO_DIR_CHECK='TRUE';
      ALLOW_CONNECT='TRUE';
    'VCCIN'<177>:
      PIN_NUMBER='(0,0,0,0,0,0,0,0,0,0,0,0,0,0,0,0,0,BJ64,0,0,0,0,0,0,0,0,0,0,0,0)';
      PINUSE='POWER';
      NO_LOAD_CHECK='Both';
      NO_IO_CHECK='Both';
      NO_ASSERT_CHECK='TRUE';
      NO_DIR_CHECK='TRUE';
      ALLOW_CONNECT='TRUE';
    'VCCIN'<176>:
      PIN_NUMBER='(0,0,0,0,0,0,0,0,0,0,0,0,0,0,0,0,0,BJ66,0,0,0,0,0,0,0,0,0,0,0,0)';
      PINUSE='POWER';
      NO_LOAD_CHECK='Both';
      NO_IO_CHECK='Both';
      NO_ASSERT_CHECK='TRUE';
      NO_DIR_CHECK='TRUE';
      ALLOW_CONNECT='TRUE';
    'VCCIN'<175>:
      PIN_NUMBER='(0,0,0,0,0,0,0,0,0,0,0,0,0,0,0,0,0,BJ68,0,0,0,0,0,0,0,0,0,0,0,0)';
      PINUSE='POWER';
      NO_LOAD_CHECK='Both';
      NO_IO_CHECK='Both';
      NO_ASSERT_CHECK='TRUE';
      NO_DIR_CHECK='TRUE';
      ALLOW_CONNECT='TRUE';
    'VCCIN'<174>:
      PIN_NUMBER='(0,0,0,0,0,0,0,0,0,0,0,0,0,0,0,0,0,BJ70,0,0,0,0,0,0,0,0,0,0,0,0)';
      PINUSE='POWER';
      NO_LOAD_CHECK='Both';
      NO_IO_CHECK='Both';
      NO_ASSERT_CHECK='TRUE';
      NO_DIR_CHECK='TRUE';
      ALLOW_CONNECT='TRUE';
    'VCCIN'<173>:
      PIN_NUMBER='(0,0,0,0,0,0,0,0,0,0,0,0,0,0,0,0,0,BJ72,0,0,0,0,0,0,0,0,0,0,0,0)';
      PINUSE='POWER';
      NO_LOAD_CHECK='Both';
      NO_IO_CHECK='Both';
      NO_ASSERT_CHECK='TRUE';
      NO_DIR_CHECK='TRUE';
      ALLOW_CONNECT='TRUE';
    'VCCIN'<172>:
      PIN_NUMBER='(0,0,0,0,0,0,0,0,0,0,0,0,0,0,0,0,0,BJ74,0,0,0,0,0,0,0,0,0,0,0,0)';
      PINUSE='POWER';
      NO_LOAD_CHECK='Both';
      NO_IO_CHECK='Both';
      NO_ASSERT_CHECK='TRUE';
      NO_DIR_CHECK='TRUE';
      ALLOW_CONNECT='TRUE';
    'VCCIN'<171>:
      PIN_NUMBER='(0,0,0,0,0,0,0,0,0,0,0,0,0,0,0,0,0,BJ76,0,0,0,0,0,0,0,0,0,0,0,0)';
      PINUSE='POWER';
      NO_LOAD_CHECK='Both';
      NO_IO_CHECK='Both';
      NO_ASSERT_CHECK='TRUE';
      NO_DIR_CHECK='TRUE';
      ALLOW_CONNECT='TRUE';
    'VCCIN'<170>:
      PIN_NUMBER='(0,0,0,0,0,0,0,0,0,0,0,0,0,0,0,0,0,BJ78,0,0,0,0,0,0,0,0,0,0,0,0)';
      PINUSE='POWER';
      NO_LOAD_CHECK='Both';
      NO_IO_CHECK='Both';
      NO_ASSERT_CHECK='TRUE';
      NO_DIR_CHECK='TRUE';
      ALLOW_CONNECT='TRUE';
    'VCCIN'<169>:
      PIN_NUMBER='(0,0,0,0,0,0,0,0,0,0,0,0,0,0,0,0,0,BJ80,0,0,0,0,0,0,0,0,0,0,0,0)';
      PINUSE='POWER';
      NO_LOAD_CHECK='Both';
      NO_IO_CHECK='Both';
      NO_ASSERT_CHECK='TRUE';
      NO_DIR_CHECK='TRUE';
      ALLOW_CONNECT='TRUE';
    'VCCIN'<168>:
      PIN_NUMBER='(0,0,0,0,0,0,0,0,0,0,0,0,0,0,0,0,0,BJ82,0,0,0,0,0,0,0,0,0,0,0,0)';
      PINUSE='POWER';
      NO_LOAD_CHECK='Both';
      NO_IO_CHECK='Both';
      NO_ASSERT_CHECK='TRUE';
      NO_DIR_CHECK='TRUE';
      ALLOW_CONNECT='TRUE';
    'VCCIN'<167>:
      PIN_NUMBER='(0,0,0,0,0,0,0,0,0,0,0,0,0,0,0,0,0,BJ84,0,0,0,0,0,0,0,0,0,0,0,0)';
      PINUSE='POWER';
      NO_LOAD_CHECK='Both';
      NO_IO_CHECK='Both';
      NO_ASSERT_CHECK='TRUE';
      NO_DIR_CHECK='TRUE';
      ALLOW_CONNECT='TRUE';
    'VCCIN'<166>:
      PIN_NUMBER='(0,0,0,0,0,0,0,0,0,0,0,0,0,0,0,0,0,BK61,0,0,0,0,0,0,0,0,0,0,0,0)';
      PINUSE='POWER';
      NO_LOAD_CHECK='Both';
      NO_IO_CHECK='Both';
      NO_ASSERT_CHECK='TRUE';
      NO_DIR_CHECK='TRUE';
      ALLOW_CONNECT='TRUE';
    'VCCIN'<165>:
      PIN_NUMBER='(0,0,0,0,0,0,0,0,0,0,0,0,0,0,0,0,0,BK63,0,0,0,0,0,0,0,0,0,0,0,0)';
      PINUSE='POWER';
      NO_LOAD_CHECK='Both';
      NO_IO_CHECK='Both';
      NO_ASSERT_CHECK='TRUE';
      NO_DIR_CHECK='TRUE';
      ALLOW_CONNECT='TRUE';
    'VCCIN'<164>:
      PIN_NUMBER='(0,0,0,0,0,0,0,0,0,0,0,0,0,0,0,0,0,BK65,0,0,0,0,0,0,0,0,0,0,0,0)';
      PINUSE='POWER';
      NO_LOAD_CHECK='Both';
      NO_IO_CHECK='Both';
      NO_ASSERT_CHECK='TRUE';
      NO_DIR_CHECK='TRUE';
      ALLOW_CONNECT='TRUE';
    'VCCIN'<163>:
      PIN_NUMBER='(0,0,0,0,0,0,0,0,0,0,0,0,0,0,0,0,0,BK67,0,0,0,0,0,0,0,0,0,0,0,0)';
      PINUSE='POWER';
      NO_LOAD_CHECK='Both';
      NO_IO_CHECK='Both';
      NO_ASSERT_CHECK='TRUE';
      NO_DIR_CHECK='TRUE';
      ALLOW_CONNECT='TRUE';
    'VCCIN'<162>:
      PIN_NUMBER='(0,0,0,0,0,0,0,0,0,0,0,0,0,0,0,0,0,BK69,0,0,0,0,0,0,0,0,0,0,0,0)';
      PINUSE='POWER';
      NO_LOAD_CHECK='Both';
      NO_IO_CHECK='Both';
      NO_ASSERT_CHECK='TRUE';
      NO_DIR_CHECK='TRUE';
      ALLOW_CONNECT='TRUE';
    'VCCIN'<161>:
      PIN_NUMBER='(0,0,0,0,0,0,0,0,0,0,0,0,0,0,0,0,0,BK71,0,0,0,0,0,0,0,0,0,0,0,0)';
      PINUSE='POWER';
      NO_LOAD_CHECK='Both';
      NO_IO_CHECK='Both';
      NO_ASSERT_CHECK='TRUE';
      NO_DIR_CHECK='TRUE';
      ALLOW_CONNECT='TRUE';
    'VCCIN'<160>:
      PIN_NUMBER='(0,0,0,0,0,0,0,0,0,0,0,0,0,0,0,0,0,BK73,0,0,0,0,0,0,0,0,0,0,0,0)';
      PINUSE='POWER';
      NO_LOAD_CHECK='Both';
      NO_IO_CHECK='Both';
      NO_ASSERT_CHECK='TRUE';
      NO_DIR_CHECK='TRUE';
      ALLOW_CONNECT='TRUE';
    'VCCIN'<159>:
      PIN_NUMBER='(0,0,0,0,0,0,0,0,0,0,0,0,0,0,0,0,0,BK75,0,0,0,0,0,0,0,0,0,0,0,0)';
      PINUSE='POWER';
      NO_LOAD_CHECK='Both';
      NO_IO_CHECK='Both';
      NO_ASSERT_CHECK='TRUE';
      NO_DIR_CHECK='TRUE';
      ALLOW_CONNECT='TRUE';
    'VCCIN'<158>:
      PIN_NUMBER='(0,0,0,0,0,0,0,0,0,0,0,0,0,0,0,0,0,BK77,0,0,0,0,0,0,0,0,0,0,0,0)';
      PINUSE='POWER';
      NO_LOAD_CHECK='Both';
      NO_IO_CHECK='Both';
      NO_ASSERT_CHECK='TRUE';
      NO_DIR_CHECK='TRUE';
      ALLOW_CONNECT='TRUE';
    'VCCIN'<157>:
      PIN_NUMBER='(0,0,0,0,0,0,0,0,0,0,0,0,0,0,0,0,0,BK79,0,0,0,0,0,0,0,0,0,0,0,0)';
      PINUSE='POWER';
      NO_LOAD_CHECK='Both';
      NO_IO_CHECK='Both';
      NO_ASSERT_CHECK='TRUE';
      NO_DIR_CHECK='TRUE';
      ALLOW_CONNECT='TRUE';
    'VCCIN'<156>:
      PIN_NUMBER='(0,0,0,0,0,0,0,0,0,0,0,0,0,0,0,0,0,BK81,0,0,0,0,0,0,0,0,0,0,0,0)';
      PINUSE='POWER';
      NO_LOAD_CHECK='Both';
      NO_IO_CHECK='Both';
      NO_ASSERT_CHECK='TRUE';
      NO_DIR_CHECK='TRUE';
      ALLOW_CONNECT='TRUE';
    'VCCIN'<155>:
      PIN_NUMBER='(0,0,0,0,0,0,0,0,0,0,0,0,0,0,0,0,0,BK83,0,0,0,0,0,0,0,0,0,0,0,0)';
      PINUSE='POWER';
      NO_LOAD_CHECK='Both';
      NO_IO_CHECK='Both';
      NO_ASSERT_CHECK='TRUE';
      NO_DIR_CHECK='TRUE';
      ALLOW_CONNECT='TRUE';
    'VCCIN'<154>:
      PIN_NUMBER='(0,0,0,0,0,0,0,0,0,0,0,0,0,0,0,0,0,BL60,0,0,0,0,0,0,0,0,0,0,0,0)';
      PINUSE='POWER';
      NO_LOAD_CHECK='Both';
      NO_IO_CHECK='Both';
      NO_ASSERT_CHECK='TRUE';
      NO_DIR_CHECK='TRUE';
      ALLOW_CONNECT='TRUE';
    'VCCIN'<153>:
      PIN_NUMBER='(0,0,0,0,0,0,0,0,0,0,0,0,0,0,0,0,0,BL62,0,0,0,0,0,0,0,0,0,0,0,0)';
      PINUSE='POWER';
      NO_LOAD_CHECK='Both';
      NO_IO_CHECK='Both';
      NO_ASSERT_CHECK='TRUE';
      NO_DIR_CHECK='TRUE';
      ALLOW_CONNECT='TRUE';
    'VCCIN'<152>:
      PIN_NUMBER='(0,0,0,0,0,0,0,0,0,0,0,0,0,0,0,0,0,BL84,0,0,0,0,0,0,0,0,0,0,0,0)';
      PINUSE='POWER';
      NO_LOAD_CHECK='Both';
      NO_IO_CHECK='Both';
      NO_ASSERT_CHECK='TRUE';
      NO_DIR_CHECK='TRUE';
      ALLOW_CONNECT='TRUE';
    'VCCIN'<151>:
      PIN_NUMBER='(0,0,0,0,0,0,0,0,0,0,0,0,0,0,0,0,0,BM61,0,0,0,0,0,0,0,0,0,0,0,0)';
      PINUSE='POWER';
      NO_LOAD_CHECK='Both';
      NO_IO_CHECK='Both';
      NO_ASSERT_CHECK='TRUE';
      NO_DIR_CHECK='TRUE';
      ALLOW_CONNECT='TRUE';
    'VCCIN'<150>:
      PIN_NUMBER='(0,0,0,0,0,0,0,0,0,0,0,0,0,0,0,0,0,BM63,0,0,0,0,0,0,0,0,0,0,0,0)';
      PINUSE='POWER';
      NO_LOAD_CHECK='Both';
      NO_IO_CHECK='Both';
      NO_ASSERT_CHECK='TRUE';
      NO_DIR_CHECK='TRUE';
      ALLOW_CONNECT='TRUE';
    'VCCIN'<149>:
      PIN_NUMBER='(0,0,0,0,0,0,0,0,0,0,0,0,0,0,0,0,0,BM65,0,0,0,0,0,0,0,0,0,0,0,0)';
      PINUSE='POWER';
      NO_LOAD_CHECK='Both';
      NO_IO_CHECK='Both';
      NO_ASSERT_CHECK='TRUE';
      NO_DIR_CHECK='TRUE';
      ALLOW_CONNECT='TRUE';
    'VCCIN'<148>:
      PIN_NUMBER='(0,0,0,0,0,0,0,0,0,0,0,0,0,0,0,0,0,BM67,0,0,0,0,0,0,0,0,0,0,0,0)';
      PINUSE='POWER';
      NO_LOAD_CHECK='Both';
      NO_IO_CHECK='Both';
      NO_ASSERT_CHECK='TRUE';
      NO_DIR_CHECK='TRUE';
      ALLOW_CONNECT='TRUE';
    'VCCIN'<147>:
      PIN_NUMBER='(0,0,0,0,0,0,0,0,0,0,0,0,0,0,0,0,0,BM69,0,0,0,0,0,0,0,0,0,0,0,0)';
      PINUSE='POWER';
      NO_LOAD_CHECK='Both';
      NO_IO_CHECK='Both';
      NO_ASSERT_CHECK='TRUE';
      NO_DIR_CHECK='TRUE';
      ALLOW_CONNECT='TRUE';
    'VCCIN'<146>:
      PIN_NUMBER='(0,0,0,0,0,0,0,0,0,0,0,0,0,0,0,0,0,BM71,0,0,0,0,0,0,0,0,0,0,0,0)';
      PINUSE='POWER';
      NO_LOAD_CHECK='Both';
      NO_IO_CHECK='Both';
      NO_ASSERT_CHECK='TRUE';
      NO_DIR_CHECK='TRUE';
      ALLOW_CONNECT='TRUE';
    'VCCIN'<145>:
      PIN_NUMBER='(0,0,0,0,0,0,0,0,0,0,0,0,0,0,0,0,0,BM73,0,0,0,0,0,0,0,0,0,0,0,0)';
      PINUSE='POWER';
      NO_LOAD_CHECK='Both';
      NO_IO_CHECK='Both';
      NO_ASSERT_CHECK='TRUE';
      NO_DIR_CHECK='TRUE';
      ALLOW_CONNECT='TRUE';
    'VCCIN'<144>:
      PIN_NUMBER='(0,0,0,0,0,0,0,0,0,0,0,0,0,0,0,0,0,BM75,0,0,0,0,0,0,0,0,0,0,0,0)';
      PINUSE='POWER';
      NO_LOAD_CHECK='Both';
      NO_IO_CHECK='Both';
      NO_ASSERT_CHECK='TRUE';
      NO_DIR_CHECK='TRUE';
      ALLOW_CONNECT='TRUE';
    'VCCIN'<143>:
      PIN_NUMBER='(0,0,0,0,0,0,0,0,0,0,0,0,0,0,0,0,0,BM77,0,0,0,0,0,0,0,0,0,0,0,0)';
      PINUSE='POWER';
      NO_LOAD_CHECK='Both';
      NO_IO_CHECK='Both';
      NO_ASSERT_CHECK='TRUE';
      NO_DIR_CHECK='TRUE';
      ALLOW_CONNECT='TRUE';
    'VCCIN'<142>:
      PIN_NUMBER='(0,0,0,0,0,0,0,0,0,0,0,0,0,0,0,0,0,BM79,0,0,0,0,0,0,0,0,0,0,0,0)';
      PINUSE='POWER';
      NO_LOAD_CHECK='Both';
      NO_IO_CHECK='Both';
      NO_ASSERT_CHECK='TRUE';
      NO_DIR_CHECK='TRUE';
      ALLOW_CONNECT='TRUE';
    'VCCIN'<141>:
      PIN_NUMBER='(0,0,0,0,0,0,0,0,0,0,0,0,0,0,0,0,0,BM81,0,0,0,0,0,0,0,0,0,0,0,0)';
      PINUSE='POWER';
      NO_LOAD_CHECK='Both';
      NO_IO_CHECK='Both';
      NO_ASSERT_CHECK='TRUE';
      NO_DIR_CHECK='TRUE';
      ALLOW_CONNECT='TRUE';
    'VCCIN'<140>:
      PIN_NUMBER='(0,0,0,0,0,0,0,0,0,0,0,0,0,0,0,0,0,BM83,0,0,0,0,0,0,0,0,0,0,0,0)';
      PINUSE='POWER';
      NO_LOAD_CHECK='Both';
      NO_IO_CHECK='Both';
      NO_ASSERT_CHECK='TRUE';
      NO_DIR_CHECK='TRUE';
      ALLOW_CONNECT='TRUE';
    'VCCIN'<139>:
      PIN_NUMBER='(0,0,0,0,0,0,0,0,0,0,0,0,0,0,0,0,0,BN60,0,0,0,0,0,0,0,0,0,0,0,0)';
      PINUSE='POWER';
      NO_LOAD_CHECK='Both';
      NO_IO_CHECK='Both';
      NO_ASSERT_CHECK='TRUE';
      NO_DIR_CHECK='TRUE';
      ALLOW_CONNECT='TRUE';
    'VCCIN'<138>:
      PIN_NUMBER='(0,0,0,0,0,0,0,0,0,0,0,0,0,0,0,0,0,BN62,0,0,0,0,0,0,0,0,0,0,0,0)';
      PINUSE='POWER';
      NO_LOAD_CHECK='Both';
      NO_IO_CHECK='Both';
      NO_ASSERT_CHECK='TRUE';
      NO_DIR_CHECK='TRUE';
      ALLOW_CONNECT='TRUE';
    'VCCIN'<137>:
      PIN_NUMBER='(0,0,0,0,0,0,0,0,0,0,0,0,0,0,0,0,0,BN64,0,0,0,0,0,0,0,0,0,0,0,0)';
      PINUSE='POWER';
      NO_LOAD_CHECK='Both';
      NO_IO_CHECK='Both';
      NO_ASSERT_CHECK='TRUE';
      NO_DIR_CHECK='TRUE';
      ALLOW_CONNECT='TRUE';
    'VCCIN'<136>:
      PIN_NUMBER='(0,0,0,0,0,0,0,0,0,0,0,0,0,0,0,0,0,BN66,0,0,0,0,0,0,0,0,0,0,0,0)';
      PINUSE='POWER';
      NO_LOAD_CHECK='Both';
      NO_IO_CHECK='Both';
      NO_ASSERT_CHECK='TRUE';
      NO_DIR_CHECK='TRUE';
      ALLOW_CONNECT='TRUE';
    'VCCIN'<135>:
      PIN_NUMBER='(0,0,0,0,0,0,0,0,0,0,0,0,0,0,0,0,0,BN68,0,0,0,0,0,0,0,0,0,0,0,0)';
      PINUSE='POWER';
      NO_LOAD_CHECK='Both';
      NO_IO_CHECK='Both';
      NO_ASSERT_CHECK='TRUE';
      NO_DIR_CHECK='TRUE';
      ALLOW_CONNECT='TRUE';
    'VCCIN'<134>:
      PIN_NUMBER='(0,0,0,0,0,0,0,0,0,0,0,0,0,0,0,0,0,BN70,0,0,0,0,0,0,0,0,0,0,0,0)';
      PINUSE='POWER';
      NO_LOAD_CHECK='Both';
      NO_IO_CHECK='Both';
      NO_ASSERT_CHECK='TRUE';
      NO_DIR_CHECK='TRUE';
      ALLOW_CONNECT='TRUE';
    'VCCIN'<133>:
      PIN_NUMBER='(0,0,0,0,0,0,0,0,0,0,0,0,0,0,0,0,0,BN72,0,0,0,0,0,0,0,0,0,0,0,0)';
      PINUSE='POWER';
      NO_LOAD_CHECK='Both';
      NO_IO_CHECK='Both';
      NO_ASSERT_CHECK='TRUE';
      NO_DIR_CHECK='TRUE';
      ALLOW_CONNECT='TRUE';
    'VCCIN'<132>:
      PIN_NUMBER='(0,0,0,0,0,0,0,0,0,0,0,0,0,0,0,0,0,BN74,0,0,0,0,0,0,0,0,0,0,0,0)';
      PINUSE='POWER';
      NO_LOAD_CHECK='Both';
      NO_IO_CHECK='Both';
      NO_ASSERT_CHECK='TRUE';
      NO_DIR_CHECK='TRUE';
      ALLOW_CONNECT='TRUE';
    'VCCIN'<131>:
      PIN_NUMBER='(0,0,0,0,0,0,0,0,0,0,0,0,0,0,0,0,0,BN76,0,0,0,0,0,0,0,0,0,0,0,0)';
      PINUSE='POWER';
      NO_LOAD_CHECK='Both';
      NO_IO_CHECK='Both';
      NO_ASSERT_CHECK='TRUE';
      NO_DIR_CHECK='TRUE';
      ALLOW_CONNECT='TRUE';
    'VCCIN'<130>:
      PIN_NUMBER='(0,0,0,0,0,0,0,0,0,0,0,0,0,0,0,0,0,BN78,0,0,0,0,0,0,0,0,0,0,0,0)';
      PINUSE='POWER';
      NO_LOAD_CHECK='Both';
      NO_IO_CHECK='Both';
      NO_ASSERT_CHECK='TRUE';
      NO_DIR_CHECK='TRUE';
      ALLOW_CONNECT='TRUE';
    'VCCIN'<129>:
      PIN_NUMBER='(0,0,0,0,0,0,0,0,0,0,0,0,0,0,0,0,0,0,BN80,0,0,0,0,0,0,0,0,0,0,0)';
      PINUSE='POWER';
      NO_LOAD_CHECK='Both';
      NO_IO_CHECK='Both';
      NO_ASSERT_CHECK='TRUE';
      NO_DIR_CHECK='TRUE';
      ALLOW_CONNECT='TRUE';
    'VCCIN'<128>:
      PIN_NUMBER='(0,0,0,0,0,0,0,0,0,0,0,0,0,0,0,0,0,0,BN82,0,0,0,0,0,0,0,0,0,0,0)';
      PINUSE='POWER';
      NO_LOAD_CHECK='Both';
      NO_IO_CHECK='Both';
      NO_ASSERT_CHECK='TRUE';
      NO_DIR_CHECK='TRUE';
      ALLOW_CONNECT='TRUE';
    'VCCIN'<127>:
      PIN_NUMBER='(0,0,0,0,0,0,0,0,0,0,0,0,0,0,0,0,0,0,BN84,0,0,0,0,0,0,0,0,0,0,0)';
      PINUSE='POWER';
      NO_LOAD_CHECK='Both';
      NO_IO_CHECK='Both';
      NO_ASSERT_CHECK='TRUE';
      NO_DIR_CHECK='TRUE';
      ALLOW_CONNECT='TRUE';
    'VCCIN'<126>:
      PIN_NUMBER='(0,0,0,0,0,0,0,0,0,0,0,0,0,0,0,0,0,0,BP61,0,0,0,0,0,0,0,0,0,0,0)';
      PINUSE='POWER';
      NO_LOAD_CHECK='Both';
      NO_IO_CHECK='Both';
      NO_ASSERT_CHECK='TRUE';
      NO_DIR_CHECK='TRUE';
      ALLOW_CONNECT='TRUE';
    'VCCIN'<125>:
      PIN_NUMBER='(0,0,0,0,0,0,0,0,0,0,0,0,0,0,0,0,0,0,BP63,0,0,0,0,0,0,0,0,0,0,0)';
      PINUSE='POWER';
      NO_LOAD_CHECK='Both';
      NO_IO_CHECK='Both';
      NO_ASSERT_CHECK='TRUE';
      NO_DIR_CHECK='TRUE';
      ALLOW_CONNECT='TRUE';
    'VCCIN'<124>:
      PIN_NUMBER='(0,0,0,0,0,0,0,0,0,0,0,0,0,0,0,0,0,0,BP65,0,0,0,0,0,0,0,0,0,0,0)';
      PINUSE='POWER';
      NO_LOAD_CHECK='Both';
      NO_IO_CHECK='Both';
      NO_ASSERT_CHECK='TRUE';
      NO_DIR_CHECK='TRUE';
      ALLOW_CONNECT='TRUE';
    'VCCIN'<123>:
      PIN_NUMBER='(0,0,0,0,0,0,0,0,0,0,0,0,0,0,0,0,0,0,BP67,0,0,0,0,0,0,0,0,0,0,0)';
      PINUSE='POWER';
      NO_LOAD_CHECK='Both';
      NO_IO_CHECK='Both';
      NO_ASSERT_CHECK='TRUE';
      NO_DIR_CHECK='TRUE';
      ALLOW_CONNECT='TRUE';
    'VCCIN'<122>:
      PIN_NUMBER='(0,0,0,0,0,0,0,0,0,0,0,0,0,0,0,0,0,0,BP69,0,0,0,0,0,0,0,0,0,0,0)';
      PINUSE='POWER';
      NO_LOAD_CHECK='Both';
      NO_IO_CHECK='Both';
      NO_ASSERT_CHECK='TRUE';
      NO_DIR_CHECK='TRUE';
      ALLOW_CONNECT='TRUE';
    'VCCIN'<121>:
      PIN_NUMBER='(0,0,0,0,0,0,0,0,0,0,0,0,0,0,0,0,0,0,BP71,0,0,0,0,0,0,0,0,0,0,0)';
      PINUSE='POWER';
      NO_LOAD_CHECK='Both';
      NO_IO_CHECK='Both';
      NO_ASSERT_CHECK='TRUE';
      NO_DIR_CHECK='TRUE';
      ALLOW_CONNECT='TRUE';
    'VCCIN'<120>:
      PIN_NUMBER='(0,0,0,0,0,0,0,0,0,0,0,0,0,0,0,0,0,0,BP73,0,0,0,0,0,0,0,0,0,0,0)';
      PINUSE='POWER';
      NO_LOAD_CHECK='Both';
      NO_IO_CHECK='Both';
      NO_ASSERT_CHECK='TRUE';
      NO_DIR_CHECK='TRUE';
      ALLOW_CONNECT='TRUE';
    'VCCIN'<119>:
      PIN_NUMBER='(0,0,0,0,0,0,0,0,0,0,0,0,0,0,0,0,0,0,BP75,0,0,0,0,0,0,0,0,0,0,0)';
      PINUSE='POWER';
      NO_LOAD_CHECK='Both';
      NO_IO_CHECK='Both';
      NO_ASSERT_CHECK='TRUE';
      NO_DIR_CHECK='TRUE';
      ALLOW_CONNECT='TRUE';
    'VCCIN'<118>:
      PIN_NUMBER='(0,0,0,0,0,0,0,0,0,0,0,0,0,0,0,0,0,0,BP77,0,0,0,0,0,0,0,0,0,0,0)';
      PINUSE='POWER';
      NO_LOAD_CHECK='Both';
      NO_IO_CHECK='Both';
      NO_ASSERT_CHECK='TRUE';
      NO_DIR_CHECK='TRUE';
      ALLOW_CONNECT='TRUE';
    'VCCIN'<117>:
      PIN_NUMBER='(0,0,0,0,0,0,0,0,0,0,0,0,0,0,0,0,0,0,BP79,0,0,0,0,0,0,0,0,0,0,0)';
      PINUSE='POWER';
      NO_LOAD_CHECK='Both';
      NO_IO_CHECK='Both';
      NO_ASSERT_CHECK='TRUE';
      NO_DIR_CHECK='TRUE';
      ALLOW_CONNECT='TRUE';
    'VCCIN'<116>:
      PIN_NUMBER='(0,0,0,0,0,0,0,0,0,0,0,0,0,0,0,0,0,0,BP81,0,0,0,0,0,0,0,0,0,0,0)';
      PINUSE='POWER';
      NO_LOAD_CHECK='Both';
      NO_IO_CHECK='Both';
      NO_ASSERT_CHECK='TRUE';
      NO_DIR_CHECK='TRUE';
      ALLOW_CONNECT='TRUE';
    'VCCIN'<115>:
      PIN_NUMBER='(0,0,0,0,0,0,0,0,0,0,0,0,0,0,0,0,0,0,BP83,0,0,0,0,0,0,0,0,0,0,0)';
      PINUSE='POWER';
      NO_LOAD_CHECK='Both';
      NO_IO_CHECK='Both';
      NO_ASSERT_CHECK='TRUE';
      NO_DIR_CHECK='TRUE';
      ALLOW_CONNECT='TRUE';
    'VCCIN'<114>:
      PIN_NUMBER='(0,0,0,0,0,0,0,0,0,0,0,0,0,0,0,0,0,0,BR60,0,0,0,0,0,0,0,0,0,0,0)';
      PINUSE='POWER';
      NO_LOAD_CHECK='Both';
      NO_IO_CHECK='Both';
      NO_ASSERT_CHECK='TRUE';
      NO_DIR_CHECK='TRUE';
      ALLOW_CONNECT='TRUE';
    'VCCIN'<113>:
      PIN_NUMBER='(0,0,0,0,0,0,0,0,0,0,0,0,0,0,0,0,0,0,BR62,0,0,0,0,0,0,0,0,0,0,0)';
      PINUSE='POWER';
      NO_LOAD_CHECK='Both';
      NO_IO_CHECK='Both';
      NO_ASSERT_CHECK='TRUE';
      NO_DIR_CHECK='TRUE';
      ALLOW_CONNECT='TRUE';
    'VCCIN'<112>:
      PIN_NUMBER='(0,0,0,0,0,0,0,0,0,0,0,0,0,0,0,0,0,0,BR84,0,0,0,0,0,0,0,0,0,0,0)';
      PINUSE='POWER';
      NO_LOAD_CHECK='Both';
      NO_IO_CHECK='Both';
      NO_ASSERT_CHECK='TRUE';
      NO_DIR_CHECK='TRUE';
      ALLOW_CONNECT='TRUE';
    'VCCIN'<111>:
      PIN_NUMBER='(0,0,0,0,0,0,0,0,0,0,0,0,0,0,0,0,0,0,BT61,0,0,0,0,0,0,0,0,0,0,0)';
      PINUSE='POWER';
      NO_LOAD_CHECK='Both';
      NO_IO_CHECK='Both';
      NO_ASSERT_CHECK='TRUE';
      NO_DIR_CHECK='TRUE';
      ALLOW_CONNECT='TRUE';
    'VCCIN'<110>:
      PIN_NUMBER='(0,0,0,0,0,0,0,0,0,0,0,0,0,0,0,0,0,0,BT63,0,0,0,0,0,0,0,0,0,0,0)';
      PINUSE='POWER';
      NO_LOAD_CHECK='Both';
      NO_IO_CHECK='Both';
      NO_ASSERT_CHECK='TRUE';
      NO_DIR_CHECK='TRUE';
      ALLOW_CONNECT='TRUE';
    'VCCIN'<109>:
      PIN_NUMBER='(0,0,0,0,0,0,0,0,0,0,0,0,0,0,0,0,0,0,BT65,0,0,0,0,0,0,0,0,0,0,0)';
      PINUSE='POWER';
      NO_LOAD_CHECK='Both';
      NO_IO_CHECK='Both';
      NO_ASSERT_CHECK='TRUE';
      NO_DIR_CHECK='TRUE';
      ALLOW_CONNECT='TRUE';
    'VCCIN'<108>:
      PIN_NUMBER='(0,0,0,0,0,0,0,0,0,0,0,0,0,0,0,0,0,0,BT67,0,0,0,0,0,0,0,0,0,0,0)';
      PINUSE='POWER';
      NO_LOAD_CHECK='Both';
      NO_IO_CHECK='Both';
      NO_ASSERT_CHECK='TRUE';
      NO_DIR_CHECK='TRUE';
      ALLOW_CONNECT='TRUE';
    'VCCIN'<107>:
      PIN_NUMBER='(0,0,0,0,0,0,0,0,0,0,0,0,0,0,0,0,0,0,BT69,0,0,0,0,0,0,0,0,0,0,0)';
      PINUSE='POWER';
      NO_LOAD_CHECK='Both';
      NO_IO_CHECK='Both';
      NO_ASSERT_CHECK='TRUE';
      NO_DIR_CHECK='TRUE';
      ALLOW_CONNECT='TRUE';
    'VCCIN'<106>:
      PIN_NUMBER='(0,0,0,0,0,0,0,0,0,0,0,0,0,0,0,0,0,0,BT71,0,0,0,0,0,0,0,0,0,0,0)';
      PINUSE='POWER';
      NO_LOAD_CHECK='Both';
      NO_IO_CHECK='Both';
      NO_ASSERT_CHECK='TRUE';
      NO_DIR_CHECK='TRUE';
      ALLOW_CONNECT='TRUE';
    'VCCIN'<105>:
      PIN_NUMBER='(0,0,0,0,0,0,0,0,0,0,0,0,0,0,0,0,0,0,BT73,0,0,0,0,0,0,0,0,0,0,0)';
      PINUSE='POWER';
      NO_LOAD_CHECK='Both';
      NO_IO_CHECK='Both';
      NO_ASSERT_CHECK='TRUE';
      NO_DIR_CHECK='TRUE';
      ALLOW_CONNECT='TRUE';
    'VCCIN'<104>:
      PIN_NUMBER='(0,0,0,0,0,0,0,0,0,0,0,0,0,0,0,0,0,0,BT75,0,0,0,0,0,0,0,0,0,0,0)';
      PINUSE='POWER';
      NO_LOAD_CHECK='Both';
      NO_IO_CHECK='Both';
      NO_ASSERT_CHECK='TRUE';
      NO_DIR_CHECK='TRUE';
      ALLOW_CONNECT='TRUE';
    'VCCIN'<103>:
      PIN_NUMBER='(0,0,0,0,0,0,0,0,0,0,0,0,0,0,0,0,0,0,BT77,0,0,0,0,0,0,0,0,0,0,0)';
      PINUSE='POWER';
      NO_LOAD_CHECK='Both';
      NO_IO_CHECK='Both';
      NO_ASSERT_CHECK='TRUE';
      NO_DIR_CHECK='TRUE';
      ALLOW_CONNECT='TRUE';
    'VCCIN'<102>:
      PIN_NUMBER='(0,0,0,0,0,0,0,0,0,0,0,0,0,0,0,0,0,0,BT79,0,0,0,0,0,0,0,0,0,0,0)';
      PINUSE='POWER';
      NO_LOAD_CHECK='Both';
      NO_IO_CHECK='Both';
      NO_ASSERT_CHECK='TRUE';
      NO_DIR_CHECK='TRUE';
      ALLOW_CONNECT='TRUE';
    'VCCIN'<101>:
      PIN_NUMBER='(0,0,0,0,0,0,0,0,0,0,0,0,0,0,0,0,0,0,BT81,0,0,0,0,0,0,0,0,0,0,0)';
      PINUSE='POWER';
      NO_LOAD_CHECK='Both';
      NO_IO_CHECK='Both';
      NO_ASSERT_CHECK='TRUE';
      NO_DIR_CHECK='TRUE';
      ALLOW_CONNECT='TRUE';
    'VCCIN'<100>:
      PIN_NUMBER='(0,0,0,0,0,0,0,0,0,0,0,0,0,0,0,0,0,0,BT83,0,0,0,0,0,0,0,0,0,0,0)';
      PINUSE='POWER';
      NO_LOAD_CHECK='Both';
      NO_IO_CHECK='Both';
      NO_ASSERT_CHECK='TRUE';
      NO_DIR_CHECK='TRUE';
      ALLOW_CONNECT='TRUE';
    'VCCIN'<99>:
      PIN_NUMBER='(0,0,0,0,0,0,0,0,0,0,0,0,0,0,0,0,0,0,BU60,0,0,0,0,0,0,0,0,0,0,0)';
      PINUSE='POWER';
      NO_LOAD_CHECK='Both';
      NO_IO_CHECK='Both';
      NO_ASSERT_CHECK='TRUE';
      NO_DIR_CHECK='TRUE';
      ALLOW_CONNECT='TRUE';
    'VCCIN'<98>:
      PIN_NUMBER='(0,0,0,0,0,0,0,0,0,0,0,0,0,0,0,0,0,0,BU62,0,0,0,0,0,0,0,0,0,0,0)';
      PINUSE='POWER';
      NO_LOAD_CHECK='Both';
      NO_IO_CHECK='Both';
      NO_ASSERT_CHECK='TRUE';
      NO_DIR_CHECK='TRUE';
      ALLOW_CONNECT='TRUE';
    'VCCIN'<97>:
      PIN_NUMBER='(0,0,0,0,0,0,0,0,0,0,0,0,0,0,0,0,0,0,BU64,0,0,0,0,0,0,0,0,0,0,0)';
      PINUSE='POWER';
      NO_LOAD_CHECK='Both';
      NO_IO_CHECK='Both';
      NO_ASSERT_CHECK='TRUE';
      NO_DIR_CHECK='TRUE';
      ALLOW_CONNECT='TRUE';
    'VCCIN'<96>:
      PIN_NUMBER='(0,0,0,0,0,0,0,0,0,0,0,0,0,0,0,0,0,0,BU66,0,0,0,0,0,0,0,0,0,0,0)';
      PINUSE='POWER';
      NO_LOAD_CHECK='Both';
      NO_IO_CHECK='Both';
      NO_ASSERT_CHECK='TRUE';
      NO_DIR_CHECK='TRUE';
      ALLOW_CONNECT='TRUE';
    'VCCIN'<95>:
      PIN_NUMBER='(0,0,0,0,0,0,0,0,0,0,0,0,0,0,0,0,0,0,BU68,0,0,0,0,0,0,0,0,0,0,0)';
      PINUSE='POWER';
      NO_LOAD_CHECK='Both';
      NO_IO_CHECK='Both';
      NO_ASSERT_CHECK='TRUE';
      NO_DIR_CHECK='TRUE';
      ALLOW_CONNECT='TRUE';
    'VCCIN'<94>:
      PIN_NUMBER='(0,0,0,0,0,0,0,0,0,0,0,0,0,0,0,0,0,0,BU70,0,0,0,0,0,0,0,0,0,0,0)';
      PINUSE='POWER';
      NO_LOAD_CHECK='Both';
      NO_IO_CHECK='Both';
      NO_ASSERT_CHECK='TRUE';
      NO_DIR_CHECK='TRUE';
      ALLOW_CONNECT='TRUE';
    'VCCIN'<93>:
      PIN_NUMBER='(0,0,0,0,0,0,0,0,0,0,0,0,0,0,0,0,0,0,BU72,0,0,0,0,0,0,0,0,0,0,0)';
      PINUSE='POWER';
      NO_LOAD_CHECK='Both';
      NO_IO_CHECK='Both';
      NO_ASSERT_CHECK='TRUE';
      NO_DIR_CHECK='TRUE';
      ALLOW_CONNECT='TRUE';
    'VCCIN'<92>:
      PIN_NUMBER='(0,0,0,0,0,0,0,0,0,0,0,0,0,0,0,0,0,0,BU74,0,0,0,0,0,0,0,0,0,0,0)';
      PINUSE='POWER';
      NO_LOAD_CHECK='Both';
      NO_IO_CHECK='Both';
      NO_ASSERT_CHECK='TRUE';
      NO_DIR_CHECK='TRUE';
      ALLOW_CONNECT='TRUE';
    'VCCIN'<91>:
      PIN_NUMBER='(0,0,0,0,0,0,0,0,0,0,0,0,0,0,0,0,0,0,BU76,0,0,0,0,0,0,0,0,0,0,0)';
      PINUSE='POWER';
      NO_LOAD_CHECK='Both';
      NO_IO_CHECK='Both';
      NO_ASSERT_CHECK='TRUE';
      NO_DIR_CHECK='TRUE';
      ALLOW_CONNECT='TRUE';
    'VCCIN'<90>:
      PIN_NUMBER='(0,0,0,0,0,0,0,0,0,0,0,0,0,0,0,0,0,0,BU78,0,0,0,0,0,0,0,0,0,0,0)';
      PINUSE='POWER';
      NO_LOAD_CHECK='Both';
      NO_IO_CHECK='Both';
      NO_ASSERT_CHECK='TRUE';
      NO_DIR_CHECK='TRUE';
      ALLOW_CONNECT='TRUE';
    'VCCIN'<89>:
      PIN_NUMBER='(0,0,0,0,0,0,0,0,0,0,0,0,0,0,0,0,0,0,BU80,0,0,0,0,0,0,0,0,0,0,0)';
      PINUSE='POWER';
      NO_LOAD_CHECK='Both';
      NO_IO_CHECK='Both';
      NO_ASSERT_CHECK='TRUE';
      NO_DIR_CHECK='TRUE';
      ALLOW_CONNECT='TRUE';
    'VCCIN'<88>:
      PIN_NUMBER='(0,0,0,0,0,0,0,0,0,0,0,0,0,0,0,0,0,0,BU82,0,0,0,0,0,0,0,0,0,0,0)';
      PINUSE='POWER';
      NO_LOAD_CHECK='Both';
      NO_IO_CHECK='Both';
      NO_ASSERT_CHECK='TRUE';
      NO_DIR_CHECK='TRUE';
      ALLOW_CONNECT='TRUE';
    'VCCIN'<87>:
      PIN_NUMBER='(0,0,0,0,0,0,0,0,0,0,0,0,0,0,0,0,0,0,BU84,0,0,0,0,0,0,0,0,0,0,0)';
      PINUSE='POWER';
      NO_LOAD_CHECK='Both';
      NO_IO_CHECK='Both';
      NO_ASSERT_CHECK='TRUE';
      NO_DIR_CHECK='TRUE';
      ALLOW_CONNECT='TRUE';
    'VCCIN'<86>:
      PIN_NUMBER='(0,0,0,0,0,0,0,0,0,0,0,0,0,0,0,0,0,0,BV61,0,0,0,0,0,0,0,0,0,0,0)';
      PINUSE='POWER';
      NO_LOAD_CHECK='Both';
      NO_IO_CHECK='Both';
      NO_ASSERT_CHECK='TRUE';
      NO_DIR_CHECK='TRUE';
      ALLOW_CONNECT='TRUE';
    'VCCIN'<85>:
      PIN_NUMBER='(0,0,0,0,0,0,0,0,0,0,0,0,0,0,0,0,0,0,BV63,0,0,0,0,0,0,0,0,0,0,0)';
      PINUSE='POWER';
      NO_LOAD_CHECK='Both';
      NO_IO_CHECK='Both';
      NO_ASSERT_CHECK='TRUE';
      NO_DIR_CHECK='TRUE';
      ALLOW_CONNECT='TRUE';
    'VCCIN'<84>:
      PIN_NUMBER='(0,0,0,0,0,0,0,0,0,0,0,0,0,0,0,0,0,0,BV65,0,0,0,0,0,0,0,0,0,0,0)';
      PINUSE='POWER';
      NO_LOAD_CHECK='Both';
      NO_IO_CHECK='Both';
      NO_ASSERT_CHECK='TRUE';
      NO_DIR_CHECK='TRUE';
      ALLOW_CONNECT='TRUE';
    'VCCIN'<83>:
      PIN_NUMBER='(0,0,0,0,0,0,0,0,0,0,0,0,0,0,0,0,0,0,BV67,0,0,0,0,0,0,0,0,0,0,0)';
      PINUSE='POWER';
      NO_LOAD_CHECK='Both';
      NO_IO_CHECK='Both';
      NO_ASSERT_CHECK='TRUE';
      NO_DIR_CHECK='TRUE';
      ALLOW_CONNECT='TRUE';
    'VCCIN'<82>:
      PIN_NUMBER='(0,0,0,0,0,0,0,0,0,0,0,0,0,0,0,0,0,0,BV69,0,0,0,0,0,0,0,0,0,0,0)';
      PINUSE='POWER';
      NO_LOAD_CHECK='Both';
      NO_IO_CHECK='Both';
      NO_ASSERT_CHECK='TRUE';
      NO_DIR_CHECK='TRUE';
      ALLOW_CONNECT='TRUE';
    'VCCIN'<81>:
      PIN_NUMBER='(0,0,0,0,0,0,0,0,0,0,0,0,0,0,0,0,0,0,BV71,0,0,0,0,0,0,0,0,0,0,0)';
      PINUSE='POWER';
      NO_LOAD_CHECK='Both';
      NO_IO_CHECK='Both';
      NO_ASSERT_CHECK='TRUE';
      NO_DIR_CHECK='TRUE';
      ALLOW_CONNECT='TRUE';
    'VCCIN'<80>:
      PIN_NUMBER='(0,0,0,0,0,0,0,0,0,0,0,0,0,0,0,0,0,0,BV73,0,0,0,0,0,0,0,0,0,0,0)';
      PINUSE='POWER';
      NO_LOAD_CHECK='Both';
      NO_IO_CHECK='Both';
      NO_ASSERT_CHECK='TRUE';
      NO_DIR_CHECK='TRUE';
      ALLOW_CONNECT='TRUE';
    'VCCIN'<79>:
      PIN_NUMBER='(0,0,0,0,0,0,0,0,0,0,0,0,0,0,0,0,0,0,BV75,0,0,0,0,0,0,0,0,0,0,0)';
      PINUSE='POWER';
      NO_LOAD_CHECK='Both';
      NO_IO_CHECK='Both';
      NO_ASSERT_CHECK='TRUE';
      NO_DIR_CHECK='TRUE';
      ALLOW_CONNECT='TRUE';
    'VCCIN'<78>:
      PIN_NUMBER='(0,0,0,0,0,0,0,0,0,0,0,0,0,0,0,0,0,0,BV77,0,0,0,0,0,0,0,0,0,0,0)';
      PINUSE='POWER';
      NO_LOAD_CHECK='Both';
      NO_IO_CHECK='Both';
      NO_ASSERT_CHECK='TRUE';
      NO_DIR_CHECK='TRUE';
      ALLOW_CONNECT='TRUE';
    'VCCIN'<77>:
      PIN_NUMBER='(0,0,0,0,0,0,0,0,0,0,0,0,0,0,0,0,0,0,BV79,0,0,0,0,0,0,0,0,0,0,0)';
      PINUSE='POWER';
      NO_LOAD_CHECK='Both';
      NO_IO_CHECK='Both';
      NO_ASSERT_CHECK='TRUE';
      NO_DIR_CHECK='TRUE';
      ALLOW_CONNECT='TRUE';
    'VCCIN'<76>:
      PIN_NUMBER='(0,0,0,0,0,0,0,0,0,0,0,0,0,0,0,0,0,0,BV81,0,0,0,0,0,0,0,0,0,0,0)';
      PINUSE='POWER';
      NO_LOAD_CHECK='Both';
      NO_IO_CHECK='Both';
      NO_ASSERT_CHECK='TRUE';
      NO_DIR_CHECK='TRUE';
      ALLOW_CONNECT='TRUE';
    'VCCIN'<75>:
      PIN_NUMBER='(0,0,0,0,0,0,0,0,0,0,0,0,0,0,0,0,0,0,BV83,0,0,0,0,0,0,0,0,0,0,0)';
      PINUSE='POWER';
      NO_LOAD_CHECK='Both';
      NO_IO_CHECK='Both';
      NO_ASSERT_CHECK='TRUE';
      NO_DIR_CHECK='TRUE';
      ALLOW_CONNECT='TRUE';
    'VCCIN'<74>:
      PIN_NUMBER='(0,0,0,0,0,0,0,0,0,0,0,0,0,0,0,0,0,0,BW60,0,0,0,0,0,0,0,0,0,0,0)';
      PINUSE='POWER';
      NO_LOAD_CHECK='Both';
      NO_IO_CHECK='Both';
      NO_ASSERT_CHECK='TRUE';
      NO_DIR_CHECK='TRUE';
      ALLOW_CONNECT='TRUE';
    'VCCIN'<73>:
      PIN_NUMBER='(0,0,0,0,0,0,0,0,0,0,0,0,0,0,0,0,0,0,BW62,0,0,0,0,0,0,0,0,0,0,0)';
      PINUSE='POWER';
      NO_LOAD_CHECK='Both';
      NO_IO_CHECK='Both';
      NO_ASSERT_CHECK='TRUE';
      NO_DIR_CHECK='TRUE';
      ALLOW_CONNECT='TRUE';
    'VCCIN'<72>:
      PIN_NUMBER='(0,0,0,0,0,0,0,0,0,0,0,0,0,0,0,0,0,0,BW64,0,0,0,0,0,0,0,0,0,0,0)';
      PINUSE='POWER';
      NO_LOAD_CHECK='Both';
      NO_IO_CHECK='Both';
      NO_ASSERT_CHECK='TRUE';
      NO_DIR_CHECK='TRUE';
      ALLOW_CONNECT='TRUE';
    'VCCIN'<71>:
      PIN_NUMBER='(0,0,0,0,0,0,0,0,0,0,0,0,0,0,0,0,0,0,BW66,0,0,0,0,0,0,0,0,0,0,0)';
      PINUSE='POWER';
      NO_LOAD_CHECK='Both';
      NO_IO_CHECK='Both';
      NO_ASSERT_CHECK='TRUE';
      NO_DIR_CHECK='TRUE';
      ALLOW_CONNECT='TRUE';
    'VCCIN'<70>:
      PIN_NUMBER='(0,0,0,0,0,0,0,0,0,0,0,0,0,0,0,0,0,0,BW68,0,0,0,0,0,0,0,0,0,0,0)';
      PINUSE='POWER';
      NO_LOAD_CHECK='Both';
      NO_IO_CHECK='Both';
      NO_ASSERT_CHECK='TRUE';
      NO_DIR_CHECK='TRUE';
      ALLOW_CONNECT='TRUE';
    'VCCIN'<69>:
      PIN_NUMBER='(0,0,0,0,0,0,0,0,0,0,0,0,0,0,0,0,0,0,BW70,0,0,0,0,0,0,0,0,0,0,0)';
      PINUSE='POWER';
      NO_LOAD_CHECK='Both';
      NO_IO_CHECK='Both';
      NO_ASSERT_CHECK='TRUE';
      NO_DIR_CHECK='TRUE';
      ALLOW_CONNECT='TRUE';
    'VCCIN'<68>:
      PIN_NUMBER='(0,0,0,0,0,0,0,0,0,0,0,0,0,0,0,0,0,0,BW84,0,0,0,0,0,0,0,0,0,0,0)';
      PINUSE='POWER';
      NO_LOAD_CHECK='Both';
      NO_IO_CHECK='Both';
      NO_ASSERT_CHECK='TRUE';
      NO_DIR_CHECK='TRUE';
      ALLOW_CONNECT='TRUE';
    'VCCIN'<67>:
      PIN_NUMBER='(0,0,0,0,0,0,0,0,0,0,0,0,0,0,0,0,0,0,BY61,0,0,0,0,0,0,0,0,0,0,0)';
      PINUSE='POWER';
      NO_LOAD_CHECK='Both';
      NO_IO_CHECK='Both';
      NO_ASSERT_CHECK='TRUE';
      NO_DIR_CHECK='TRUE';
      ALLOW_CONNECT='TRUE';
    'VCCIN'<66>:
      PIN_NUMBER='(0,0,0,0,0,0,0,0,0,0,0,0,0,0,0,0,0,0,BY73,0,0,0,0,0,0,0,0,0,0,0)';
      PINUSE='POWER';
      NO_LOAD_CHECK='Both';
      NO_IO_CHECK='Both';
      NO_ASSERT_CHECK='TRUE';
      NO_DIR_CHECK='TRUE';
      ALLOW_CONNECT='TRUE';
    'VCCIN'<65>:
      PIN_NUMBER='(0,0,0,0,0,0,0,0,0,0,0,0,0,0,0,0,0,0,BY75,0,0,0,0,0,0,0,0,0,0,0)';
      PINUSE='POWER';
      NO_LOAD_CHECK='Both';
      NO_IO_CHECK='Both';
      NO_ASSERT_CHECK='TRUE';
      NO_DIR_CHECK='TRUE';
      ALLOW_CONNECT='TRUE';
    'VCCIN'<64>:
      PIN_NUMBER='(0,0,0,0,0,0,0,0,0,0,0,0,0,0,0,0,0,0,BY77,0,0,0,0,0,0,0,0,0,0,0)';
      PINUSE='POWER';
      NO_LOAD_CHECK='Both';
      NO_IO_CHECK='Both';
      NO_ASSERT_CHECK='TRUE';
      NO_DIR_CHECK='TRUE';
      ALLOW_CONNECT='TRUE';
    'VCCIN'<63>:
      PIN_NUMBER='(0,0,0,0,0,0,0,0,0,0,0,0,0,0,0,0,0,0,BY79,0,0,0,0,0,0,0,0,0,0,0)';
      PINUSE='POWER';
      NO_LOAD_CHECK='Both';
      NO_IO_CHECK='Both';
      NO_ASSERT_CHECK='TRUE';
      NO_DIR_CHECK='TRUE';
      ALLOW_CONNECT='TRUE';
    'VCCIN'<62>:
      PIN_NUMBER='(0,0,0,0,0,0,0,0,0,0,0,0,0,0,0,0,0,0,BY81,0,0,0,0,0,0,0,0,0,0,0)';
      PINUSE='POWER';
      NO_LOAD_CHECK='Both';
      NO_IO_CHECK='Both';
      NO_ASSERT_CHECK='TRUE';
      NO_DIR_CHECK='TRUE';
      ALLOW_CONNECT='TRUE';
    'VCCIN'<61>:
      PIN_NUMBER='(0,0,0,0,0,0,0,0,0,0,0,0,0,0,0,0,0,0,BY83,0,0,0,0,0,0,0,0,0,0,0)';
      PINUSE='POWER';
      NO_LOAD_CHECK='Both';
      NO_IO_CHECK='Both';
      NO_ASSERT_CHECK='TRUE';
      NO_DIR_CHECK='TRUE';
      ALLOW_CONNECT='TRUE';
    'VCCIN'<60>:
      PIN_NUMBER='(0,0,0,0,0,0,0,0,0,0,0,0,0,0,0,0,0,0,CA60,0,0,0,0,0,0,0,0,0,0,0)';
      PINUSE='POWER';
      NO_LOAD_CHECK='Both';
      NO_IO_CHECK='Both';
      NO_ASSERT_CHECK='TRUE';
      NO_DIR_CHECK='TRUE';
      ALLOW_CONNECT='TRUE';
    'VCCIN'<59>:
      PIN_NUMBER='(0,0,0,0,0,0,0,0,0,0,0,0,0,0,0,0,0,0,CA62,0,0,0,0,0,0,0,0,0,0,0)';
      PINUSE='POWER';
      NO_LOAD_CHECK='Both';
      NO_IO_CHECK='Both';
      NO_ASSERT_CHECK='TRUE';
      NO_DIR_CHECK='TRUE';
      ALLOW_CONNECT='TRUE';
    'VCCIN'<58>:
      PIN_NUMBER='(0,0,0,0,0,0,0,0,0,0,0,0,0,0,0,0,0,0,CA72,0,0,0,0,0,0,0,0,0,0,0)';
      PINUSE='POWER';
      NO_LOAD_CHECK='Both';
      NO_IO_CHECK='Both';
      NO_ASSERT_CHECK='TRUE';
      NO_DIR_CHECK='TRUE';
      ALLOW_CONNECT='TRUE';
    'VCCIN'<57>:
      PIN_NUMBER='(0,0,0,0,0,0,0,0,0,0,0,0,0,0,0,0,0,0,CA74,0,0,0,0,0,0,0,0,0,0,0)';
      PINUSE='POWER';
      NO_LOAD_CHECK='Both';
      NO_IO_CHECK='Both';
      NO_ASSERT_CHECK='TRUE';
      NO_DIR_CHECK='TRUE';
      ALLOW_CONNECT='TRUE';
    'VCCIN'<56>:
      PIN_NUMBER='(0,0,0,0,0,0,0,0,0,0,0,0,0,0,0,0,0,0,CA76,0,0,0,0,0,0,0,0,0,0,0)';
      PINUSE='POWER';
      NO_LOAD_CHECK='Both';
      NO_IO_CHECK='Both';
      NO_ASSERT_CHECK='TRUE';
      NO_DIR_CHECK='TRUE';
      ALLOW_CONNECT='TRUE';
    'VCCIN'<55>:
      PIN_NUMBER='(0,0,0,0,0,0,0,0,0,0,0,0,0,0,0,0,0,0,CA78,0,0,0,0,0,0,0,0,0,0,0)';
      PINUSE='POWER';
      NO_LOAD_CHECK='Both';
      NO_IO_CHECK='Both';
      NO_ASSERT_CHECK='TRUE';
      NO_DIR_CHECK='TRUE';
      ALLOW_CONNECT='TRUE';
    'VCCIN'<54>:
      PIN_NUMBER='(0,0,0,0,0,0,0,0,0,0,0,0,0,0,0,0,0,0,CA80,0,0,0,0,0,0,0,0,0,0,0)';
      PINUSE='POWER';
      NO_LOAD_CHECK='Both';
      NO_IO_CHECK='Both';
      NO_ASSERT_CHECK='TRUE';
      NO_DIR_CHECK='TRUE';
      ALLOW_CONNECT='TRUE';
    'VCCIN'<53>:
      PIN_NUMBER='(0,0,0,0,0,0,0,0,0,0,0,0,0,0,0,0,0,0,CA82,0,0,0,0,0,0,0,0,0,0,0)';
      PINUSE='POWER';
      NO_LOAD_CHECK='Both';
      NO_IO_CHECK='Both';
      NO_ASSERT_CHECK='TRUE';
      NO_DIR_CHECK='TRUE';
      ALLOW_CONNECT='TRUE';
    'VCCIN'<52>:
      PIN_NUMBER='(0,0,0,0,0,0,0,0,0,0,0,0,0,0,0,0,0,0,CA84,0,0,0,0,0,0,0,0,0,0,0)';
      PINUSE='POWER';
      NO_LOAD_CHECK='Both';
      NO_IO_CHECK='Both';
      NO_ASSERT_CHECK='TRUE';
      NO_DIR_CHECK='TRUE';
      ALLOW_CONNECT='TRUE';
    'VCCIN'<51>:
      PIN_NUMBER='(0,0,0,0,0,0,0,0,0,0,0,0,0,0,0,0,0,0,CB61,0,0,0,0,0,0,0,0,0,0,0)';
      PINUSE='POWER';
      NO_LOAD_CHECK='Both';
      NO_IO_CHECK='Both';
      NO_ASSERT_CHECK='TRUE';
      NO_DIR_CHECK='TRUE';
      ALLOW_CONNECT='TRUE';
    'VCCIN'<50>:
      PIN_NUMBER='(0,0,0,0,0,0,0,0,0,0,0,0,0,0,0,0,0,0,CB73,0,0,0,0,0,0,0,0,0,0,0)';
      PINUSE='POWER';
      NO_LOAD_CHECK='Both';
      NO_IO_CHECK='Both';
      NO_ASSERT_CHECK='TRUE';
      NO_DIR_CHECK='TRUE';
      ALLOW_CONNECT='TRUE';
    'VCCIN'<49>:
      PIN_NUMBER='(0,0,0,0,0,0,0,0,0,0,0,0,0,0,0,0,0,0,CB75,0,0,0,0,0,0,0,0,0,0,0)';
      PINUSE='POWER';
      NO_LOAD_CHECK='Both';
      NO_IO_CHECK='Both';
      NO_ASSERT_CHECK='TRUE';
      NO_DIR_CHECK='TRUE';
      ALLOW_CONNECT='TRUE';
    'VCCIN'<48>:
      PIN_NUMBER='(0,0,0,0,0,0,0,0,0,0,0,0,0,0,0,0,0,0,CB77,0,0,0,0,0,0,0,0,0,0,0)';
      PINUSE='POWER';
      NO_LOAD_CHECK='Both';
      NO_IO_CHECK='Both';
      NO_ASSERT_CHECK='TRUE';
      NO_DIR_CHECK='TRUE';
      ALLOW_CONNECT='TRUE';
    'VCCIN'<47>:
      PIN_NUMBER='(0,0,0,0,0,0,0,0,0,0,0,0,0,0,0,0,0,0,CB79,0,0,0,0,0,0,0,0,0,0,0)';
      PINUSE='POWER';
      NO_LOAD_CHECK='Both';
      NO_IO_CHECK='Both';
      NO_ASSERT_CHECK='TRUE';
      NO_DIR_CHECK='TRUE';
      ALLOW_CONNECT='TRUE';
    'VCCIN'<46>:
      PIN_NUMBER='(0,0,0,0,0,0,0,0,0,0,0,0,0,0,0,0,0,0,CB81,0,0,0,0,0,0,0,0,0,0,0)';
      PINUSE='POWER';
      NO_LOAD_CHECK='Both';
      NO_IO_CHECK='Both';
      NO_ASSERT_CHECK='TRUE';
      NO_DIR_CHECK='TRUE';
      ALLOW_CONNECT='TRUE';
    'VCCIN'<45>:
      PIN_NUMBER='(0,0,0,0,0,0,0,0,0,0,0,0,0,0,0,0,0,0,CB83,0,0,0,0,0,0,0,0,0,0,0)';
      PINUSE='POWER';
      NO_LOAD_CHECK='Both';
      NO_IO_CHECK='Both';
      NO_ASSERT_CHECK='TRUE';
      NO_DIR_CHECK='TRUE';
      ALLOW_CONNECT='TRUE';
    'VCCIN'<44>:
      PIN_NUMBER='(0,0,0,0,0,0,0,0,0,0,0,0,0,0,0,0,0,0,CC60,0,0,0,0,0,0,0,0,0,0,0)';
      PINUSE='POWER';
      NO_LOAD_CHECK='Both';
      NO_IO_CHECK='Both';
      NO_ASSERT_CHECK='TRUE';
      NO_DIR_CHECK='TRUE';
      ALLOW_CONNECT='TRUE';
    'VCCIN'<43>:
      PIN_NUMBER='(0,0,0,0,0,0,0,0,0,0,0,0,0,0,0,0,0,0,CC62,0,0,0,0,0,0,0,0,0,0,0)';
      PINUSE='POWER';
      NO_LOAD_CHECK='Both';
      NO_IO_CHECK='Both';
      NO_ASSERT_CHECK='TRUE';
      NO_DIR_CHECK='TRUE';
      ALLOW_CONNECT='TRUE';
    'VCCIN'<42>:
      PIN_NUMBER='(0,0,0,0,0,0,0,0,0,0,0,0,0,0,0,0,0,0,CC84,0,0,0,0,0,0,0,0,0,0,0)';
      PINUSE='POWER';
      NO_LOAD_CHECK='Both';
      NO_IO_CHECK='Both';
      NO_ASSERT_CHECK='TRUE';
      NO_DIR_CHECK='TRUE';
      ALLOW_CONNECT='TRUE';
    'VCCIN'<41>:
      PIN_NUMBER='(0,0,0,0,0,0,0,0,0,0,0,0,0,0,0,0,0,0,CD61,0,0,0,0,0,0,0,0,0,0,0)';
      PINUSE='POWER';
      NO_LOAD_CHECK='Both';
      NO_IO_CHECK='Both';
      NO_ASSERT_CHECK='TRUE';
      NO_DIR_CHECK='TRUE';
      ALLOW_CONNECT='TRUE';
    'VCCIN'<40>:
      PIN_NUMBER='(0,0,0,0,0,0,0,0,0,0,0,0,0,0,0,0,0,0,CD83,0,0,0,0,0,0,0,0,0,0,0)';
      PINUSE='POWER';
      NO_LOAD_CHECK='Both';
      NO_IO_CHECK='Both';
      NO_ASSERT_CHECK='TRUE';
      NO_DIR_CHECK='TRUE';
      ALLOW_CONNECT='TRUE';
    'VCCIN'<39>:
      PIN_NUMBER='(0,0,0,0,0,0,0,0,0,0,0,0,0,0,0,0,0,0,CD85,0,0,0,0,0,0,0,0,0,0,0)';
      PINUSE='POWER';
      NO_LOAD_CHECK='Both';
      NO_IO_CHECK='Both';
      NO_ASSERT_CHECK='TRUE';
      NO_DIR_CHECK='TRUE';
      ALLOW_CONNECT='TRUE';
    'VCCIN'<38>:
      PIN_NUMBER='(0,0,0,0,0,0,0,0,0,0,0,0,0,0,0,0,0,0,CE60,0,0,0,0,0,0,0,0,0,0,0)';
      PINUSE='POWER';
      NO_LOAD_CHECK='Both';
      NO_IO_CHECK='Both';
      NO_ASSERT_CHECK='TRUE';
      NO_DIR_CHECK='TRUE';
      ALLOW_CONNECT='TRUE';
    'VCCIN'<37>:
      PIN_NUMBER='(0,0,0,0,0,0,0,0,0,0,0,0,0,0,0,0,0,0,CE84,0,0,0,0,0,0,0,0,0,0,0)';
      PINUSE='POWER';
      NO_LOAD_CHECK='Both';
      NO_IO_CHECK='Both';
      NO_ASSERT_CHECK='TRUE';
      NO_DIR_CHECK='TRUE';
      ALLOW_CONNECT='TRUE';
    'VCCIN'<36>:
      PIN_NUMBER='(0,0,0,0,0,0,0,0,0,0,0,0,0,0,0,0,0,0,CF61,0,0,0,0,0,0,0,0,0,0,0)';
      PINUSE='POWER';
      NO_LOAD_CHECK='Both';
      NO_IO_CHECK='Both';
      NO_ASSERT_CHECK='TRUE';
      NO_DIR_CHECK='TRUE';
      ALLOW_CONNECT='TRUE';
    'VCCIN'<35>:
      PIN_NUMBER='(0,0,0,0,0,0,0,0,0,0,0,0,0,0,0,0,0,0,CF85,0,0,0,0,0,0,0,0,0,0,0)';
      PINUSE='POWER';
      NO_LOAD_CHECK='Both';
      NO_IO_CHECK='Both';
      NO_ASSERT_CHECK='TRUE';
      NO_DIR_CHECK='TRUE';
      ALLOW_CONNECT='TRUE';
    'VCCIN'<34>:
      PIN_NUMBER='(0,0,0,0,0,0,0,0,0,0,0,0,0,0,0,0,0,0,CG60,0,0,0,0,0,0,0,0,0,0,0)';
      PINUSE='POWER';
      NO_LOAD_CHECK='Both';
      NO_IO_CHECK='Both';
      NO_ASSERT_CHECK='TRUE';
      NO_DIR_CHECK='TRUE';
      ALLOW_CONNECT='TRUE';
    'VCCIN'<33>:
      PIN_NUMBER='(0,0,0,0,0,0,0,0,0,0,0,0,0,0,0,0,0,0,CG84,0,0,0,0,0,0,0,0,0,0,0)';
      PINUSE='POWER';
      NO_LOAD_CHECK='Both';
      NO_IO_CHECK='Both';
      NO_ASSERT_CHECK='TRUE';
      NO_DIR_CHECK='TRUE';
      ALLOW_CONNECT='TRUE';
    'VCCIN'<32>:
      PIN_NUMBER='(0,0,0,0,0,0,0,0,0,0,0,0,0,0,0,0,0,0,CH61,0,0,0,0,0,0,0,0,0,0,0)';
      PINUSE='POWER';
      NO_LOAD_CHECK='Both';
      NO_IO_CHECK='Both';
      NO_ASSERT_CHECK='TRUE';
      NO_DIR_CHECK='TRUE';
      ALLOW_CONNECT='TRUE';
    'VCCIN'<31>:
      PIN_NUMBER='(0,0,0,0,0,0,0,0,0,0,0,0,0,0,0,0,0,0,CH85,0,0,0,0,0,0,0,0,0,0,0)';
      PINUSE='POWER';
      NO_LOAD_CHECK='Both';
      NO_IO_CHECK='Both';
      NO_ASSERT_CHECK='TRUE';
      NO_DIR_CHECK='TRUE';
      ALLOW_CONNECT='TRUE';
    'VCCIN'<30>:
      PIN_NUMBER='(0,0,0,0,0,0,0,0,0,0,0,0,0,0,0,0,0,0,CJ60,0,0,0,0,0,0,0,0,0,0,0)';
      PINUSE='POWER';
      NO_LOAD_CHECK='Both';
      NO_IO_CHECK='Both';
      NO_ASSERT_CHECK='TRUE';
      NO_DIR_CHECK='TRUE';
      ALLOW_CONNECT='TRUE';
    'VCCIN'<29>:
      PIN_NUMBER='(0,0,0,0,0,0,0,0,0,0,0,0,0,0,0,0,0,0,CK59,0,0,0,0,0,0,0,0,0,0,0)';
      PINUSE='POWER';
      NO_LOAD_CHECK='Both';
      NO_IO_CHECK='Both';
      NO_ASSERT_CHECK='TRUE';
      NO_DIR_CHECK='TRUE';
      ALLOW_CONNECT='TRUE';
    'VCCIN'<28>:
      PIN_NUMBER='(0,0,0,0,0,0,0,0,0,0,0,0,0,0,0,0,0,0,CK61,0,0,0,0,0,0,0,0,0,0,0)';
      PINUSE='POWER';
      NO_LOAD_CHECK='Both';
      NO_IO_CHECK='Both';
      NO_ASSERT_CHECK='TRUE';
      NO_DIR_CHECK='TRUE';
      ALLOW_CONNECT='TRUE';
    'VCCIN'<27>:
      PIN_NUMBER='(0,0,0,0,0,0,0,0,0,0,0,0,0,0,0,0,0,0,CL58,0,0,0,0,0,0,0,0,0,0,0)';
      PINUSE='POWER';
      NO_LOAD_CHECK='Both';
      NO_IO_CHECK='Both';
      NO_ASSERT_CHECK='TRUE';
      NO_DIR_CHECK='TRUE';
      ALLOW_CONNECT='TRUE';
    'VCCIN'<26>:
      PIN_NUMBER='(0,0,0,0,0,0,0,0,0,0,0,0,0,0,0,0,0,0,CL60,0,0,0,0,0,0,0,0,0,0,0)';
      PINUSE='POWER';
      NO_LOAD_CHECK='Both';
      NO_IO_CHECK='Both';
      NO_ASSERT_CHECK='TRUE';
      NO_DIR_CHECK='TRUE';
      ALLOW_CONNECT='TRUE';
    'VCCIN'<25>:
      PIN_NUMBER='(0,0,0,0,0,0,0,0,0,0,0,0,0,0,0,0,0,0,CM57,0,0,0,0,0,0,0,0,0,0,0)';
      PINUSE='POWER';
      NO_LOAD_CHECK='Both';
      NO_IO_CHECK='Both';
      NO_ASSERT_CHECK='TRUE';
      NO_DIR_CHECK='TRUE';
      ALLOW_CONNECT='TRUE';
    'VCCIN'<24>:
      PIN_NUMBER='(0,0,0,0,0,0,0,0,0,0,0,0,0,0,0,0,0,0,CM59,0,0,0,0,0,0,0,0,0,0,0)';
      PINUSE='POWER';
      NO_LOAD_CHECK='Both';
      NO_IO_CHECK='Both';
      NO_ASSERT_CHECK='TRUE';
      NO_DIR_CHECK='TRUE';
      ALLOW_CONNECT='TRUE';
    'VCCIN'<23>:
      PIN_NUMBER='(0,0,0,0,0,0,0,0,0,0,0,0,0,0,0,0,0,0,CN56,0,0,0,0,0,0,0,0,0,0,0)';
      PINUSE='POWER';
      NO_LOAD_CHECK='Both';
      NO_IO_CHECK='Both';
      NO_ASSERT_CHECK='TRUE';
      NO_DIR_CHECK='TRUE';
      ALLOW_CONNECT='TRUE';
    'VCCIN'<22>:
      PIN_NUMBER='(0,0,0,0,0,0,0,0,0,0,0,0,0,0,0,0,0,0,CN58,0,0,0,0,0,0,0,0,0,0,0)';
      PINUSE='POWER';
      NO_LOAD_CHECK='Both';
      NO_IO_CHECK='Both';
      NO_ASSERT_CHECK='TRUE';
      NO_DIR_CHECK='TRUE';
      ALLOW_CONNECT='TRUE';
    'VCCIN'<21>:
      PIN_NUMBER='(0,0,0,0,0,0,0,0,0,0,0,0,0,0,0,0,0,0,CP33,0,0,0,0,0,0,0,0,0,0,0)';
      PINUSE='POWER';
      NO_LOAD_CHECK='Both';
      NO_IO_CHECK='Both';
      NO_ASSERT_CHECK='TRUE';
      NO_DIR_CHECK='TRUE';
      ALLOW_CONNECT='TRUE';
    'VCCIN'<20>:
      PIN_NUMBER='(0,0,0,0,0,0,0,0,0,0,0,0,0,0,0,0,0,0,CP55,0,0,0,0,0,0,0,0,0,0,0)';
      PINUSE='POWER';
      NO_LOAD_CHECK='Both';
      NO_IO_CHECK='Both';
      NO_ASSERT_CHECK='TRUE';
      NO_DIR_CHECK='TRUE';
      ALLOW_CONNECT='TRUE';
    'VCCIN'<19>:
      PIN_NUMBER='(0,0,0,0,0,0,0,0,0,0,0,0,0,0,0,0,0,0,CP57,0,0,0,0,0,0,0,0,0,0,0)';
      PINUSE='POWER';
      NO_LOAD_CHECK='Both';
      NO_IO_CHECK='Both';
      NO_ASSERT_CHECK='TRUE';
      NO_DIR_CHECK='TRUE';
      ALLOW_CONNECT='TRUE';
    'VCCIN'<18>:
      PIN_NUMBER='(0,0,0,0,0,0,0,0,0,0,0,0,0,0,0,0,0,0,CR34,0,0,0,0,0,0,0,0,0,0,0)';
      PINUSE='POWER';
      NO_LOAD_CHECK='Both';
      NO_IO_CHECK='Both';
      NO_ASSERT_CHECK='TRUE';
      NO_DIR_CHECK='TRUE';
      ALLOW_CONNECT='TRUE';
    'VCCIN'<17>:
      PIN_NUMBER='(0,0,0,0,0,0,0,0,0,0,0,0,0,0,0,0,0,0,CR54,0,0,0,0,0,0,0,0,0,0,0)';
      PINUSE='POWER';
      NO_LOAD_CHECK='Both';
      NO_IO_CHECK='Both';
      NO_ASSERT_CHECK='TRUE';
      NO_DIR_CHECK='TRUE';
      ALLOW_CONNECT='TRUE';
    'VCCIN'<16>:
      PIN_NUMBER='(0,0,0,0,0,0,0,0,0,0,0,0,0,0,0,0,0,0,CR56,0,0,0,0,0,0,0,0,0,0,0)';
      PINUSE='POWER';
      NO_LOAD_CHECK='Both';
      NO_IO_CHECK='Both';
      NO_ASSERT_CHECK='TRUE';
      NO_DIR_CHECK='TRUE';
      ALLOW_CONNECT='TRUE';
    'VCCIN'<15>:
      PIN_NUMBER='(0,0,0,0,0,0,0,0,0,0,0,0,0,0,0,0,0,0,CT37,0,0,0,0,0,0,0,0,0,0,0)';
      PINUSE='POWER';
      NO_LOAD_CHECK='Both';
      NO_IO_CHECK='Both';
      NO_ASSERT_CHECK='TRUE';
      NO_DIR_CHECK='TRUE';
      ALLOW_CONNECT='TRUE';
    'VCCIN'<14>:
      PIN_NUMBER='(0,0,0,0,0,0,0,0,0,0,0,0,0,0,0,0,0,0,CT39,0,0,0,0,0,0,0,0,0,0,0)';
      PINUSE='POWER';
      NO_LOAD_CHECK='Both';
      NO_IO_CHECK='Both';
      NO_ASSERT_CHECK='TRUE';
      NO_DIR_CHECK='TRUE';
      ALLOW_CONNECT='TRUE';
    'VCCIN'<13>:
      PIN_NUMBER='(0,0,0,0,0,0,0,0,0,0,0,0,0,0,0,0,0,0,CT41,0,0,0,0,0,0,0,0,0,0,0)';
      PINUSE='POWER';
      NO_LOAD_CHECK='Both';
      NO_IO_CHECK='Both';
      NO_ASSERT_CHECK='TRUE';
      NO_DIR_CHECK='TRUE';
      ALLOW_CONNECT='TRUE';
    'VCCIN'<12>:
      PIN_NUMBER='(0,0,0,0,0,0,0,0,0,0,0,0,0,0,0,0,0,0,CT53,0,0,0,0,0,0,0,0,0,0,0)';
      PINUSE='POWER';
      NO_LOAD_CHECK='Both';
      NO_IO_CHECK='Both';
      NO_ASSERT_CHECK='TRUE';
      NO_DIR_CHECK='TRUE';
      ALLOW_CONNECT='TRUE';
    'VCCIN'<11>:
      PIN_NUMBER='(0,0,0,0,0,0,0,0,0,0,0,0,0,0,0,0,0,0,CT55,0,0,0,0,0,0,0,0,0,0,0)';
      PINUSE='POWER';
      NO_LOAD_CHECK='Both';
      NO_IO_CHECK='Both';
      NO_ASSERT_CHECK='TRUE';
      NO_DIR_CHECK='TRUE';
      ALLOW_CONNECT='TRUE';
    'VCCIN'<10>:
      PIN_NUMBER='(0,0,0,0,0,0,0,0,0,0,0,0,0,0,0,0,0,0,CU38,0,0,0,0,0,0,0,0,0,0,0)';
      PINUSE='POWER';
      NO_LOAD_CHECK='Both';
      NO_IO_CHECK='Both';
      NO_ASSERT_CHECK='TRUE';
      NO_DIR_CHECK='TRUE';
      ALLOW_CONNECT='TRUE';
    'VCCIN'<9>:
      PIN_NUMBER='(0,0,0,0,0,0,0,0,0,0,0,0,0,0,0,0,0,0,CU40,0,0,0,0,0,0,0,0,0,0,0)';
      PINUSE='POWER';
      NO_LOAD_CHECK='Both';
      NO_IO_CHECK='Both';
      NO_ASSERT_CHECK='TRUE';
      NO_DIR_CHECK='TRUE';
      ALLOW_CONNECT='TRUE';
    'VCCIN'<8>:
      PIN_NUMBER='(0,0,0,0,0,0,0,0,0,0,0,0,0,0,0,0,0,0,CU42,0,0,0,0,0,0,0,0,0,0,0)';
      PINUSE='POWER';
      NO_LOAD_CHECK='Both';
      NO_IO_CHECK='Both';
      NO_ASSERT_CHECK='TRUE';
      NO_DIR_CHECK='TRUE';
      ALLOW_CONNECT='TRUE';
    'VCCIN'<7>:
      PIN_NUMBER='(0,0,0,0,0,0,0,0,0,0,0,0,0,0,0,0,0,0,CU52,0,0,0,0,0,0,0,0,0,0,0)';
      PINUSE='POWER';
      NO_LOAD_CHECK='Both';
      NO_IO_CHECK='Both';
      NO_ASSERT_CHECK='TRUE';
      NO_DIR_CHECK='TRUE';
      ALLOW_CONNECT='TRUE';
    'VCCIN'<6>:
      PIN_NUMBER='(0,0,0,0,0,0,0,0,0,0,0,0,0,0,0,0,0,0,CU54,0,0,0,0,0,0,0,0,0,0,0)';
      PINUSE='POWER';
      NO_LOAD_CHECK='Both';
      NO_IO_CHECK='Both';
      NO_ASSERT_CHECK='TRUE';
      NO_DIR_CHECK='TRUE';
      ALLOW_CONNECT='TRUE';
    'VCCIN'<5>:
      PIN_NUMBER='(0,0,0,0,0,0,0,0,0,0,0,0,0,0,0,0,0,0,CV51,0,0,0,0,0,0,0,0,0,0,0)';
      PINUSE='POWER';
      NO_LOAD_CHECK='Both';
      NO_IO_CHECK='Both';
      NO_ASSERT_CHECK='TRUE';
      NO_DIR_CHECK='TRUE';
      ALLOW_CONNECT='TRUE';
    'VCCIN'<4>:
      PIN_NUMBER='(0,0,0,0,0,0,0,0,0,0,0,0,0,0,0,0,0,0,CW46,0,0,0,0,0,0,0,0,0,0,0)';
      PINUSE='POWER';
      NO_LOAD_CHECK='Both';
      NO_IO_CHECK='Both';
      NO_ASSERT_CHECK='TRUE';
      NO_DIR_CHECK='TRUE';
      ALLOW_CONNECT='TRUE';
    'VCCIN'<3>:
      PIN_NUMBER='(0,0,0,0,0,0,0,0,0,0,0,0,0,0,0,0,0,0,CW48,0,0,0,0,0,0,0,0,0,0,0)';
      PINUSE='POWER';
      NO_LOAD_CHECK='Both';
      NO_IO_CHECK='Both';
      NO_ASSERT_CHECK='TRUE';
      NO_DIR_CHECK='TRUE';
      ALLOW_CONNECT='TRUE';
    'VCCIN'<2>:
      PIN_NUMBER='(0,0,0,0,0,0,0,0,0,0,0,0,0,0,0,0,0,0,CW50,0,0,0,0,0,0,0,0,0,0,0)';
      PINUSE='POWER';
      NO_LOAD_CHECK='Both';
      NO_IO_CHECK='Both';
      NO_ASSERT_CHECK='TRUE';
      NO_DIR_CHECK='TRUE';
      ALLOW_CONNECT='TRUE';
    'VCCIN'<1>:
      PIN_NUMBER='(0,0,0,0,0,0,0,0,0,0,0,0,0,0,0,0,0,0,CY47,0,0,0,0,0,0,0,0,0,0,0)';
      PINUSE='POWER';
      NO_LOAD_CHECK='Both';
      NO_IO_CHECK='Both';
      NO_ASSERT_CHECK='TRUE';
      NO_DIR_CHECK='TRUE';
      ALLOW_CONNECT='TRUE';
    'VCCIN'<0>:
      PIN_NUMBER='(0,0,0,0,0,0,0,0,0,0,0,0,0,0,0,0,0,0,CY49,0,0,0,0,0,0,0,0,0,0,0)';
      PINUSE='POWER';
      NO_LOAD_CHECK='Both';
      NO_IO_CHECK='Both';
      NO_ASSERT_CHECK='TRUE';
      NO_DIR_CHECK='TRUE';
      ALLOW_CONNECT='TRUE';
    'VCCINPMAX'<1>:
      PIN_NUMBER='(0,0,0,0,0,0,0,0,0,0,0,0,0,0,0,0,0,0,AV85,0,0,0,0,0,0,0,0,0,0,0)';
      PINUSE='POWER';
      NO_LOAD_CHECK='Both';
      NO_IO_CHECK='Both';
      NO_ASSERT_CHECK='TRUE';
      NO_DIR_CHECK='TRUE';
      ALLOW_CONNECT='TRUE';
    'VCCINPMAX'<0>:
      PIN_NUMBER='(0,0,0,0,0,0,0,0,0,0,0,0,0,0,0,0,0,0,AW86,0,0,0,0,0,0,0,0,0,0,0)';
      PINUSE='POWER';
      NO_LOAD_CHECK='Both';
      NO_IO_CHECK='Both';
      NO_ASSERT_CHECK='TRUE';
      NO_DIR_CHECK='TRUE';
      ALLOW_CONNECT='TRUE';
    'VCCIN_SENSE':
      PIN_NUMBER='(0,0,0,0,0,0,0,0,0,0,0,0,0,0,0,0,0,0,BA86,0,0,0,0,0,0,0,0,0,0,0)';
      BIDIRECTIONAL='TRUE';
      INPUT_LOAD='(-0.01,0.01)';
      OUTPUT_LOAD='(1.0,-1.0)';
    'VCCIO'<104>:
      PIN_NUMBER='(0,0,0,0,0,0,0,0,0,0,0,0,0,0,0,0,0,0,0,0,AR28,0,0,0,0,0,0,0,0,0)';
      PINUSE='POWER';
      NO_LOAD_CHECK='Both';
      NO_IO_CHECK='Both';
      NO_ASSERT_CHECK='TRUE';
      NO_DIR_CHECK='TRUE';
      ALLOW_CONNECT='TRUE';
    'VCCIO'<103>:
      PIN_NUMBER='(0,0,0,0,0,0,0,0,0,0,0,0,0,0,0,0,0,0,0,0,AL28,0,0,0,0,0,0,0,0,0)';
      PINUSE='POWER';
      NO_LOAD_CHECK='Both';
      NO_IO_CHECK='Both';
      NO_ASSERT_CHECK='TRUE';
      NO_DIR_CHECK='TRUE';
      ALLOW_CONNECT='TRUE';
    'VCCIO'<102>:
      PIN_NUMBER='(0,0,0,0,0,0,0,0,0,0,0,0,0,0,0,0,0,0,0,0,AM29,0,0,0,0,0,0,0,0,0)';
      PINUSE='POWER';
      NO_LOAD_CHECK='Both';
      NO_IO_CHECK='Both';
      NO_ASSERT_CHECK='TRUE';
      NO_DIR_CHECK='TRUE';
      ALLOW_CONNECT='TRUE';
    'VCCIO'<101>:
      PIN_NUMBER='(0,0,0,0,0,0,0,0,0,0,0,0,0,0,0,0,0,0,0,0,AG34,0,0,0,0,0,0,0,0,0)';
      PINUSE='POWER';
      NO_LOAD_CHECK='Both';
      NO_IO_CHECK='Both';
      NO_ASSERT_CHECK='TRUE';
      NO_DIR_CHECK='TRUE';
      ALLOW_CONNECT='TRUE';
    'VCCIO'<100>:
      PIN_NUMBER='(0,0,0,0,0,0,0,0,0,0,0,0,0,0,0,0,0,0,0,0,AE34,0,0,0,0,0,0,0,0,0)';
      PINUSE='POWER';
      NO_LOAD_CHECK='Both';
      NO_IO_CHECK='Both';
      NO_ASSERT_CHECK='TRUE';
      NO_DIR_CHECK='TRUE';
      ALLOW_CONNECT='TRUE';
    'VCCIO'<99>:
      PIN_NUMBER='(0,0,0,0,0,0,0,0,0,0,0,0,0,0,0,0,0,0,0,0,AD35,0,0,0,0,0,0,0,0,0)';
      PINUSE='POWER';
      NO_LOAD_CHECK='Both';
      NO_IO_CHECK='Both';
      NO_ASSERT_CHECK='TRUE';
      NO_DIR_CHECK='TRUE';
      ALLOW_CONNECT='TRUE';
    'VCCIO'<98>:
      PIN_NUMBER='(0,0,0,0,0,0,0,0,0,0,0,0,0,0,0,0,0,0,0,0,AF35,0,0,0,0,0,0,0,0,0)';
      PINUSE='POWER';
      NO_LOAD_CHECK='Both';
      NO_IO_CHECK='Both';
      NO_ASSERT_CHECK='TRUE';
      NO_DIR_CHECK='TRUE';
      ALLOW_CONNECT='TRUE';
    'VCCIO'<97>:
      PIN_NUMBER='(0,0,0,0,0,0,0,0,0,0,0,0,0,0,0,0,0,0,0,0,AC36,0,0,0,0,0,0,0,0,0)';
      PINUSE='POWER';
      NO_LOAD_CHECK='Both';
      NO_IO_CHECK='Both';
      NO_ASSERT_CHECK='TRUE';
      NO_DIR_CHECK='TRUE';
      ALLOW_CONNECT='TRUE';
    'VCCIO'<96>:
      PIN_NUMBER='(0,0,0,0,0,0,0,0,0,0,0,0,0,0,0,0,0,0,0,0,AD37,0,0,0,0,0,0,0,0,0)';
      PINUSE='POWER';
      NO_LOAD_CHECK='Both';
      NO_IO_CHECK='Both';
      NO_ASSERT_CHECK='TRUE';
      NO_DIR_CHECK='TRUE';
      ALLOW_CONNECT='TRUE';
    'VCCIO'<95>:
      PIN_NUMBER='(0,0,0,0,0,0,0,0,0,0,0,0,0,0,0,0,0,0,0,0,AE36,0,0,0,0,0,0,0,0,0)';
      PINUSE='POWER';
      NO_LOAD_CHECK='Both';
      NO_IO_CHECK='Both';
      NO_ASSERT_CHECK='TRUE';
      NO_DIR_CHECK='TRUE';
      ALLOW_CONNECT='TRUE';
    'VCCIO'<94>:
      PIN_NUMBER='(0,0,0,0,0,0,0,0,0,0,0,0,0,0,0,0,0,0,0,0,BF27,0,0,0,0,0,0,0,0,0)';
      PINUSE='POWER';
      NO_LOAD_CHECK='Both';
      NO_IO_CHECK='Both';
      NO_ASSERT_CHECK='TRUE';
      NO_DIR_CHECK='TRUE';
      ALLOW_CONNECT='TRUE';
    'VCCIO'<93>:
      PIN_NUMBER='(0,0,0,0,0,0,0,0,0,0,0,0,0,0,0,0,0,0,0,0,BG26,0,0,0,0,0,0,0,0,0)';
      PINUSE='POWER';
      NO_LOAD_CHECK='Both';
      NO_IO_CHECK='Both';
      NO_ASSERT_CHECK='TRUE';
      NO_DIR_CHECK='TRUE';
      ALLOW_CONNECT='TRUE';
    'VCCIO'<92>:
      PIN_NUMBER='(0,0,0,0,0,0,0,0,0,0,0,0,0,0,0,0,0,0,0,0,BH25,0,0,0,0,0,0,0,0,0)';
      PINUSE='POWER';
      NO_LOAD_CHECK='Both';
      NO_IO_CHECK='Both';
      NO_ASSERT_CHECK='TRUE';
      NO_DIR_CHECK='TRUE';
      ALLOW_CONNECT='TRUE';
    'VCCIO'<91>:
      PIN_NUMBER='(0,0,0,0,0,0,0,0,0,0,0,0,0,0,0,0,0,0,0,0,BH27,0,0,0,0,0,0,0,0,0)';
      PINUSE='POWER';
      NO_LOAD_CHECK='Both';
      NO_IO_CHECK='Both';
      NO_ASSERT_CHECK='TRUE';
      NO_DIR_CHECK='TRUE';
      ALLOW_CONNECT='TRUE';
    'VCCIO'<90>:
      PIN_NUMBER='(0,0,0,0,0,0,0,0,0,0,0,0,0,0,0,0,0,0,0,0,BJ26,0,0,0,0,0,0,0,0,0)';
      PINUSE='POWER';
      NO_LOAD_CHECK='Both';
      NO_IO_CHECK='Both';
      NO_ASSERT_CHECK='TRUE';
      NO_DIR_CHECK='TRUE';
      ALLOW_CONNECT='TRUE';
    'VCCIO'<89>:
      PIN_NUMBER='(0,0,0,0,0,0,0,0,0,0,0,0,0,0,0,0,0,0,0,0,BK25,0,0,0,0,0,0,0,0,0)';
      PINUSE='POWER';
      NO_LOAD_CHECK='Both';
      NO_IO_CHECK='Both';
      NO_ASSERT_CHECK='TRUE';
      NO_DIR_CHECK='TRUE';
      ALLOW_CONNECT='TRUE';
    'VCCIO'<88>:
      PIN_NUMBER='(0,0,0,0,0,0,0,0,0,0,0,0,0,0,0,0,0,0,0,0,BK27,0,0,0,0,0,0,0,0,0)';
      PINUSE='POWER';
      NO_LOAD_CHECK='Both';
      NO_IO_CHECK='Both';
      NO_ASSERT_CHECK='TRUE';
      NO_DIR_CHECK='TRUE';
      ALLOW_CONNECT='TRUE';
    'VCCIO'<87>:
      PIN_NUMBER='(0,0,0,0,0,0,0,0,0,0,0,0,0,0,0,0,0,0,0,0,BL26,0,0,0,0,0,0,0,0,0)';
      PINUSE='POWER';
      NO_LOAD_CHECK='Both';
      NO_IO_CHECK='Both';
      NO_ASSERT_CHECK='TRUE';
      NO_DIR_CHECK='TRUE';
      ALLOW_CONNECT='TRUE';
    'VCCIO'<86>:
      PIN_NUMBER='(0,0,0,0,0,0,0,0,0,0,0,0,0,0,0,0,0,0,0,0,BM27,0,0,0,0,0,0,0,0,0)';
      PINUSE='POWER';
      NO_LOAD_CHECK='Both';
      NO_IO_CHECK='Both';
      NO_ASSERT_CHECK='TRUE';
      NO_DIR_CHECK='TRUE';
      ALLOW_CONNECT='TRUE';
    'VCCIO'<85>:
      PIN_NUMBER='(0,0,0,0,0,0,0,0,0,0,0,0,0,0,0,0,0,0,0,0,CH27,0,0,0,0,0,0,0,0,0)';
      PINUSE='POWER';
      NO_LOAD_CHECK='Both';
      NO_IO_CHECK='Both';
      NO_ASSERT_CHECK='TRUE';
      NO_DIR_CHECK='TRUE';
      ALLOW_CONNECT='TRUE';
    'VCCIO'<84>:
      PIN_NUMBER='(0,0,0,0,0,0,0,0,0,0,0,0,0,0,0,0,0,0,0,0,CJ28,0,0,0,0,0,0,0,0,0)';
      PINUSE='POWER';
      NO_LOAD_CHECK='Both';
      NO_IO_CHECK='Both';
      NO_ASSERT_CHECK='TRUE';
      NO_DIR_CHECK='TRUE';
      ALLOW_CONNECT='TRUE';
    'VCCIO'<83>:
      PIN_NUMBER='(0,0,0,0,0,0,0,0,0,0,0,0,0,0,0,0,0,0,0,0,CC26,0,0,0,0,0,0,0,0,0)';
      PINUSE='POWER';
      NO_LOAD_CHECK='Both';
      NO_IO_CHECK='Both';
      NO_ASSERT_CHECK='TRUE';
      NO_DIR_CHECK='TRUE';
      ALLOW_CONNECT='TRUE';
    'VCCIO'<82>:
      PIN_NUMBER='(0,0,0,0,0,0,0,0,0,0,0,0,0,0,0,0,0,0,0,0,CD27,0,0,0,0,0,0,0,0,0)';
      PINUSE='POWER';
      NO_LOAD_CHECK='Both';
      NO_IO_CHECK='Both';
      NO_ASSERT_CHECK='TRUE';
      NO_DIR_CHECK='TRUE';
      ALLOW_CONNECT='TRUE';
    'VCCIO'<81>:
      PIN_NUMBER='(0,0,0,0,0,0,0,0,0,0,0,0,0,0,0,0,0,0,0,0,CF27,0,0,0,0,0,0,0,0,0)';
      PINUSE='POWER';
      NO_LOAD_CHECK='Both';
      NO_IO_CHECK='Both';
      NO_ASSERT_CHECK='TRUE';
      NO_DIR_CHECK='TRUE';
      ALLOW_CONNECT='TRUE';
    'VCCIO'<80>:
      PIN_NUMBER='(0,0,0,0,0,0,0,0,0,0,0,0,0,0,0,0,0,0,0,0,AV27,0,0,0,0,0,0,0,0,0)';
      PINUSE='POWER';
      NO_LOAD_CHECK='Both';
      NO_IO_CHECK='Both';
      NO_ASSERT_CHECK='TRUE';
      NO_DIR_CHECK='TRUE';
      ALLOW_CONNECT='TRUE';
    'VCCIO'<79>:
      PIN_NUMBER='(0,0,0,0,0,0,0,0,0,0,0,0,0,0,0,0,0,0,0,0,AW26,0,0,0,0,0,0,0,0,0)';
      PINUSE='POWER';
      NO_LOAD_CHECK='Both';
      NO_IO_CHECK='Both';
      NO_ASSERT_CHECK='TRUE';
      NO_DIR_CHECK='TRUE';
      ALLOW_CONNECT='TRUE';
    'VCCIO'<78>:
      PIN_NUMBER='(0,0,0,0,0,0,0,0,0,0,0,0,0,0,0,0,0,0,0,0,AY27,0,0,0,0,0,0,0,0,0)';
      PINUSE='POWER';
      NO_LOAD_CHECK='Both';
      NO_IO_CHECK='Both';
      NO_ASSERT_CHECK='TRUE';
      NO_DIR_CHECK='TRUE';
      ALLOW_CONNECT='TRUE';
    'VCCIO'<77>:
      PIN_NUMBER='(0,0,0,0,0,0,0,0,0,0,0,0,0,0,0,0,0,0,0,0,BA26,0,0,0,0,0,0,0,0,0)';
      PINUSE='POWER';
      NO_LOAD_CHECK='Both';
      NO_IO_CHECK='Both';
      NO_ASSERT_CHECK='TRUE';
      NO_DIR_CHECK='TRUE';
      ALLOW_CONNECT='TRUE';
    'VCCIO'<76>:
      PIN_NUMBER='(0,0,0,0,0,0,0,0,0,0,0,0,0,0,0,0,0,0,0,0,BB27,0,0,0,0,0,0,0,0,0)';
      PINUSE='POWER';
      NO_LOAD_CHECK='Both';
      NO_IO_CHECK='Both';
      NO_ASSERT_CHECK='TRUE';
      NO_DIR_CHECK='TRUE';
      ALLOW_CONNECT='TRUE';
    'VCCIO'<75>:
      PIN_NUMBER='(0,0,0,0,0,0,0,0,0,0,0,0,0,0,0,0,0,0,0,0,BC26,0,0,0,0,0,0,0,0,0)';
      PINUSE='POWER';
      NO_LOAD_CHECK='Both';
      NO_IO_CHECK='Both';
      NO_ASSERT_CHECK='TRUE';
      NO_DIR_CHECK='TRUE';
      ALLOW_CONNECT='TRUE';
    'VCCIO'<74>:
      PIN_NUMBER='(0,0,0,0,0,0,0,0,0,0,0,0,0,0,0,0,0,0,0,0,W10,0,0,0,0,0,0,0,0,0)';
      PINUSE='POWER';
      NO_LOAD_CHECK='Both';
      NO_IO_CHECK='Both';
      NO_ASSERT_CHECK='TRUE';
      NO_DIR_CHECK='TRUE';
      ALLOW_CONNECT='TRUE';
    'VCCIO'<73>:
      PIN_NUMBER='(0,0,0,0,0,0,0,0,0,0,0,0,0,0,0,0,0,0,0,0,N18,0,0,0,0,0,0,0,0,0)';
      PINUSE='POWER';
      NO_LOAD_CHECK='Both';
      NO_IO_CHECK='Both';
      NO_ASSERT_CHECK='TRUE';
      NO_DIR_CHECK='TRUE';
      ALLOW_CONNECT='TRUE';
    'VCCIO'<72>:
      PIN_NUMBER='(0,0,0,0,0,0,0,0,0,0,0,0,0,0,0,0,0,0,0,0,M9,0,0,0,0,0,0,0,0,0)';
      PINUSE='POWER';
      NO_LOAD_CHECK='Both';
      NO_IO_CHECK='Both';
      NO_ASSERT_CHECK='TRUE';
      NO_DIR_CHECK='TRUE';
      ALLOW_CONNECT='TRUE';
    'VCCIO'<71>:
      PIN_NUMBER='(0,0,0,0,0,0,0,0,0,0,0,0,0,0,0,0,0,0,0,0,M7,0,0,0,0,0,0,0,0,0)';
      PINUSE='POWER';
      NO_LOAD_CHECK='Both';
      NO_IO_CHECK='Both';
      NO_ASSERT_CHECK='TRUE';
      NO_DIR_CHECK='TRUE';
      ALLOW_CONNECT='TRUE';
    'VCCIO'<70>:
      PIN_NUMBER='(0,0,0,0,0,0,0,0,0,0,0,0,0,0,0,0,0,0,0,0,K15,0,0,0,0,0,0,0,0,0)';
      PINUSE='POWER';
      NO_LOAD_CHECK='Both';
      NO_IO_CHECK='Both';
      NO_ASSERT_CHECK='TRUE';
      NO_DIR_CHECK='TRUE';
      ALLOW_CONNECT='TRUE';
    'VCCIO'<69>:
      PIN_NUMBER='(0,0,0,0,0,0,0,0,0,0,0,0,0,0,0,0,0,0,0,0,J2,0,0,0,0,0,0,0,0,0)';
      PINUSE='POWER';
      NO_LOAD_CHECK='Both';
      NO_IO_CHECK='Both';
      NO_ASSERT_CHECK='TRUE';
      NO_DIR_CHECK='TRUE';
      ALLOW_CONNECT='TRUE';
    'VCCIO'<68>:
      PIN_NUMBER='(0,0,0,0,0,0,0,0,0,0,0,0,0,0,0,0,0,0,0,0,EB15,0,0,0,0,0,0,0,0,0)';
      PINUSE='POWER';
      NO_LOAD_CHECK='Both';
      NO_IO_CHECK='Both';
      NO_ASSERT_CHECK='TRUE';
      NO_DIR_CHECK='TRUE';
      ALLOW_CONNECT='TRUE';
    'VCCIO'<67>:
      PIN_NUMBER='(0,0,0,0,0,0,0,0,0,0,0,0,0,0,0,0,0,0,0,0,EA12,0,0,0,0,0,0,0,0,0)';
      PINUSE='POWER';
      NO_LOAD_CHECK='Both';
      NO_IO_CHECK='Both';
      NO_ASSERT_CHECK='TRUE';
      NO_DIR_CHECK='TRUE';
      ALLOW_CONNECT='TRUE';
    'VCCIO'<66>:
      PIN_NUMBER='(0,0,0,0,0,0,0,0,0,0,0,0,0,0,0,0,0,0,0,0,DU20,0,0,0,0,0,0,0,0,0)';
      PINUSE='POWER';
      NO_LOAD_CHECK='Both';
      NO_IO_CHECK='Both';
      NO_ASSERT_CHECK='TRUE';
      NO_DIR_CHECK='TRUE';
      ALLOW_CONNECT='TRUE';
    'VCCIO'<65>:
      PIN_NUMBER='(0,0,0,0,0,0,0,0,0,0,0,0,0,0,0,0,0,0,0,0,DR2,0,0,0,0,0,0,0,0,0)';
      PINUSE='POWER';
      NO_LOAD_CHECK='Both';
      NO_IO_CHECK='Both';
      NO_ASSERT_CHECK='TRUE';
      NO_DIR_CHECK='TRUE';
      ALLOW_CONNECT='TRUE';
    'VCCIO'<64>:
      PIN_NUMBER='(0,0,0,0,0,0,0,0,0,0,0,0,0,0,0,0,0,0,0,0,DR10,0,0,0,0,0,0,0,0,0)';
      PINUSE='POWER';
      NO_LOAD_CHECK='Both';
      NO_IO_CHECK='Both';
      NO_ASSERT_CHECK='TRUE';
      NO_DIR_CHECK='TRUE';
      ALLOW_CONNECT='TRUE';
    'VCCIO'<63>:
      PIN_NUMBER='(0,0,0,0,0,0,0,0,0,0,0,0,0,0,0,0,0,0,0,0,DP19,0,0,0,0,0,0,0,0,0)';
      PINUSE='POWER';
      NO_LOAD_CHECK='Both';
      NO_IO_CHECK='Both';
      NO_ASSERT_CHECK='TRUE';
      NO_DIR_CHECK='TRUE';
      ALLOW_CONNECT='TRUE';
    'VCCIO'<62>:
      PIN_NUMBER='(0,0,0,0,0,0,0,0,0,0,0,0,0,0,0,0,0,0,0,0,DN8,0,0,0,0,0,0,0,0,0)';
      PINUSE='POWER';
      NO_LOAD_CHECK='Both';
      NO_IO_CHECK='Both';
      NO_ASSERT_CHECK='TRUE';
      NO_DIR_CHECK='TRUE';
      ALLOW_CONNECT='TRUE';
    'VCCIO'<61>:
      PIN_NUMBER='(0,0,0,0,0,0,0,0,0,0,0,0,0,0,0,0,0,0,0,0,DM17,0,0,0,0,0,0,0,0,0)';
      PINUSE='POWER';
      NO_LOAD_CHECK='Both';
      NO_IO_CHECK='Both';
      NO_ASSERT_CHECK='TRUE';
      NO_DIR_CHECK='TRUE';
      ALLOW_CONNECT='TRUE';
    'VCCIO'<60>:
      PIN_NUMBER='(0,0,0,0,0,0,0,0,0,0,0,0,0,0,0,0,0,0,0,0,DJ16,0,0,0,0,0,0,0,0,0)';
      PINUSE='POWER';
      NO_LOAD_CHECK='Both';
      NO_IO_CHECK='Both';
      NO_ASSERT_CHECK='TRUE';
      NO_DIR_CHECK='TRUE';
      ALLOW_CONNECT='TRUE';
    'VCCIO'<59>:
      PIN_NUMBER='(0,0,0,0,0,0,0,0,0,0,0,0,0,0,0,0,0,0,0,0,H13,0,0,0,0,0,0,0,0,0)';
      PINUSE='POWER';
      NO_LOAD_CHECK='Both';
      NO_IO_CHECK='Both';
      NO_ASSERT_CHECK='TRUE';
      NO_DIR_CHECK='TRUE';
      ALLOW_CONNECT='TRUE';
    'VCCIO'<58>:
      PIN_NUMBER='(0,0,0,0,0,0,0,0,0,0,0,0,0,0,0,0,0,0,0,0,J10,0,0,0,0,0,0,0,0,0)';
      PINUSE='POWER';
      NO_LOAD_CHECK='Both';
      NO_IO_CHECK='Both';
      NO_ASSERT_CHECK='TRUE';
      NO_DIR_CHECK='TRUE';
      ALLOW_CONNECT='TRUE';
    'VCCIO'<57>:
      PIN_NUMBER='(0,0,0,0,0,0,0,0,0,0,0,0,0,0,0,0,0,0,0,0,L14,0,0,0,0,0,0,0,0,0)';
      PINUSE='POWER';
      NO_LOAD_CHECK='Both';
      NO_IO_CHECK='Both';
      NO_ASSERT_CHECK='TRUE';
      NO_DIR_CHECK='TRUE';
      ALLOW_CONNECT='TRUE';
    'VCCIO'<56>:
      PIN_NUMBER='(0,0,0,0,0,0,0,0,0,0,0,0,0,0,0,0,0,0,0,0,L16,0,0,0,0,0,0,0,0,0)';
      PINUSE='POWER';
      NO_LOAD_CHECK='Both';
      NO_IO_CHECK='Both';
      NO_ASSERT_CHECK='TRUE';
      NO_DIR_CHECK='TRUE';
      ALLOW_CONNECT='TRUE';
    'VCCIO'<55>:
      PIN_NUMBER='(0,0,0,0,0,0,0,0,0,0,0,0,0,0,0,0,0,0,0,0,DH7,0,0,0,0,0,0,0,0,0)';
      PINUSE='POWER';
      NO_LOAD_CHECK='Both';
      NO_IO_CHECK='Both';
      NO_ASSERT_CHECK='TRUE';
      NO_DIR_CHECK='TRUE';
      ALLOW_CONNECT='TRUE';
    'VCCIO'<54>:
      PIN_NUMBER='(0,0,0,0,0,0,0,0,0,0,0,0,0,0,0,0,0,0,0,0,DG8,0,0,0,0,0,0,0,0,0)';
      PINUSE='POWER';
      NO_LOAD_CHECK='Both';
      NO_IO_CHECK='Both';
      NO_ASSERT_CHECK='TRUE';
      NO_DIR_CHECK='TRUE';
      ALLOW_CONNECT='TRUE';
    'VCCIO'<53>:
      PIN_NUMBER='(0,0,0,0,0,0,0,0,0,0,0,0,0,0,0,0,0,0,0,0,M11,0,0,0,0,0,0,0,0,0)';
      PINUSE='POWER';
      NO_LOAD_CHECK='Both';
      NO_IO_CHECK='Both';
      NO_ASSERT_CHECK='TRUE';
      NO_DIR_CHECK='TRUE';
      ALLOW_CONNECT='TRUE';
    'VCCIO'<52>:
      PIN_NUMBER='(0,0,0,0,0,0,0,0,0,0,0,0,0,0,0,0,0,0,0,0,M21,0,0,0,0,0,0,0,0,0)';
      PINUSE='POWER';
      NO_LOAD_CHECK='Both';
      NO_IO_CHECK='Both';
      NO_ASSERT_CHECK='TRUE';
      NO_DIR_CHECK='TRUE';
      ALLOW_CONNECT='TRUE';
    'VCCIO'<51>:
      PIN_NUMBER='(0,0,0,0,0,0,0,0,0,0,0,0,0,0,0,0,0,0,0,0,P5,0,0,0,0,0,0,0,0,0)';
      PINUSE='POWER';
      NO_LOAD_CHECK='Both';
      NO_IO_CHECK='Both';
      NO_ASSERT_CHECK='TRUE';
      NO_DIR_CHECK='TRUE';
      ALLOW_CONNECT='TRUE';
    'VCCIO'<50>:
      PIN_NUMBER='(0,0,0,0,0,0,0,0,0,0,0,0,0,0,0,0,0,0,0,0,T3,0,0,0,0,0,0,0,0,0)';
      PINUSE='POWER';
      NO_LOAD_CHECK='Both';
      NO_IO_CHECK='Both';
      NO_ASSERT_CHECK='TRUE';
      NO_DIR_CHECK='TRUE';
      ALLOW_CONNECT='TRUE';
    'VCCIO'<49>:
      PIN_NUMBER='(0,0,0,0,0,0,0,0,0,0,0,0,0,0,0,0,0,0,0,0,U14,0,0,0,0,0,0,0,0,0)';
      PINUSE='POWER';
      NO_LOAD_CHECK='Both';
      NO_IO_CHECK='Both';
      NO_ASSERT_CHECK='TRUE';
      NO_DIR_CHECK='TRUE';
      ALLOW_CONNECT='TRUE';
    'VCCIO'<48>:
      PIN_NUMBER='(0,0,0,0,0,0,0,0,0,0,0,0,0,0,0,0,0,0,0,0,DF21,0,0,0,0,0,0,0,0,0)';
      PINUSE='POWER';
      NO_LOAD_CHECK='Both';
      NO_IO_CHECK='Both';
      NO_ASSERT_CHECK='TRUE';
      NO_DIR_CHECK='TRUE';
      ALLOW_CONNECT='TRUE';
    'VCCIO'<47>:
      PIN_NUMBER='(0,0,0,0,0,0,0,0,0,0,0,0,0,0,0,0,0,0,0,0,W4,0,0,0,0,0,0,0,0,0)';
      PINUSE='POWER';
      NO_LOAD_CHECK='Both';
      NO_IO_CHECK='Both';
      NO_ASSERT_CHECK='TRUE';
      NO_DIR_CHECK='TRUE';
      ALLOW_CONNECT='TRUE';
    'VCCIO'<46>:
      PIN_NUMBER='(0,0,0,0,0,0,0,0,0,0,0,0,0,0,0,0,0,0,0,0,W6,0,0,0,0,0,0,0,0,0)';
      PINUSE='POWER';
      NO_LOAD_CHECK='Both';
      NO_IO_CHECK='Both';
      NO_ASSERT_CHECK='TRUE';
      NO_DIR_CHECK='TRUE';
      ALLOW_CONNECT='TRUE';
    'VCCIO'<45>:
      PIN_NUMBER='(0,0,0,0,0,0,0,0,0,0,0,0,0,0,0,0,0,0,0,0,AA10,0,0,0,0,0,0,0,0,0)';
      PINUSE='POWER';
      NO_LOAD_CHECK='Both';
      NO_IO_CHECK='Both';
      NO_ASSERT_CHECK='TRUE';
      NO_DIR_CHECK='TRUE';
      ALLOW_CONNECT='TRUE';
    'VCCIO'<44>:
      PIN_NUMBER='(0,0,0,0,0,0,0,0,0,0,0,0,0,0,0,0,0,0,0,0,AC20,0,0,0,0,0,0,0,0,0)';
      PINUSE='POWER';
      NO_LOAD_CHECK='Both';
      NO_IO_CHECK='Both';
      NO_ASSERT_CHECK='TRUE';
      NO_DIR_CHECK='TRUE';
      ALLOW_CONNECT='TRUE';
    'VCCIO'<43>:
      PIN_NUMBER='(0,0,0,0,0,0,0,0,0,0,0,0,0,0,0,0,0,0,0,0,AC4,0,0,0,0,0,0,0,0,0)';
      PINUSE='POWER';
      NO_LOAD_CHECK='Both';
      NO_IO_CHECK='Both';
      NO_ASSERT_CHECK='TRUE';
      NO_DIR_CHECK='TRUE';
      ALLOW_CONNECT='TRUE';
    'VCCIO'<42>:
      PIN_NUMBER='(0,0,0,0,0,0,0,0,0,0,0,0,0,0,0,0,0,0,0,0,AH9,0,0,0,0,0,0,0,0,0)';
      PINUSE='POWER';
      NO_LOAD_CHECK='Both';
      NO_IO_CHECK='Both';
      NO_ASSERT_CHECK='TRUE';
      NO_DIR_CHECK='TRUE';
      ALLOW_CONNECT='TRUE';
    'VCCIO'<41>:
      PIN_NUMBER='(0,0,0,0,0,0,0,0,0,0,0,0,0,0,0,0,0,0,0,0,DF13,0,0,0,0,0,0,0,0,0)';
      PINUSE='POWER';
      NO_LOAD_CHECK='Both';
      NO_IO_CHECK='Both';
      NO_ASSERT_CHECK='TRUE';
      NO_DIR_CHECK='TRUE';
      ALLOW_CONNECT='TRUE';
    'VCCIO'<40>:
      PIN_NUMBER='(0,0,0,0,0,0,0,0,0,0,0,0,0,0,0,0,0,0,0,0,AN10,0,0,0,0,0,0,0,0,0)';
      PINUSE='POWER';
      NO_LOAD_CHECK='Both';
      NO_IO_CHECK='Both';
      NO_ASSERT_CHECK='TRUE';
      NO_DIR_CHECK='TRUE';
      ALLOW_CONNECT='TRUE';
    'VCCIO'<39>:
      PIN_NUMBER='(0,0,0,0,0,0,0,0,0,0,0,0,0,0,0,0,0,0,0,0,DD7,0,0,0,0,0,0,0,0,0)';
      PINUSE='POWER';
      NO_LOAD_CHECK='Both';
      NO_IO_CHECK='Both';
      NO_ASSERT_CHECK='TRUE';
      NO_DIR_CHECK='TRUE';
      ALLOW_CONNECT='TRUE';
    'VCCIO'<38>:
      PIN_NUMBER='(0,0,0,0,0,0,0,0,0,0,0,0,0,0,0,0,0,0,0,0,AT11,0,0,0,0,0,0,0,0,0)';
      PINUSE='POWER';
      NO_LOAD_CHECK='Both';
      NO_IO_CHECK='Both';
      NO_ASSERT_CHECK='TRUE';
      NO_DIR_CHECK='TRUE';
      ALLOW_CONNECT='TRUE';
    'VCCIO'<37>:
      PIN_NUMBER='(0,0,0,0,0,0,0,0,0,0,0,0,0,0,0,0,0,0,0,0,AW6,0,0,0,0,0,0,0,0,0)';
      PINUSE='POWER';
      NO_LOAD_CHECK='Both';
      NO_IO_CHECK='Both';
      NO_ASSERT_CHECK='TRUE';
      NO_DIR_CHECK='TRUE';
      ALLOW_CONNECT='TRUE';
    'VCCIO'<36>:
      PIN_NUMBER='(0,0,0,0,0,0,0,0,0,0,0,0,0,0,0,0,0,0,0,0,AY11,0,0,0,0,0,0,0,0,0)';
      PINUSE='POWER';
      NO_LOAD_CHECK='Both';
      NO_IO_CHECK='Both';
      NO_ASSERT_CHECK='TRUE';
      NO_DIR_CHECK='TRUE';
      ALLOW_CONNECT='TRUE';
    'VCCIO'<35>:
      PIN_NUMBER='(0,0,0,0,0,0,0,0,0,0,0,0,0,0,0,0,0,0,0,0,BA24,0,0,0,0,0,0,0,0,0)';
      PINUSE='POWER';
      NO_LOAD_CHECK='Both';
      NO_IO_CHECK='Both';
      NO_ASSERT_CHECK='TRUE';
      NO_DIR_CHECK='TRUE';
      ALLOW_CONNECT='TRUE';
    'VCCIO'<34>:
      PIN_NUMBER='(0,0,0,0,0,0,0,0,0,0,0,0,0,0,0,0,0,0,0,0,BB5,0,0,0,0,0,0,0,0,0)';
      PINUSE='POWER';
      NO_LOAD_CHECK='Both';
      NO_IO_CHECK='Both';
      NO_ASSERT_CHECK='TRUE';
      NO_DIR_CHECK='TRUE';
      ALLOW_CONNECT='TRUE';
    'VCCIO'<33>:
      PIN_NUMBER='(0,0,0,0,0,0,0,0,0,0,0,0,0,0,0,0,0,0,0,0,DA14,0,0,0,0,0,0,0,0,0)';
      PINUSE='POWER';
      NO_LOAD_CHECK='Both';
      NO_IO_CHECK='Both';
      NO_ASSERT_CHECK='TRUE';
      NO_DIR_CHECK='TRUE';
      ALLOW_CONNECT='TRUE';
    'VCCIO'<32>:
      PIN_NUMBER='(0,0,0,0,0,0,0,0,0,0,0,0,0,0,0,0,0,0,0,0,BF23,0,0,0,0,0,0,0,0,0)';
      PINUSE='POWER';
      NO_LOAD_CHECK='Both';
      NO_IO_CHECK='Both';
      NO_ASSERT_CHECK='TRUE';
      NO_DIR_CHECK='TRUE';
      ALLOW_CONNECT='TRUE';
    'VCCIO'<31>:
      PIN_NUMBER='(0,0,0,0,0,0,0,0,0,0,0,0,0,0,0,0,0,0,0,0,BJ24,0,0,0,0,0,0,0,0,0)';
      PINUSE='POWER';
      NO_LOAD_CHECK='Both';
      NO_IO_CHECK='Both';
      NO_ASSERT_CHECK='TRUE';
      NO_DIR_CHECK='TRUE';
      ALLOW_CONNECT='TRUE';
    'VCCIO'<30>:
      PIN_NUMBER='(0,0,0,0,0,0,0,0,0,0,0,0,0,0,0,0,0,0,0,0,BP25,0,0,0,0,0,0,0,0,0)';
      PINUSE='POWER';
      NO_LOAD_CHECK='Both';
      NO_IO_CHECK='Both';
      NO_ASSERT_CHECK='TRUE';
      NO_DIR_CHECK='TRUE';
      ALLOW_CONNECT='TRUE';
    'VCCIO'<29>:
      PIN_NUMBER='(0,0,0,0,0,0,0,0,0,0,0,0,0,0,0,0,0,0,0,0,CB13,0,0,0,0,0,0,0,0,0)';
      PINUSE='POWER';
      NO_LOAD_CHECK='Both';
      NO_IO_CHECK='Both';
      NO_ASSERT_CHECK='TRUE';
      NO_DIR_CHECK='TRUE';
      ALLOW_CONNECT='TRUE';
    'VCCIO'<28>:
      PIN_NUMBER='(0,0,0,0,0,0,0,0,0,0,0,0,0,0,0,0,0,0,0,0,CB17,0,0,0,0,0,0,0,0,0)';
      PINUSE='POWER';
      NO_LOAD_CHECK='Both';
      NO_IO_CHECK='Both';
      NO_ASSERT_CHECK='TRUE';
      NO_DIR_CHECK='TRUE';
      ALLOW_CONNECT='TRUE';
    'VCCIO'<27>:
      PIN_NUMBER='(0,0,0,0,0,0,0,0,0,0,0,0,0,0,0,0,0,0,0,0,CD9,0,0,0,0,0,0,0,0,0)';
      PINUSE='POWER';
      NO_LOAD_CHECK='Both';
      NO_IO_CHECK='Both';
      NO_ASSERT_CHECK='TRUE';
      NO_DIR_CHECK='TRUE';
      ALLOW_CONNECT='TRUE';
    'VCCIO'<26>:
      PIN_NUMBER='(0,0,0,0,0,0,0,0,0,0,0,0,0,0,0,0,0,0,0,0,CE18,0,0,0,0,0,0,0,0,0)';
      PINUSE='POWER';
      NO_LOAD_CHECK='Both';
      NO_IO_CHECK='Both';
      NO_ASSERT_CHECK='TRUE';
      NO_DIR_CHECK='TRUE';
      ALLOW_CONNECT='TRUE';
    'VCCIO'<25>:
      PIN_NUMBER='(0,0,0,0,0,0,0,0,0,0,0,0,0,0,0,0,0,0,0,0,D7,0,0,0,0,0,0,0,0,0)';
      PINUSE='POWER';
      NO_LOAD_CHECK='Both';
      NO_IO_CHECK='Both';
      NO_ASSERT_CHECK='TRUE';
      NO_DIR_CHECK='TRUE';
      ALLOW_CONNECT='TRUE';
    'VCCIO'<24>:
      PIN_NUMBER='(0,0,0,0,0,0,0,0,0,0,0,0,0,0,0,0,0,0,0,0,CH9,0,0,0,0,0,0,0,0,0)';
      PINUSE='POWER';
      NO_LOAD_CHECK='Both';
      NO_IO_CHECK='Both';
      NO_ASSERT_CHECK='TRUE';
      NO_DIR_CHECK='TRUE';
      ALLOW_CONNECT='TRUE';
    'VCCIO'<23>:
      PIN_NUMBER='(0,0,0,0,0,0,0,0,0,0,0,0,0,0,0,0,0,0,0,0,CV7,0,0,0,0,0,0,0,0,0)';
      PINUSE='POWER';
      NO_LOAD_CHECK='Both';
      NO_IO_CHECK='Both';
      NO_ASSERT_CHECK='TRUE';
      NO_DIR_CHECK='TRUE';
      ALLOW_CONNECT='TRUE';
    'VCCIO'<22>:
      PIN_NUMBER='(0,0,0,0,0,0,0,0,0,0,0,0,0,0,0,0,0,0,0,0,CK5,0,0,0,0,0,0,0,0,0)';
      PINUSE='POWER';
      NO_LOAD_CHECK='Both';
      NO_IO_CHECK='Both';
      NO_ASSERT_CHECK='TRUE';
      NO_DIR_CHECK='TRUE';
      ALLOW_CONNECT='TRUE';
    'VCCIO'<21>:
      PIN_NUMBER='(0,0,0,0,0,0,0,0,0,0,0,0,0,0,0,0,0,0,0,0,CL12,0,0,0,0,0,0,0,0,0)';
      PINUSE='POWER';
      NO_LOAD_CHECK='Both';
      NO_IO_CHECK='Both';
      NO_ASSERT_CHECK='TRUE';
      NO_DIR_CHECK='TRUE';
      ALLOW_CONNECT='TRUE';
    'VCCIO'<20>:
      PIN_NUMBER='(0,0,0,0,0,0,0,0,0,0,0,0,0,0,0,0,0,0,0,0,CM15,0,0,0,0,0,0,0,0,0)';
      PINUSE='POWER';
      NO_LOAD_CHECK='Both';
      NO_IO_CHECK='Both';
      NO_ASSERT_CHECK='TRUE';
      NO_DIR_CHECK='TRUE';
      ALLOW_CONNECT='TRUE';
    'VCCIO'<19>:
      PIN_NUMBER='(0,0,0,0,0,0,0,0,0,0,0,0,0,0,0,0,0,0,0,0,0,CN6,0,0,0,0,0,0,0,0)';
      PINUSE='POWER';
      NO_LOAD_CHECK='Both';
      NO_IO_CHECK='Both';
      NO_ASSERT_CHECK='TRUE';
      NO_DIR_CHECK='TRUE';
      ALLOW_CONNECT='TRUE';
    'VCCIO'<18>:
      PIN_NUMBER='(0,0,0,0,0,0,0,0,0,0,0,0,0,0,0,0,0,0,0,0,0,CU12,0,0,0,0,0,0,0,0)';
      PINUSE='POWER';
      NO_LOAD_CHECK='Both';
      NO_IO_CHECK='Both';
      NO_ASSERT_CHECK='TRUE';
      NO_DIR_CHECK='TRUE';
      ALLOW_CONNECT='TRUE';
    'VCCIO'<17>:
      PIN_NUMBER='(0,0,0,0,0,0,0,0,0,0,0,0,0,0,0,0,0,0,0,0,0,CV21,0,0,0,0,0,0,0,0)';
      PINUSE='POWER';
      NO_LOAD_CHECK='Both';
      NO_IO_CHECK='Both';
      NO_ASSERT_CHECK='TRUE';
      NO_DIR_CHECK='TRUE';
      ALLOW_CONNECT='TRUE';
    'VCCIO'<16>:
      PIN_NUMBER='(0,0,0,0,0,0,0,0,0,0,0,0,0,0,0,0,0,0,0,0,0,CU18,0,0,0,0,0,0,0,0)';
      PINUSE='POWER';
      NO_LOAD_CHECK='Both';
      NO_IO_CHECK='Both';
      NO_ASSERT_CHECK='TRUE';
      NO_DIR_CHECK='TRUE';
      ALLOW_CONNECT='TRUE';
    'VCCIO'<15>:
      PIN_NUMBER='(0,0,0,0,0,0,0,0,0,0,0,0,0,0,0,0,0,0,0,0,0,CY17,0,0,0,0,0,0,0,0)';
      PINUSE='POWER';
      NO_LOAD_CHECK='Both';
      NO_IO_CHECK='Both';
      NO_ASSERT_CHECK='TRUE';
      NO_DIR_CHECK='TRUE';
      ALLOW_CONNECT='TRUE';
    'VCCIO'<14>:
      PIN_NUMBER='(0,0,0,0,0,0,0,0,0,0,0,0,0,0,0,0,0,0,0,0,0,DC18,0,0,0,0,0,0,0,0)';
      PINUSE='POWER';
      NO_LOAD_CHECK='Both';
      NO_IO_CHECK='Both';
      NO_ASSERT_CHECK='TRUE';
      NO_DIR_CHECK='TRUE';
      ALLOW_CONNECT='TRUE';
    'VCCIO'<13>:
      PIN_NUMBER='(0,0,0,0,0,0,0,0,0,0,0,0,0,0,0,0,0,0,0,0,0,DE14,0,0,0,0,0,0,0,0)';
      PINUSE='POWER';
      NO_LOAD_CHECK='Both';
      NO_IO_CHECK='Both';
      NO_ASSERT_CHECK='TRUE';
      NO_DIR_CHECK='TRUE';
      ALLOW_CONNECT='TRUE';
    'VCCIO'<12>:
      PIN_NUMBER='(0,0,0,0,0,0,0,0,0,0,0,0,0,0,0,0,0,0,0,0,0,CP13,0,0,0,0,0,0,0,0)';
      PINUSE='POWER';
      NO_LOAD_CHECK='Both';
      NO_IO_CHECK='Both';
      NO_ASSERT_CHECK='TRUE';
      NO_DIR_CHECK='TRUE';
      ALLOW_CONNECT='TRUE';
    'VCCIO'<11>:
      PIN_NUMBER='(0,0,0,0,0,0,0,0,0,0,0,0,0,0,0,0,0,0,0,0,0,CL20,0,0,0,0,0,0,0,0)';
      PINUSE='POWER';
      NO_LOAD_CHECK='Both';
      NO_IO_CHECK='Both';
      NO_ASSERT_CHECK='TRUE';
      NO_DIR_CHECK='TRUE';
      ALLOW_CONNECT='TRUE';
    'VCCIO'<10>:
      PIN_NUMBER='(0,0,0,0,0,0,0,0,0,0,0,0,0,0,0,0,0,0,0,0,0,CG14,0,0,0,0,0,0,0,0)';
      PINUSE='POWER';
      NO_LOAD_CHECK='Both';
      NO_IO_CHECK='Both';
      NO_ASSERT_CHECK='TRUE';
      NO_DIR_CHECK='TRUE';
      ALLOW_CONNECT='TRUE';
    'VCCIO'<9>:
      PIN_NUMBER='(0,0,0,0,0,0,0,0,0,0,0,0,0,0,0,0,0,0,0,0,0,CF5,0,0,0,0,0,0,0,0)';
      PINUSE='POWER';
      NO_LOAD_CHECK='Both';
      NO_IO_CHECK='Both';
      NO_ASSERT_CHECK='TRUE';
      NO_DIR_CHECK='TRUE';
      ALLOW_CONNECT='TRUE';
    'VCCIO'<8>:
      PIN_NUMBER='(0,0,0,0,0,0,0,0,0,0,0,0,0,0,0,0,0,0,0,0,0,DK21,0,0,0,0,0,0,0,0)';
      PINUSE='POWER';
      NO_LOAD_CHECK='Both';
      NO_IO_CHECK='Both';
      NO_ASSERT_CHECK='TRUE';
      NO_DIR_CHECK='TRUE';
      ALLOW_CONNECT='TRUE';
    'VCCIO'<7>:
      PIN_NUMBER='(0,0,0,0,0,0,0,0,0,0,0,0,0,0,0,0,0,0,0,0,0,BE24,0,0,0,0,0,0,0,0)';
      PINUSE='POWER';
      NO_LOAD_CHECK='Both';
      NO_IO_CHECK='Both';
      NO_ASSERT_CHECK='TRUE';
      NO_DIR_CHECK='TRUE';
      ALLOW_CONNECT='TRUE';
    'VCCIO'<6>:
      PIN_NUMBER='(0,0,0,0,0,0,0,0,0,0,0,0,0,0,0,0,0,0,0,0,0,AT7,0,0,0,0,0,0,0,0)';
      PINUSE='POWER';
      NO_LOAD_CHECK='Both';
      NO_IO_CHECK='Both';
      NO_ASSERT_CHECK='TRUE';
      NO_DIR_CHECK='TRUE';
      ALLOW_CONNECT='TRUE';
    'VCCIO'<5>:
      PIN_NUMBER='(0,0,0,0,0,0,0,0,0,0,0,0,0,0,0,0,0,0,0,0,0,AT5,0,0,0,0,0,0,0,0)';
      PINUSE='POWER';
      NO_LOAD_CHECK='Both';
      NO_IO_CHECK='Both';
      NO_ASSERT_CHECK='TRUE';
      NO_DIR_CHECK='TRUE';
      ALLOW_CONNECT='TRUE';
    'VCCIO'<4>:
      PIN_NUMBER='(0,0,0,0,0,0,0,0,0,0,0,0,0,0,0,0,0,0,0,0,0,AM5,0,0,0,0,0,0,0,0)';
      PINUSE='POWER';
      NO_LOAD_CHECK='Both';
      NO_IO_CHECK='Both';
      NO_ASSERT_CHECK='TRUE';
      NO_DIR_CHECK='TRUE';
      ALLOW_CONNECT='TRUE';
    'VCCIO'<3>:
      PIN_NUMBER='(0,0,0,0,0,0,0,0,0,0,0,0,0,0,0,0,0,0,0,0,0,DV11,0,0,0,0,0,0,0,0)';
      PINUSE='POWER';
      NO_LOAD_CHECK='Both';
      NO_IO_CHECK='Both';
      NO_ASSERT_CHECK='TRUE';
      NO_DIR_CHECK='TRUE';
      ALLOW_CONNECT='TRUE';
    'VCCIO'<2>:
      PIN_NUMBER='(0,0,0,0,0,0,0,0,0,0,0,0,0,0,0,0,0,0,0,0,0,AF5,0,0,0,0,0,0,0,0)';
      PINUSE='POWER';
      NO_LOAD_CHECK='Both';
      NO_IO_CHECK='Both';
      NO_ASSERT_CHECK='TRUE';
      NO_DIR_CHECK='TRUE';
      ALLOW_CONNECT='TRUE';
    'VCCIO'<1>:
      PIN_NUMBER='(0,0,0,0,0,0,0,0,0,0,0,0,0,0,0,0,0,0,0,0,0,AE10,0,0,0,0,0,0,0,0)';
      PINUSE='POWER';
      NO_LOAD_CHECK='Both';
      NO_IO_CHECK='Both';
      NO_ASSERT_CHECK='TRUE';
      NO_DIR_CHECK='TRUE';
      ALLOW_CONNECT='TRUE';
    'VCCIO'<0>:
      PIN_NUMBER='(0,0,0,0,0,0,0,0,0,0,0,0,0,0,0,0,0,0,0,0,0,EE10,0,0,0,0,0,0,0,0)';
      PINUSE='POWER';
      NO_LOAD_CHECK='Both';
      NO_IO_CHECK='Both';
      NO_ASSERT_CHECK='TRUE';
      NO_DIR_CHECK='TRUE';
      ALLOW_CONNECT='TRUE';
    'VCCIO_SENSE':
      PIN_NUMBER='(0,0,0,0,0,0,0,0,0,0,0,0,0,0,0,0,0,0,0,0,0,BH5,0,0,0,0,0,0,0,0)';
      PINUSE='POWER';
      NO_LOAD_CHECK='Both';
      NO_IO_CHECK='Both';
      NO_ASSERT_CHECK='TRUE';
      NO_DIR_CHECK='TRUE';
      ALLOW_CONNECT='TRUE';
    'VCCSA'<25>:
      PIN_NUMBER='(0,0,0,0,0,0,0,0,0,0,0,0,0,0,0,0,0,0,0,0,CB65,0,0,0,0,0,0,0,0,0)';
      PINUSE='POWER';
      NO_LOAD_CHECK='Both';
      NO_IO_CHECK='Both';
      NO_ASSERT_CHECK='TRUE';
      NO_DIR_CHECK='TRUE';
      ALLOW_CONNECT='TRUE';
    'VCCSA'<24>:
      PIN_NUMBER='(0,0,0,0,0,0,0,0,0,0,0,0,0,0,0,0,0,0,0,0,CB67,0,0,0,0,0,0,0,0,0)';
      PINUSE='POWER';
      NO_LOAD_CHECK='Both';
      NO_IO_CHECK='Both';
      NO_ASSERT_CHECK='TRUE';
      NO_DIR_CHECK='TRUE';
      ALLOW_CONNECT='TRUE';
    'VCCSA'<23>:
      PIN_NUMBER='(0,0,0,0,0,0,0,0,0,0,0,0,0,0,0,0,0,0,0,0,CB69,0,0,0,0,0,0,0,0,0)';
      PINUSE='POWER';
      NO_LOAD_CHECK='Both';
      NO_IO_CHECK='Both';
      NO_ASSERT_CHECK='TRUE';
      NO_DIR_CHECK='TRUE';
      ALLOW_CONNECT='TRUE';
    'VCCSA'<22>:
      PIN_NUMBER='(0,0,0,0,0,0,0,0,0,0,0,0,0,0,0,0,0,0,0,0,CC66,0,0,0,0,0,0,0,0,0)';
      PINUSE='POWER';
      NO_LOAD_CHECK='Both';
      NO_IO_CHECK='Both';
      NO_ASSERT_CHECK='TRUE';
      NO_DIR_CHECK='TRUE';
      ALLOW_CONNECT='TRUE';
    'VCCSA'<21>:
      PIN_NUMBER='(0,0,0,0,0,0,0,0,0,0,0,0,0,0,0,0,0,0,0,0,CC68,0,0,0,0,0,0,0,0,0)';
      PINUSE='POWER';
      NO_LOAD_CHECK='Both';
      NO_IO_CHECK='Both';
      NO_ASSERT_CHECK='TRUE';
      NO_DIR_CHECK='TRUE';
      ALLOW_CONNECT='TRUE';
    'VCCSA'<20>:
      PIN_NUMBER='(0,0,0,0,0,0,0,0,0,0,0,0,0,0,0,0,0,0,0,0,CC70,0,0,0,0,0,0,0,0,0)';
      PINUSE='POWER';
      NO_LOAD_CHECK='Both';
      NO_IO_CHECK='Both';
      NO_ASSERT_CHECK='TRUE';
      NO_DIR_CHECK='TRUE';
      ALLOW_CONNECT='TRUE';
    'VCCSA'<19>:
      PIN_NUMBER='(0,0,0,0,0,0,0,0,0,0,0,0,0,0,0,0,0,0,0,0,CD65,0,0,0,0,0,0,0,0,0)';
      PINUSE='POWER';
      NO_LOAD_CHECK='Both';
      NO_IO_CHECK='Both';
      NO_ASSERT_CHECK='TRUE';
      NO_DIR_CHECK='TRUE';
      ALLOW_CONNECT='TRUE';
    'VCCSA'<18>:
      PIN_NUMBER='(0,0,0,0,0,0,0,0,0,0,0,0,0,0,0,0,0,0,0,0,CD67,0,0,0,0,0,0,0,0,0)';
      PINUSE='POWER';
      NO_LOAD_CHECK='Both';
      NO_IO_CHECK='Both';
      NO_ASSERT_CHECK='TRUE';
      NO_DIR_CHECK='TRUE';
      ALLOW_CONNECT='TRUE';
    'VCCSA'<17>:
      PIN_NUMBER='(0,0,0,0,0,0,0,0,0,0,0,0,0,0,0,0,0,0,0,0,CD69,0,0,0,0,0,0,0,0,0)';
      PINUSE='POWER';
      NO_LOAD_CHECK='Both';
      NO_IO_CHECK='Both';
      NO_ASSERT_CHECK='TRUE';
      NO_DIR_CHECK='TRUE';
      ALLOW_CONNECT='TRUE';
    'VCCSA'<16>:
      PIN_NUMBER='(0,0,0,0,0,0,0,0,0,0,0,0,0,0,0,0,0,0,0,0,CD71,0,0,0,0,0,0,0,0,0)';
      PINUSE='POWER';
      NO_LOAD_CHECK='Both';
      NO_IO_CHECK='Both';
      NO_ASSERT_CHECK='TRUE';
      NO_DIR_CHECK='TRUE';
      ALLOW_CONNECT='TRUE';
    'VCCSA'<15>:
      PIN_NUMBER='(0,0,0,0,0,0,0,0,0,0,0,0,0,0,0,0,0,0,0,0,CE64,0,0,0,0,0,0,0,0,0)';
      PINUSE='POWER';
      NO_LOAD_CHECK='Both';
      NO_IO_CHECK='Both';
      NO_ASSERT_CHECK='TRUE';
      NO_DIR_CHECK='TRUE';
      ALLOW_CONNECT='TRUE';
    'VCCSA'<14>:
      PIN_NUMBER='(0,0,0,0,0,0,0,0,0,0,0,0,0,0,0,0,0,0,0,0,CE66,0,0,0,0,0,0,0,0,0)';
      PINUSE='POWER';
      NO_LOAD_CHECK='Both';
      NO_IO_CHECK='Both';
      NO_ASSERT_CHECK='TRUE';
      NO_DIR_CHECK='TRUE';
      ALLOW_CONNECT='TRUE';
    'VCCSA'<13>:
      PIN_NUMBER='(0,0,0,0,0,0,0,0,0,0,0,0,0,0,0,0,0,0,0,0,CE68,0,0,0,0,0,0,0,0,0)';
      PINUSE='POWER';
      NO_LOAD_CHECK='Both';
      NO_IO_CHECK='Both';
      NO_ASSERT_CHECK='TRUE';
      NO_DIR_CHECK='TRUE';
      ALLOW_CONNECT='TRUE';
    'VCCSA'<12>:
      PIN_NUMBER='(0,0,0,0,0,0,0,0,0,0,0,0,0,0,0,0,0,0,0,0,CE72,0,0,0,0,0,0,0,0,0)';
      PINUSE='POWER';
      NO_LOAD_CHECK='Both';
      NO_IO_CHECK='Both';
      NO_ASSERT_CHECK='TRUE';
      NO_DIR_CHECK='TRUE';
      ALLOW_CONNECT='TRUE';
    'VCCSA'<11>:
      PIN_NUMBER='(0,0,0,0,0,0,0,0,0,0,0,0,0,0,0,0,0,0,0,0,CE74,0,0,0,0,0,0,0,0,0)';
      PINUSE='POWER';
      NO_LOAD_CHECK='Both';
      NO_IO_CHECK='Both';
      NO_ASSERT_CHECK='TRUE';
      NO_DIR_CHECK='TRUE';
      ALLOW_CONNECT='TRUE';
    'VCCSA'<10>:
      PIN_NUMBER='(0,0,0,0,0,0,0,0,0,0,0,0,0,0,0,0,0,0,0,0,CF65,0,0,0,0,0,0,0,0,0)';
      PINUSE='POWER';
      NO_LOAD_CHECK='Both';
      NO_IO_CHECK='Both';
      NO_ASSERT_CHECK='TRUE';
      NO_DIR_CHECK='TRUE';
      ALLOW_CONNECT='TRUE';
    'VCCSA'<9>:
      PIN_NUMBER='(0,0,0,0,0,0,0,0,0,0,0,0,0,0,0,0,0,0,0,0,CF67,0,0,0,0,0,0,0,0,0)';
      PINUSE='POWER';
      NO_LOAD_CHECK='Both';
      NO_IO_CHECK='Both';
      NO_ASSERT_CHECK='TRUE';
      NO_DIR_CHECK='TRUE';
      ALLOW_CONNECT='TRUE';
    'VCCSA'<8>:
      PIN_NUMBER='(0,0,0,0,0,0,0,0,0,0,0,0,0,0,0,0,0,0,0,0,CF73,0,0,0,0,0,0,0,0,0)';
      PINUSE='POWER';
      NO_LOAD_CHECK='Both';
      NO_IO_CHECK='Both';
      NO_ASSERT_CHECK='TRUE';
      NO_DIR_CHECK='TRUE';
      ALLOW_CONNECT='TRUE';
    'VCCSA'<7>:
      PIN_NUMBER='(0,0,0,0,0,0,0,0,0,0,0,0,0,0,0,0,0,0,0,0,CF75,0,0,0,0,0,0,0,0,0)';
      PINUSE='POWER';
      NO_LOAD_CHECK='Both';
      NO_IO_CHECK='Both';
      NO_ASSERT_CHECK='TRUE';
      NO_DIR_CHECK='TRUE';
      ALLOW_CONNECT='TRUE';
    'VCCSA'<6>:
      PIN_NUMBER='(0,0,0,0,0,0,0,0,0,0,0,0,0,0,0,0,0,0,0,0,CG64,0,0,0,0,0,0,0,0,0)';
      PINUSE='POWER';
      NO_LOAD_CHECK='Both';
      NO_IO_CHECK='Both';
      NO_ASSERT_CHECK='TRUE';
      NO_DIR_CHECK='TRUE';
      ALLOW_CONNECT='TRUE';
    'VCCSA'<5>:
      PIN_NUMBER='(0,0,0,0,0,0,0,0,0,0,0,0,0,0,0,0,0,0,0,0,CG66,0,0,0,0,0,0,0,0,0)';
      PINUSE='POWER';
      NO_LOAD_CHECK='Both';
      NO_IO_CHECK='Both';
      NO_ASSERT_CHECK='TRUE';
      NO_DIR_CHECK='TRUE';
      ALLOW_CONNECT='TRUE';
    'VCCSA'<4>:
      PIN_NUMBER='(0,0,0,0,0,0,0,0,0,0,0,0,0,0,0,0,0,0,0,0,CG74,0,0,0,0,0,0,0,0,0)';
      PINUSE='POWER';
      NO_LOAD_CHECK='Both';
      NO_IO_CHECK='Both';
      NO_ASSERT_CHECK='TRUE';
      NO_DIR_CHECK='TRUE';
      ALLOW_CONNECT='TRUE';
    'VCCSA'<3>:
      PIN_NUMBER='(0,0,0,0,0,0,0,0,0,0,0,0,0,0,0,0,0,0,0,0,CH65,0,0,0,0,0,0,0,0,0)';
      PINUSE='POWER';
      NO_LOAD_CHECK='Both';
      NO_IO_CHECK='Both';
      NO_ASSERT_CHECK='TRUE';
      NO_DIR_CHECK='TRUE';
      ALLOW_CONNECT='TRUE';
    'VCCSA'<2>:
      PIN_NUMBER='(0,0,0,0,0,0,0,0,0,0,0,0,0,0,0,0,0,0,0,0,CH75,0,0,0,0,0,0,0,0,0)';
      PINUSE='POWER';
      NO_LOAD_CHECK='Both';
      NO_IO_CHECK='Both';
      NO_ASSERT_CHECK='TRUE';
      NO_DIR_CHECK='TRUE';
      ALLOW_CONNECT='TRUE';
    'VCCSA'<1>:
      PIN_NUMBER='(0,0,0,0,0,0,0,0,0,0,0,0,0,0,0,0,0,0,0,0,CJ64,0,0,0,0,0,0,0,0,0)';
      PINUSE='POWER';
      NO_LOAD_CHECK='Both';
      NO_IO_CHECK='Both';
      NO_ASSERT_CHECK='TRUE';
      NO_DIR_CHECK='TRUE';
      ALLOW_CONNECT='TRUE';
    'VCCSA'<0>:
      PIN_NUMBER='(0,0,0,0,0,0,0,0,0,0,0,0,0,0,0,0,0,0,0,0,CJ66,0,0,0,0,0,0,0,0,0)';
      PINUSE='POWER';
      NO_LOAD_CHECK='Both';
      NO_IO_CHECK='Both';
      NO_ASSERT_CHECK='TRUE';
      NO_DIR_CHECK='TRUE';
      ALLOW_CONNECT='TRUE';
    'VCCSA_SENSE':
      PIN_NUMBER='(0,0,0,0,0,0,0,0,0,0,0,0,0,0,0,0,0,0,0,0,0,CE76,0,0,0,0,0,0,0,0)';
      PINUSE='POWER';
      NO_LOAD_CHECK='Both';
      NO_IO_CHECK='Both';
      NO_ASSERT_CHECK='TRUE';
      NO_DIR_CHECK='TRUE';
      ALLOW_CONNECT='TRUE';
    'VSENSEPMAX':
      PIN_NUMBER='(0,0,0,0,0,0,0,0,0,0,0,0,0,0,0,0,0,0,AD41,0,0,0,0,0,0,0,0,0,0,0)';
      PINUSE='POWER';
      NO_LOAD_CHECK='Both';
      NO_IO_CHECK='Both';
      NO_ASSERT_CHECK='TRUE';
      NO_DIR_CHECK='TRUE';
      ALLOW_CONNECT='TRUE';
    'VSS'<1253>:
      PIN_NUMBER='(0,0,0,0,0,0,0,0,0,0,0,0,0,0,0,0,0,0,0,0,0,0,B9,0,0,0,0,0,0,0)';
      PINUSE='GROUND';
      NO_LOAD_CHECK='Both';
      NO_IO_CHECK='Both';
      NO_ASSERT_CHECK='TRUE';
      NO_DIR_CHECK='TRUE';
      ALLOW_CONNECT='TRUE';
    'VSS'<1252>:
      PIN_NUMBER='(0,0,0,0,0,0,0,0,0,0,0,0,0,0,0,0,0,0,0,0,0,0,A42,0,0,0,0,0,0,0)';
      PINUSE='GROUND';
      NO_LOAD_CHECK='Both';
      NO_IO_CHECK='Both';
      NO_ASSERT_CHECK='TRUE';
      NO_DIR_CHECK='TRUE';
      ALLOW_CONNECT='TRUE';
    'VSS'<1251>:
      PIN_NUMBER='(0,0,0,0,0,0,0,0,0,0,0,0,0,0,0,0,0,0,0,0,0,0,B43,0,0,0,0,0,0,0)';
      PINUSE='GROUND';
      NO_LOAD_CHECK='Both';
      NO_IO_CHECK='Both';
      NO_ASSERT_CHECK='TRUE';
      NO_DIR_CHECK='TRUE';
      ALLOW_CONNECT='TRUE';
    'VSS'<1250>:
      PIN_NUMBER='(0,0,0,0,0,0,0,0,0,0,0,0,0,0,0,0,0,0,0,0,0,0,B5,0,0,0,0,0,0,0)';
      PINUSE='GROUND';
      NO_LOAD_CHECK='Both';
      NO_IO_CHECK='Both';
      NO_ASSERT_CHECK='TRUE';
      NO_DIR_CHECK='TRUE';
      ALLOW_CONNECT='TRUE';
    'VSS'<1249>:
      PIN_NUMBER='(0,0,0,0,0,0,0,0,0,0,0,0,0,0,0,0,0,0,0,0,0,0,B79,0,0,0,0,0,0,0)';
      PINUSE='GROUND';
      NO_LOAD_CHECK='Both';
      NO_IO_CHECK='Both';
      NO_ASSERT_CHECK='TRUE';
      NO_DIR_CHECK='TRUE';
      ALLOW_CONNECT='TRUE';
    'VSS'<1248>:
      PIN_NUMBER='(0,0,0,0,0,0,0,0,0,0,0,0,0,0,0,0,0,0,0,0,0,0,C4,0,0,0,0,0,0,0)';
      PINUSE='GROUND';
      NO_LOAD_CHECK='Both';
      NO_IO_CHECK='Both';
      NO_ASSERT_CHECK='TRUE';
      NO_DIR_CHECK='TRUE';
      ALLOW_CONNECT='TRUE';
    'VSS'<1247>:
      PIN_NUMBER='(0,0,0,0,0,0,0,0,0,0,0,0,0,0,0,0,0,0,0,0,0,0,C80,0,0,0,0,0,0,0)';
      PINUSE='GROUND';
      NO_LOAD_CHECK='Both';
      NO_IO_CHECK='Both';
      NO_ASSERT_CHECK='TRUE';
      NO_DIR_CHECK='TRUE';
      ALLOW_CONNECT='TRUE';
    'VSS'<1246>:
      PIN_NUMBER='(0,0,0,0,0,0,0,0,0,0,0,0,0,0,0,0,0,0,0,0,0,0,D3,0,0,0,0,0,0,0)';
      PINUSE='GROUND';
      NO_LOAD_CHECK='Both';
      NO_IO_CHECK='Both';
      NO_ASSERT_CHECK='TRUE';
      NO_DIR_CHECK='TRUE';
      ALLOW_CONNECT='TRUE';
    'VSS'<1245>:
      PIN_NUMBER='(0,0,0,0,0,0,0,0,0,0,0,0,0,0,0,0,0,0,0,0,0,0,D81,0,0,0,0,0,0,0)';
      PINUSE='GROUND';
      NO_LOAD_CHECK='Both';
      NO_IO_CHECK='Both';
      NO_ASSERT_CHECK='TRUE';
      NO_DIR_CHECK='TRUE';
      ALLOW_CONNECT='TRUE';
    'VSS'<1244>:
      PIN_NUMBER='(0,0,0,0,0,0,0,0,0,0,0,0,0,0,0,0,0,0,0,0,0,0,E82,0,0,0,0,0,0,0)';
      PINUSE='GROUND';
      NO_LOAD_CHECK='Both';
      NO_IO_CHECK='Both';
      NO_ASSERT_CHECK='TRUE';
      NO_DIR_CHECK='TRUE';
      ALLOW_CONNECT='TRUE';
    'VSS'<1243>:
      PIN_NUMBER='(0,0,0,0,0,0,0,0,0,0,0,0,0,0,0,0,0,0,0,0,0,0,J86,0,0,0,0,0,0,0)';
      PINUSE='GROUND';
      NO_LOAD_CHECK='Both';
      NO_IO_CHECK='Both';
      NO_ASSERT_CHECK='TRUE';
      NO_DIR_CHECK='TRUE';
      ALLOW_CONNECT='TRUE';
    'VSS'<1242>:
      PIN_NUMBER='(0,0,0,0,0,0,0,0,0,0,0,0,0,0,0,0,0,0,0,0,0,0,DY85,0,0,0,0,0,0,0)';
      PINUSE='GROUND';
      NO_LOAD_CHECK='Both';
      NO_IO_CHECK='Both';
      NO_ASSERT_CHECK='TRUE';
      NO_DIR_CHECK='TRUE';
      ALLOW_CONNECT='TRUE';
    'VSS'<1241>:
      PIN_NUMBER='(0,0,0,0,0,0,0,0,0,0,0,0,0,0,0,0,0,0,0,0,0,0,EA84,0,0,0,0,0,0,0)';
      PINUSE='GROUND';
      NO_LOAD_CHECK='Both';
      NO_IO_CHECK='Both';
      NO_ASSERT_CHECK='TRUE';
      NO_DIR_CHECK='TRUE';
      ALLOW_CONNECT='TRUE';
    'VSS'<1240>:
      PIN_NUMBER='(0,0,0,0,0,0,0,0,0,0,0,0,0,0,0,0,0,0,0,0,0,0,EB83,0,0,0,0,0,0,0)';
      PINUSE='GROUND';
      NO_LOAD_CHECK='Both';
      NO_IO_CHECK='Both';
      NO_ASSERT_CHECK='TRUE';
      NO_DIR_CHECK='TRUE';
      ALLOW_CONNECT='TRUE';
    'VSS'<1239>:
      PIN_NUMBER='(0,0,0,0,0,0,0,0,0,0,0,0,0,0,0,0,0,0,0,0,0,0,DW2,0,0,0,0,0,0,0)';
      PINUSE='GROUND';
      NO_LOAD_CHECK='Both';
      NO_IO_CHECK='Both';
      NO_ASSERT_CHECK='TRUE';
      NO_DIR_CHECK='TRUE';
      ALLOW_CONNECT='TRUE';
    'VSS'<1238>:
      PIN_NUMBER='(0,0,0,0,0,0,0,0,0,0,0,0,0,0,0,0,0,0,0,0,0,0,EC42,0,0,0,0,0,0,0)';
      PINUSE='GROUND';
      NO_LOAD_CHECK='Both';
      NO_IO_CHECK='Both';
      NO_ASSERT_CHECK='TRUE';
      NO_DIR_CHECK='TRUE';
      ALLOW_CONNECT='TRUE';
    'VSS'<1237>:
      PIN_NUMBER='(0,0,0,0,0,0,0,0,0,0,0,0,0,0,0,0,0,0,0,0,0,0,EC6,0,0,0,0,0,0,0)';
      PINUSE='GROUND';
      NO_LOAD_CHECK='Both';
      NO_IO_CHECK='Both';
      NO_ASSERT_CHECK='TRUE';
      NO_DIR_CHECK='TRUE';
      ALLOW_CONNECT='TRUE';
    'VSS'<1236>:
      PIN_NUMBER='(0,0,0,0,0,0,0,0,0,0,0,0,0,0,0,0,0,0,0,0,0,0,EC82,0,0,0,0,0,0,0)';
      PINUSE='GROUND';
      NO_LOAD_CHECK='Both';
      NO_IO_CHECK='Both';
      NO_ASSERT_CHECK='TRUE';
      NO_DIR_CHECK='TRUE';
      ALLOW_CONNECT='TRUE';
    'VSS'<1235>:
      PIN_NUMBER='(0,0,0,0,0,0,0,0,0,0,0,0,0,0,0,0,0,0,0,0,0,0,ED41,0,0,0,0,0,0,0)';
      PINUSE='GROUND';
      NO_LOAD_CHECK='Both';
      NO_IO_CHECK='Both';
      NO_ASSERT_CHECK='TRUE';
      NO_DIR_CHECK='TRUE';
      ALLOW_CONNECT='TRUE';
    'VSS'<1234>:
      PIN_NUMBER='(0,0,0,0,0,0,0,0,0,0,0,0,0,0,0,0,0,0,0,0,0,0,ED7,0,0,0,0,0,0,0)';
      PINUSE='GROUND';
      NO_LOAD_CHECK='Both';
      NO_IO_CHECK='Both';
      NO_ASSERT_CHECK='TRUE';
      NO_DIR_CHECK='TRUE';
      ALLOW_CONNECT='TRUE';
    'VSS'<1233>:
      PIN_NUMBER='(0,0,0,0,0,0,0,0,0,0,0,0,0,0,0,0,0,0,0,0,0,0,ED81,0,0,0,0,0,0,0)';
      PINUSE='GROUND';
      NO_LOAD_CHECK='Both';
      NO_IO_CHECK='Both';
      NO_ASSERT_CHECK='TRUE';
      NO_DIR_CHECK='TRUE';
      ALLOW_CONNECT='TRUE';
    'VSS'<1232>:
      PIN_NUMBER='(0,0,0,0,0,0,0,0,0,0,0,0,0,0,0,0,0,0,0,0,0,0,EE40,0,0,0,0,0,0,0)';
      PINUSE='GROUND';
      NO_LOAD_CHECK='Both';
      NO_IO_CHECK='Both';
      NO_ASSERT_CHECK='TRUE';
      NO_DIR_CHECK='TRUE';
      ALLOW_CONNECT='TRUE';
    'VSS'<1231>:
      PIN_NUMBER='(0,0,0,0,0,0,0,0,0,0,0,0,0,0,0,0,0,0,0,0,0,0,EE8,0,0,0,0,0,0,0)';
      PINUSE='GROUND';
      NO_LOAD_CHECK='Both';
      NO_IO_CHECK='Both';
      NO_ASSERT_CHECK='TRUE';
      NO_DIR_CHECK='TRUE';
      ALLOW_CONNECT='TRUE';
    'VSS'<1230>:
      PIN_NUMBER='(0,0,0,0,0,0,0,0,0,0,0,0,0,0,0,0,0,0,0,0,0,0,EE80,0,0,0,0,0,0,0)';
      PINUSE='GROUND';
      NO_LOAD_CHECK='Both';
      NO_IO_CHECK='Both';
      NO_ASSERT_CHECK='TRUE';
      NO_DIR_CHECK='TRUE';
      ALLOW_CONNECT='TRUE';
    'VSS'<1229>:
      PIN_NUMBER='(0,0,0,0,0,0,0,0,0,0,0,0,0,0,0,0,0,0,0,0,0,0,ED69,0,0,0,0,0,0,0)';
      PINUSE='GROUND';
      NO_LOAD_CHECK='Both';
      NO_IO_CHECK='Both';
      NO_ASSERT_CHECK='TRUE';
      NO_DIR_CHECK='TRUE';
      ALLOW_CONNECT='TRUE';
    'VSS'<1228>:
      PIN_NUMBER='(0,0,0,0,0,0,0,0,0,0,0,0,0,0,0,0,0,0,0,0,0,0,E66,0,0,0,0,0,0,0)';
      PINUSE='GROUND';
      NO_LOAD_CHECK='Both';
      NO_IO_CHECK='Both';
      NO_ASSERT_CHECK='TRUE';
      NO_DIR_CHECK='TRUE';
      ALLOW_CONNECT='TRUE';
    'VSS'<1227>:
      PIN_NUMBER='(0,0,0,0,0,0,0,0,0,0,0,0,0,0,0,0,0,0,0,0,0,0,V11,0,0,0,0,0,0,0)';
      PINUSE='GROUND';
      NO_LOAD_CHECK='Both';
      NO_IO_CHECK='Both';
      NO_ASSERT_CHECK='TRUE';
      NO_DIR_CHECK='TRUE';
      ALLOW_CONNECT='TRUE';
    'VSS'<1226>:
      PIN_NUMBER='(0,0,0,0,0,0,0,0,0,0,0,0,0,0,0,0,0,0,0,0,0,0,L8,0,0,0,0,0,0,0)';
      PINUSE='GROUND';
      NO_LOAD_CHECK='Both';
      NO_IO_CHECK='Both';
      NO_ASSERT_CHECK='TRUE';
      NO_DIR_CHECK='TRUE';
      ALLOW_CONNECT='TRUE';
    'VSS'<1225>:
      PIN_NUMBER='(0,0,0,0,0,0,0,0,0,0,0,0,0,0,0,0,0,0,0,0,0,0,EA14,0,0,0,0,0,0,0)';
      PINUSE='GROUND';
      NO_LOAD_CHECK='Both';
      NO_IO_CHECK='Both';
      NO_ASSERT_CHECK='TRUE';
      NO_DIR_CHECK='TRUE';
      ALLOW_CONNECT='TRUE';
    'VSS'<1224>:
      PIN_NUMBER='(0,0,0,0,0,0,0,0,0,0,0,0,0,0,0,0,0,0,0,0,0,0,DY63,0,0,0,0,0,0,0)';
      PINUSE='GROUND';
      NO_LOAD_CHECK='Both';
      NO_IO_CHECK='Both';
      NO_ASSERT_CHECK='TRUE';
      NO_DIR_CHECK='TRUE';
      ALLOW_CONNECT='TRUE';
    'VSS'<1223>:
      PIN_NUMBER='(0,0,0,0,0,0,0,0,0,0,0,0,0,0,0,0,0,0,0,0,0,0,DY61,0,0,0,0,0,0,0)';
      PINUSE='GROUND';
      NO_LOAD_CHECK='Both';
      NO_IO_CHECK='Both';
      NO_ASSERT_CHECK='TRUE';
      NO_DIR_CHECK='TRUE';
      ALLOW_CONNECT='TRUE';
    'VSS'<1222>:
      PIN_NUMBER='(0,0,0,0,0,0,0,0,0,0,0,0,0,0,0,0,0,0,0,0,0,0,DY59,0,0,0,0,0,0,0)';
      PINUSE='GROUND';
      NO_LOAD_CHECK='Both';
      NO_IO_CHECK='Both';
      NO_ASSERT_CHECK='TRUE';
      NO_DIR_CHECK='TRUE';
      ALLOW_CONNECT='TRUE';
    'VSS'<1221>:
      PIN_NUMBER='(0,0,0,0,0,0,0,0,0,0,0,0,0,0,0,0,0,0,0,0,0,0,DY57,0,0,0,0,0,0,0)';
      PINUSE='GROUND';
      NO_LOAD_CHECK='Both';
      NO_IO_CHECK='Both';
      NO_ASSERT_CHECK='TRUE';
      NO_DIR_CHECK='TRUE';
      ALLOW_CONNECT='TRUE';
    'VSS'<1220>:
      PIN_NUMBER='(0,0,0,0,0,0,0,0,0,0,0,0,0,0,0,0,0,0,0,0,0,0,DY55,0,0,0,0,0,0,0)';
      PINUSE='GROUND';
      NO_LOAD_CHECK='Both';
      NO_IO_CHECK='Both';
      NO_ASSERT_CHECK='TRUE';
      NO_DIR_CHECK='TRUE';
      ALLOW_CONNECT='TRUE';
    'VSS'<1219>:
      PIN_NUMBER='(0,0,0,0,0,0,0,0,0,0,0,0,0,0,0,0,0,0,0,0,0,0,DY53,0,0,0,0,0,0,0)';
      PINUSE='GROUND';
      NO_LOAD_CHECK='Both';
      NO_IO_CHECK='Both';
      NO_ASSERT_CHECK='TRUE';
      NO_DIR_CHECK='TRUE';
      ALLOW_CONNECT='TRUE';
    'VSS'<1218>:
      PIN_NUMBER='(0,0,0,0,0,0,0,0,0,0,0,0,0,0,0,0,0,0,0,0,0,0,DY51,0,0,0,0,0,0,0)';
      PINUSE='GROUND';
      NO_LOAD_CHECK='Both';
      NO_IO_CHECK='Both';
      NO_ASSERT_CHECK='TRUE';
      NO_DIR_CHECK='TRUE';
      ALLOW_CONNECT='TRUE';
    'VSS'<1217>:
      PIN_NUMBER='(0,0,0,0,0,0,0,0,0,0,0,0,0,0,0,0,0,0,0,0,0,0,DY49,0,0,0,0,0,0,0)';
      PINUSE='GROUND';
      NO_LOAD_CHECK='Both';
      NO_IO_CHECK='Both';
      NO_ASSERT_CHECK='TRUE';
      NO_DIR_CHECK='TRUE';
      ALLOW_CONNECT='TRUE';
    'VSS'<1216>:
      PIN_NUMBER='(0,0,0,0,0,0,0,0,0,0,0,0,0,0,0,0,0,0,0,0,0,0,DY47,0,0,0,0,0,0,0)';
      PINUSE='GROUND';
      NO_LOAD_CHECK='Both';
      NO_IO_CHECK='Both';
      NO_ASSERT_CHECK='TRUE';
      NO_DIR_CHECK='TRUE';
      ALLOW_CONNECT='TRUE';
    'VSS'<1215>:
      PIN_NUMBER='(0,0,0,0,0,0,0,0,0,0,0,0,0,0,0,0,0,0,0,0,0,0,DY45,0,0,0,0,0,0,0)';
      PINUSE='GROUND';
      NO_LOAD_CHECK='Both';
      NO_IO_CHECK='Both';
      NO_ASSERT_CHECK='TRUE';
      NO_DIR_CHECK='TRUE';
      ALLOW_CONNECT='TRUE';
    'VSS'<1214>:
      PIN_NUMBER='(0,0,0,0,0,0,0,0,0,0,0,0,0,0,0,0,0,0,0,0,0,0,DV19,0,0,0,0,0,0,0)';
      PINUSE='GROUND';
      NO_LOAD_CHECK='Both';
      NO_IO_CHECK='Both';
      NO_ASSERT_CHECK='TRUE';
      NO_DIR_CHECK='TRUE';
      ALLOW_CONNECT='TRUE';
    'VSS'<1213>:
      PIN_NUMBER='(0,0,0,0,0,0,0,0,0,0,0,0,0,0,0,0,0,0,0,0,0,0,DP9,0,0,0,0,0,0,0)';
      PINUSE='GROUND';
      NO_LOAD_CHECK='Both';
      NO_IO_CHECK='Both';
      NO_ASSERT_CHECK='TRUE';
      NO_DIR_CHECK='TRUE';
      ALLOW_CONNECT='TRUE';
    'VSS'<1212>:
      PIN_NUMBER='(0,0,0,0,0,0,0,0,0,0,0,0,0,0,0,0,0,0,0,0,0,0,DP63,0,0,0,0,0,0,0)';
      PINUSE='GROUND';
      NO_LOAD_CHECK='Both';
      NO_IO_CHECK='Both';
      NO_ASSERT_CHECK='TRUE';
      NO_DIR_CHECK='TRUE';
      ALLOW_CONNECT='TRUE';
    'VSS'<1211>:
      PIN_NUMBER='(0,0,0,0,0,0,0,0,0,0,0,0,0,0,0,0,0,0,0,0,0,0,DP61,0,0,0,0,0,0,0)';
      PINUSE='GROUND';
      NO_LOAD_CHECK='Both';
      NO_IO_CHECK='Both';
      NO_ASSERT_CHECK='TRUE';
      NO_DIR_CHECK='TRUE';
      ALLOW_CONNECT='TRUE';
    'VSS'<1210>:
      PIN_NUMBER='(0,0,0,0,0,0,0,0,0,0,0,0,0,0,0,0,0,0,0,0,0,0,DP59,0,0,0,0,0,0,0)';
      PINUSE='GROUND';
      NO_LOAD_CHECK='Both';
      NO_IO_CHECK='Both';
      NO_ASSERT_CHECK='TRUE';
      NO_DIR_CHECK='TRUE';
      ALLOW_CONNECT='TRUE';
    'VSS'<1209>:
      PIN_NUMBER='(0,0,0,0,0,0,0,0,0,0,0,0,0,0,0,0,0,0,0,0,0,0,DP57,0,0,0,0,0,0,0)';
      PINUSE='GROUND';
      NO_LOAD_CHECK='Both';
      NO_IO_CHECK='Both';
      NO_ASSERT_CHECK='TRUE';
      NO_DIR_CHECK='TRUE';
      ALLOW_CONNECT='TRUE';
    'VSS'<1208>:
      PIN_NUMBER='(0,0,0,0,0,0,0,0,0,0,0,0,0,0,0,0,0,0,0,0,0,0,DP55,0,0,0,0,0,0,0)';
      PINUSE='GROUND';
      NO_LOAD_CHECK='Both';
      NO_IO_CHECK='Both';
      NO_ASSERT_CHECK='TRUE';
      NO_DIR_CHECK='TRUE';
      ALLOW_CONNECT='TRUE';
    'VSS'<1207>:
      PIN_NUMBER='(0,0,0,0,0,0,0,0,0,0,0,0,0,0,0,0,0,0,0,0,0,0,DP53,0,0,0,0,0,0,0)';
      PINUSE='GROUND';
      NO_LOAD_CHECK='Both';
      NO_IO_CHECK='Both';
      NO_ASSERT_CHECK='TRUE';
      NO_DIR_CHECK='TRUE';
      ALLOW_CONNECT='TRUE';
    'VSS'<1206>:
      PIN_NUMBER='(0,0,0,0,0,0,0,0,0,0,0,0,0,0,0,0,0,0,0,0,0,0,DP51,0,0,0,0,0,0,0)';
      PINUSE='GROUND';
      NO_LOAD_CHECK='Both';
      NO_IO_CHECK='Both';
      NO_ASSERT_CHECK='TRUE';
      NO_DIR_CHECK='TRUE';
      ALLOW_CONNECT='TRUE';
    'VSS'<1205>:
      PIN_NUMBER='(0,0,0,0,0,0,0,0,0,0,0,0,0,0,0,0,0,0,0,0,0,0,DP49,0,0,0,0,0,0,0)';
      PINUSE='GROUND';
      NO_LOAD_CHECK='Both';
      NO_IO_CHECK='Both';
      NO_ASSERT_CHECK='TRUE';
      NO_DIR_CHECK='TRUE';
      ALLOW_CONNECT='TRUE';
    'VSS'<1204>:
      PIN_NUMBER='(0,0,0,0,0,0,0,0,0,0,0,0,0,0,0,0,0,0,0,0,0,0,DP47,0,0,0,0,0,0,0)';
      PINUSE='GROUND';
      NO_LOAD_CHECK='Both';
      NO_IO_CHECK='Both';
      NO_ASSERT_CHECK='TRUE';
      NO_DIR_CHECK='TRUE';
      ALLOW_CONNECT='TRUE';
    'VSS'<1203>:
      PIN_NUMBER='(0,0,0,0,0,0,0,0,0,0,0,0,0,0,0,0,0,0,0,0,0,0,DP45,0,0,0,0,0,0,0)';
      PINUSE='GROUND';
      NO_LOAD_CHECK='Both';
      NO_IO_CHECK='Both';
      NO_ASSERT_CHECK='TRUE';
      NO_DIR_CHECK='TRUE';
      ALLOW_CONNECT='TRUE';
    'VSS'<1202>:
      PIN_NUMBER='(0,0,0,0,0,0,0,0,0,0,0,0,0,0,0,0,0,0,0,0,0,0,DN18,0,0,0,0,0,0,0)';
      PINUSE='GROUND';
      NO_LOAD_CHECK='Both';
      NO_IO_CHECK='Both';
      NO_ASSERT_CHECK='TRUE';
      NO_DIR_CHECK='TRUE';
      ALLOW_CONNECT='TRUE';
    'VSS'<1201>:
      PIN_NUMBER='(0,0,0,0,0,0,0,0,0,0,0,0,0,0,0,0,0,0,0,0,0,0,DL8,0,0,0,0,0,0,0)';
      PINUSE='GROUND';
      NO_LOAD_CHECK='Both';
      NO_IO_CHECK='Both';
      NO_ASSERT_CHECK='TRUE';
      NO_DIR_CHECK='TRUE';
      ALLOW_CONNECT='TRUE';
    'VSS'<1200>:
      PIN_NUMBER='(0,0,0,0,0,0,0,0,0,0,0,0,0,0,0,0,0,0,0,0,0,0,DE62,0,0,0,0,0,0,0)';
      PINUSE='GROUND';
      NO_LOAD_CHECK='Both';
      NO_IO_CHECK='Both';
      NO_ASSERT_CHECK='TRUE';
      NO_DIR_CHECK='TRUE';
      ALLOW_CONNECT='TRUE';
    'VSS'<1199>:
      PIN_NUMBER='(0,0,0,0,0,0,0,0,0,0,0,0,0,0,0,0,0,0,0,0,0,0,DE60,0,0,0,0,0,0,0)';
      PINUSE='GROUND';
      NO_LOAD_CHECK='Both';
      NO_IO_CHECK='Both';
      NO_ASSERT_CHECK='TRUE';
      NO_DIR_CHECK='TRUE';
      ALLOW_CONNECT='TRUE';
    'VSS'<1198>:
      PIN_NUMBER='(0,0,0,0,0,0,0,0,0,0,0,0,0,0,0,0,0,0,0,0,0,0,DE58,0,0,0,0,0,0,0)';
      PINUSE='GROUND';
      NO_LOAD_CHECK='Both';
      NO_IO_CHECK='Both';
      NO_ASSERT_CHECK='TRUE';
      NO_DIR_CHECK='TRUE';
      ALLOW_CONNECT='TRUE';
    'VSS'<1197>:
      PIN_NUMBER='(0,0,0,0,0,0,0,0,0,0,0,0,0,0,0,0,0,0,0,0,0,0,DE56,0,0,0,0,0,0,0)';
      PINUSE='GROUND';
      NO_LOAD_CHECK='Both';
      NO_IO_CHECK='Both';
      NO_ASSERT_CHECK='TRUE';
      NO_DIR_CHECK='TRUE';
      ALLOW_CONNECT='TRUE';
    'VSS'<1196>:
      PIN_NUMBER='(0,0,0,0,0,0,0,0,0,0,0,0,0,0,0,0,0,0,0,0,0,0,DE54,0,0,0,0,0,0,0)';
      PINUSE='GROUND';
      NO_LOAD_CHECK='Both';
      NO_IO_CHECK='Both';
      NO_ASSERT_CHECK='TRUE';
      NO_DIR_CHECK='TRUE';
      ALLOW_CONNECT='TRUE';
    'VSS'<1195>:
      PIN_NUMBER='(0,0,0,0,0,0,0,0,0,0,0,0,0,0,0,0,0,0,0,0,0,0,DE52,0,0,0,0,0,0,0)';
      PINUSE='GROUND';
      NO_LOAD_CHECK='Both';
      NO_IO_CHECK='Both';
      NO_ASSERT_CHECK='TRUE';
      NO_DIR_CHECK='TRUE';
      ALLOW_CONNECT='TRUE';
    'VSS'<1194>:
      PIN_NUMBER='(0,0,0,0,0,0,0,0,0,0,0,0,0,0,0,0,0,0,0,0,0,0,DE50,0,0,0,0,0,0,0)';
      PINUSE='GROUND';
      NO_LOAD_CHECK='Both';
      NO_IO_CHECK='Both';
      NO_ASSERT_CHECK='TRUE';
      NO_DIR_CHECK='TRUE';
      ALLOW_CONNECT='TRUE';
    'VSS'<1193>:
      PIN_NUMBER='(0,0,0,0,0,0,0,0,0,0,0,0,0,0,0,0,0,0,0,0,0,0,DE48,0,0,0,0,0,0,0)';
      PINUSE='GROUND';
      NO_LOAD_CHECK='Both';
      NO_IO_CHECK='Both';
      NO_ASSERT_CHECK='TRUE';
      NO_DIR_CHECK='TRUE';
      ALLOW_CONNECT='TRUE';
    'VSS'<1192>:
      PIN_NUMBER='(0,0,0,0,0,0,0,0,0,0,0,0,0,0,0,0,0,0,0,0,0,0,CW6,0,0,0,0,0,0,0)';
      PINUSE='GROUND';
      NO_LOAD_CHECK='Both';
      NO_IO_CHECK='Both';
      NO_ASSERT_CHECK='TRUE';
      NO_DIR_CHECK='TRUE';
      ALLOW_CONNECT='TRUE';
    'VSS'<1191>:
      PIN_NUMBER='(0,0,0,0,0,0,0,0,0,0,0,0,0,0,0,0,0,0,0,0,0,0,CG6,0,0,0,0,0,0,0)';
      PINUSE='GROUND';
      NO_LOAD_CHECK='Both';
      NO_IO_CHECK='Both';
      NO_ASSERT_CHECK='TRUE';
      NO_DIR_CHECK='TRUE';
      ALLOW_CONNECT='TRUE';
    'VSS'<1190>:
      PIN_NUMBER='(0,0,0,0,0,0,0,0,0,0,0,0,0,0,0,0,0,0,0,0,0,0,AR6,0,0,0,0,0,0,0)';
      PINUSE='GROUND';
      NO_LOAD_CHECK='Both';
      NO_IO_CHECK='Both';
      NO_ASSERT_CHECK='TRUE';
      NO_DIR_CHECK='TRUE';
      ALLOW_CONNECT='TRUE';
    'VSS'<1189>:
      PIN_NUMBER='(0,0,0,0,0,0,0,0,0,0,0,0,0,0,0,0,0,0,0,0,0,0,AJ4,0,0,0,0,0,0,0)';
      PINUSE='GROUND';
      NO_LOAD_CHECK='Both';
      NO_IO_CHECK='Both';
      NO_ASSERT_CHECK='TRUE';
      NO_DIR_CHECK='TRUE';
      ALLOW_CONNECT='TRUE';
    'VSS'<1188>:
      PIN_NUMBER='(0,0,0,0,0,0,0,0,0,0,0,0,0,0,0,0,0,0,0,0,0,0,AC62,0,0,0,0,0,0,0)';
      PINUSE='GROUND';
      NO_LOAD_CHECK='Both';
      NO_IO_CHECK='Both';
      NO_ASSERT_CHECK='TRUE';
      NO_DIR_CHECK='TRUE';
      ALLOW_CONNECT='TRUE';
    'VSS'<1187>:
      PIN_NUMBER='(0,0,0,0,0,0,0,0,0,0,0,0,0,0,0,0,0,0,0,0,0,0,AC60,0,0,0,0,0,0,0)';
      PINUSE='GROUND';
      NO_LOAD_CHECK='Both';
      NO_IO_CHECK='Both';
      NO_ASSERT_CHECK='TRUE';
      NO_DIR_CHECK='TRUE';
      ALLOW_CONNECT='TRUE';
    'VSS'<1186>:
      PIN_NUMBER='(0,0,0,0,0,0,0,0,0,0,0,0,0,0,0,0,0,0,0,0,0,0,AC58,0,0,0,0,0,0,0)';
      PINUSE='GROUND';
      NO_LOAD_CHECK='Both';
      NO_IO_CHECK='Both';
      NO_ASSERT_CHECK='TRUE';
      NO_DIR_CHECK='TRUE';
      ALLOW_CONNECT='TRUE';
    'VSS'<1185>:
      PIN_NUMBER='(0,0,0,0,0,0,0,0,0,0,0,0,0,0,0,0,0,0,0,0,0,0,A26,0,0,0,0,0,0,0)';
      PINUSE='GROUND';
      NO_LOAD_CHECK='Both';
      NO_IO_CHECK='Both';
      NO_ASSERT_CHECK='TRUE';
      NO_DIR_CHECK='TRUE';
      ALLOW_CONNECT='TRUE';
    'VSS'<1184>:
      PIN_NUMBER='(0,0,0,0,0,0,0,0,0,0,0,0,0,0,0,0,0,0,0,0,0,0,A30,0,0,0,0,0,0,0)';
      PINUSE='GROUND';
      NO_LOAD_CHECK='Both';
      NO_IO_CHECK='Both';
      NO_ASSERT_CHECK='TRUE';
      NO_DIR_CHECK='TRUE';
      ALLOW_CONNECT='TRUE';
    'VSS'<1183>:
      PIN_NUMBER='(0,0,0,0,0,0,0,0,0,0,0,0,0,0,0,0,0,0,0,0,0,0,A32,0,0,0,0,0,0,0)';
      PINUSE='GROUND';
      NO_LOAD_CHECK='Both';
      NO_IO_CHECK='Both';
      NO_ASSERT_CHECK='TRUE';
      NO_DIR_CHECK='TRUE';
      ALLOW_CONNECT='TRUE';
    'VSS'<1182>:
      PIN_NUMBER='(0,0,0,0,0,0,0,0,0,0,0,0,0,0,0,0,0,0,0,0,0,0,A36,0,0,0,0,0,0,0)';
      PINUSE='GROUND';
      NO_LOAD_CHECK='Both';
      NO_IO_CHECK='Both';
      NO_ASSERT_CHECK='TRUE';
      NO_DIR_CHECK='TRUE';
      ALLOW_CONNECT='TRUE';
    'VSS'<1181>:
      PIN_NUMBER='(0,0,0,0,0,0,0,0,0,0,0,0,0,0,0,0,0,0,0,0,0,0,A38,0,0,0,0,0,0,0)';
      PINUSE='GROUND';
      NO_LOAD_CHECK='Both';
      NO_IO_CHECK='Both';
      NO_ASSERT_CHECK='TRUE';
      NO_DIR_CHECK='TRUE';
      ALLOW_CONNECT='TRUE';
    'VSS'<1180>:
      PIN_NUMBER='(0,0,0,0,0,0,0,0,0,0,0,0,0,0,0,0,0,0,0,0,0,0,B25,0,0,0,0,0,0,0)';
      PINUSE='GROUND';
      NO_LOAD_CHECK='Both';
      NO_IO_CHECK='Both';
      NO_ASSERT_CHECK='TRUE';
      NO_DIR_CHECK='TRUE';
      ALLOW_CONNECT='TRUE';
    'VSS'<1179>:
      PIN_NUMBER='(0,0,0,0,0,0,0,0,0,0,0,0,0,0,0,0,0,0,0,0,0,0,B31,0,0,0,0,0,0,0)';
      PINUSE='GROUND';
      NO_LOAD_CHECK='Both';
      NO_IO_CHECK='Both';
      NO_ASSERT_CHECK='TRUE';
      NO_DIR_CHECK='TRUE';
      ALLOW_CONNECT='TRUE';
    'VSS'<1178>:
      PIN_NUMBER='(0,0,0,0,0,0,0,0,0,0,0,0,0,0,0,0,0,0,0,0,0,0,B37,0,0,0,0,0,0,0)';
      PINUSE='GROUND';
      NO_LOAD_CHECK='Both';
      NO_IO_CHECK='Both';
      NO_ASSERT_CHECK='TRUE';
      NO_DIR_CHECK='TRUE';
      ALLOW_CONNECT='TRUE';
    'VSS'<1177>:
      PIN_NUMBER='(0,0,0,0,0,0,0,0,0,0,0,0,0,0,0,0,0,0,0,0,0,0,B71,0,0,0,0,0,0,0)';
      PINUSE='GROUND';
      NO_LOAD_CHECK='Both';
      NO_IO_CHECK='Both';
      NO_ASSERT_CHECK='TRUE';
      NO_DIR_CHECK='TRUE';
      ALLOW_CONNECT='TRUE';
    'VSS'<1176>:
      PIN_NUMBER='(0,0,0,0,0,0,0,0,0,0,0,0,0,0,0,0,0,0,0,0,0,0,B75,0,0,0,0,0,0,0)';
      PINUSE='GROUND';
      NO_LOAD_CHECK='Both';
      NO_IO_CHECK='Both';
      NO_ASSERT_CHECK='TRUE';
      NO_DIR_CHECK='TRUE';
      ALLOW_CONNECT='TRUE';
    'VSS'<1175>:
      PIN_NUMBER='(0,0,0,0,0,0,0,0,0,0,0,0,0,0,0,0,0,0,0,0,0,0,C8,0,0,0,0,0,0,0)';
      PINUSE='GROUND';
      NO_LOAD_CHECK='Both';
      NO_IO_CHECK='Both';
      NO_ASSERT_CHECK='TRUE';
      NO_DIR_CHECK='TRUE';
      ALLOW_CONNECT='TRUE';
    'VSS'<1174>:
      PIN_NUMBER='(0,0,0,0,0,0,0,0,0,0,0,0,0,0,0,0,0,0,0,0,0,0,C10,0,0,0,0,0,0,0)';
      PINUSE='GROUND';
      NO_LOAD_CHECK='Both';
      NO_IO_CHECK='Both';
      NO_ASSERT_CHECK='TRUE';
      NO_DIR_CHECK='TRUE';
      ALLOW_CONNECT='TRUE';
    'VSS'<1173>:
      PIN_NUMBER='(0,0,0,0,0,0,0,0,0,0,0,0,0,0,0,0,0,0,0,0,0,0,C12,0,0,0,0,0,0,0)';
      PINUSE='GROUND';
      NO_LOAD_CHECK='Both';
      NO_IO_CHECK='Both';
      NO_ASSERT_CHECK='TRUE';
      NO_DIR_CHECK='TRUE';
      ALLOW_CONNECT='TRUE';
    'VSS'<1172>:
      PIN_NUMBER='(0,0,0,0,0,0,0,0,0,0,0,0,0,0,0,0,0,0,0,0,0,0,C14,0,0,0,0,0,0,0)';
      PINUSE='GROUND';
      NO_LOAD_CHECK='Both';
      NO_IO_CHECK='Both';
      NO_ASSERT_CHECK='TRUE';
      NO_DIR_CHECK='TRUE';
      ALLOW_CONNECT='TRUE';
    'VSS'<1171>:
      PIN_NUMBER='(0,0,0,0,0,0,0,0,0,0,0,0,0,0,0,0,0,0,0,0,0,0,C16,0,0,0,0,0,0,0)';
      PINUSE='GROUND';
      NO_LOAD_CHECK='Both';
      NO_IO_CHECK='Both';
      NO_ASSERT_CHECK='TRUE';
      NO_DIR_CHECK='TRUE';
      ALLOW_CONNECT='TRUE';
    'VSS'<1170>:
      PIN_NUMBER='(0,0,0,0,0,0,0,0,0,0,0,0,0,0,0,0,0,0,0,0,0,0,C76,0,0,0,0,0,0,0)';
      PINUSE='GROUND';
      NO_LOAD_CHECK='Both';
      NO_IO_CHECK='Both';
      NO_ASSERT_CHECK='TRUE';
      NO_DIR_CHECK='TRUE';
      ALLOW_CONNECT='TRUE';
    'VSS'<1169>:
      PIN_NUMBER='(0,0,0,0,0,0,0,0,0,0,0,0,0,0,0,0,0,0,0,0,0,0,C78,0,0,0,0,0,0,0)';
      PINUSE='GROUND';
      NO_LOAD_CHECK='Both';
      NO_IO_CHECK='Both';
      NO_ASSERT_CHECK='TRUE';
      NO_DIR_CHECK='TRUE';
      ALLOW_CONNECT='TRUE';
    'VSS'<1168>:
      PIN_NUMBER='(0,0,0,0,0,0,0,0,0,0,0,0,0,0,0,0,0,0,0,0,0,0,CM27,0,0,0,0,0,0,0)';
      PINUSE='GROUND';
      NO_LOAD_CHECK='Both';
      NO_IO_CHECK='Both';
      NO_ASSERT_CHECK='TRUE';
      NO_DIR_CHECK='TRUE';
      ALLOW_CONNECT='TRUE';
    'VSS'<1167>:
      PIN_NUMBER='(0,0,0,0,0,0,0,0,0,0,0,0,0,0,0,0,0,0,0,0,0,0,D11,0,0,0,0,0,0,0)';
      PINUSE='GROUND';
      NO_LOAD_CHECK='Both';
      NO_IO_CHECK='Both';
      NO_ASSERT_CHECK='TRUE';
      NO_DIR_CHECK='TRUE';
      ALLOW_CONNECT='TRUE';
    'VSS'<1166>:
      PIN_NUMBER='(0,0,0,0,0,0,0,0,0,0,0,0,0,0,0,0,0,0,0,0,0,0,D13,0,0,0,0,0,0,0)';
      PINUSE='GROUND';
      NO_LOAD_CHECK='Both';
      NO_IO_CHECK='Both';
      NO_ASSERT_CHECK='TRUE';
      NO_DIR_CHECK='TRUE';
      ALLOW_CONNECT='TRUE';
    'VSS'<1165>:
      PIN_NUMBER='(0,0,0,0,0,0,0,0,0,0,0,0,0,0,0,0,0,0,0,0,0,0,D25,0,0,0,0,0,0,0)';
      PINUSE='GROUND';
      NO_LOAD_CHECK='Both';
      NO_IO_CHECK='Both';
      NO_ASSERT_CHECK='TRUE';
      NO_DIR_CHECK='TRUE';
      ALLOW_CONNECT='TRUE';
    'VSS'<1164>:
      PIN_NUMBER='(0,0,0,0,0,0,0,0,0,0,0,0,0,0,0,0,0,0,0,0,0,0,D27,0,0,0,0,0,0,0)';
      PINUSE='GROUND';
      NO_LOAD_CHECK='Both';
      NO_IO_CHECK='Both';
      NO_ASSERT_CHECK='TRUE';
      NO_DIR_CHECK='TRUE';
      ALLOW_CONNECT='TRUE';
    'VSS'<1163>:
      PIN_NUMBER='(0,0,0,0,0,0,0,0,0,0,0,0,0,0,0,0,0,0,0,0,0,0,D29,0,0,0,0,0,0,0)';
      PINUSE='GROUND';
      NO_LOAD_CHECK='Both';
      NO_IO_CHECK='Both';
      NO_ASSERT_CHECK='TRUE';
      NO_DIR_CHECK='TRUE';
      ALLOW_CONNECT='TRUE';
    'VSS'<1162>:
      PIN_NUMBER='(0,0,0,0,0,0,0,0,0,0,0,0,0,0,0,0,0,0,0,0,0,0,D31,0,0,0,0,0,0,0)';
      PINUSE='GROUND';
      NO_LOAD_CHECK='Both';
      NO_IO_CHECK='Both';
      NO_ASSERT_CHECK='TRUE';
      NO_DIR_CHECK='TRUE';
      ALLOW_CONNECT='TRUE';
    'VSS'<1161>:
      PIN_NUMBER='(0,0,0,0,0,0,0,0,0,0,0,0,0,0,0,0,0,0,0,0,0,0,D33,0,0,0,0,0,0,0)';
      PINUSE='GROUND';
      NO_LOAD_CHECK='Both';
      NO_IO_CHECK='Both';
      NO_ASSERT_CHECK='TRUE';
      NO_DIR_CHECK='TRUE';
      ALLOW_CONNECT='TRUE';
    'VSS'<1160>:
      PIN_NUMBER='(0,0,0,0,0,0,0,0,0,0,0,0,0,0,0,0,0,0,0,0,0,0,D35,0,0,0,0,0,0,0)';
      PINUSE='GROUND';
      NO_LOAD_CHECK='Both';
      NO_IO_CHECK='Both';
      NO_ASSERT_CHECK='TRUE';
      NO_DIR_CHECK='TRUE';
      ALLOW_CONNECT='TRUE';
    'VSS'<1159>:
      PIN_NUMBER='(0,0,0,0,0,0,0,0,0,0,0,0,0,0,0,0,0,0,0,0,0,0,D37,0,0,0,0,0,0,0)';
      PINUSE='GROUND';
      NO_LOAD_CHECK='Both';
      NO_IO_CHECK='Both';
      NO_ASSERT_CHECK='TRUE';
      NO_DIR_CHECK='TRUE';
      ALLOW_CONNECT='TRUE';
    'VSS'<1158>:
      PIN_NUMBER='(0,0,0,0,0,0,0,0,0,0,0,0,0,0,0,0,0,0,0,0,0,0,D39,0,0,0,0,0,0,0)';
      PINUSE='GROUND';
      NO_LOAD_CHECK='Both';
      NO_IO_CHECK='Both';
      NO_ASSERT_CHECK='TRUE';
      NO_DIR_CHECK='TRUE';
      ALLOW_CONNECT='TRUE';
    'VSS'<1157>:
      PIN_NUMBER='(0,0,0,0,0,0,0,0,0,0,0,0,0,0,0,0,0,0,0,0,0,0,D41,0,0,0,0,0,0,0)';
      PINUSE='GROUND';
      NO_LOAD_CHECK='Both';
      NO_IO_CHECK='Both';
      NO_ASSERT_CHECK='TRUE';
      NO_DIR_CHECK='TRUE';
      ALLOW_CONNECT='TRUE';
    'VSS'<1156>:
      PIN_NUMBER='(0,0,0,0,0,0,0,0,0,0,0,0,0,0,0,0,0,0,0,0,0,0,D43,0,0,0,0,0,0,0)';
      PINUSE='GROUND';
      NO_LOAD_CHECK='Both';
      NO_IO_CHECK='Both';
      NO_ASSERT_CHECK='TRUE';
      NO_DIR_CHECK='TRUE';
      ALLOW_CONNECT='TRUE';
    'VSS'<1155>:
      PIN_NUMBER='(0,0,0,0,0,0,0,0,0,0,0,0,0,0,0,0,0,0,0,0,0,0,D77,0,0,0,0,0,0,0)';
      PINUSE='GROUND';
      NO_LOAD_CHECK='Both';
      NO_IO_CHECK='Both';
      NO_ASSERT_CHECK='TRUE';
      NO_DIR_CHECK='TRUE';
      ALLOW_CONNECT='TRUE';
    'VSS'<1154>:
      PIN_NUMBER='(0,0,0,0,0,0,0,0,0,0,0,0,0,0,0,0,0,0,0,0,0,0,E6,0,0,0,0,0,0,0)';
      PINUSE='GROUND';
      NO_LOAD_CHECK='Both';
      NO_IO_CHECK='Both';
      NO_ASSERT_CHECK='TRUE';
      NO_DIR_CHECK='TRUE';
      ALLOW_CONNECT='TRUE';
    'VSS'<1153>:
      PIN_NUMBER='(0,0,0,0,0,0,0,0,0,0,0,0,0,0,0,0,0,0,0,0,0,0,E8,0,0,0,0,0,0,0)';
      PINUSE='GROUND';
      NO_LOAD_CHECK='Both';
      NO_IO_CHECK='Both';
      NO_ASSERT_CHECK='TRUE';
      NO_DIR_CHECK='TRUE';
      ALLOW_CONNECT='TRUE';
    'VSS'<1152>:
      PIN_NUMBER='(0,0,0,0,0,0,0,0,0,0,0,0,0,0,0,0,0,0,0,0,0,0,E16,0,0,0,0,0,0,0)';
      PINUSE='GROUND';
      NO_LOAD_CHECK='Both';
      NO_IO_CHECK='Both';
      NO_ASSERT_CHECK='TRUE';
      NO_DIR_CHECK='TRUE';
      ALLOW_CONNECT='TRUE';
    'VSS'<1151>:
      PIN_NUMBER='(0,0,0,0,0,0,0,0,0,0,0,0,0,0,0,0,0,0,0,0,0,0,E18,0,0,0,0,0,0,0)';
      PINUSE='GROUND';
      NO_LOAD_CHECK='Both';
      NO_IO_CHECK='Both';
      NO_ASSERT_CHECK='TRUE';
      NO_DIR_CHECK='TRUE';
      ALLOW_CONNECT='TRUE';
    'VSS'<1150>:
      PIN_NUMBER='(0,0,0,0,0,0,0,0,0,0,0,0,0,0,0,0,0,0,0,0,0,0,E20,0,0,0,0,0,0,0)';
      PINUSE='GROUND';
      NO_LOAD_CHECK='Both';
      NO_IO_CHECK='Both';
      NO_ASSERT_CHECK='TRUE';
      NO_DIR_CHECK='TRUE';
      ALLOW_CONNECT='TRUE';
    'VSS'<1149>:
      PIN_NUMBER='(0,0,0,0,0,0,0,0,0,0,0,0,0,0,0,0,0,0,0,0,0,0,E22,0,0,0,0,0,0,0)';
      PINUSE='GROUND';
      NO_LOAD_CHECK='Both';
      NO_IO_CHECK='Both';
      NO_ASSERT_CHECK='TRUE';
      NO_DIR_CHECK='TRUE';
      ALLOW_CONNECT='TRUE';
    'VSS'<1148>:
      PIN_NUMBER='(0,0,0,0,0,0,0,0,0,0,0,0,0,0,0,0,0,0,0,0,0,0,E72,0,0,0,0,0,0,0)';
      PINUSE='GROUND';
      NO_LOAD_CHECK='Both';
      NO_IO_CHECK='Both';
      NO_ASSERT_CHECK='TRUE';
      NO_DIR_CHECK='TRUE';
      ALLOW_CONNECT='TRUE';
    'VSS'<1147>:
      PIN_NUMBER='(0,0,0,0,0,0,0,0,0,0,0,0,0,0,0,0,0,0,0,0,0,0,E74,0,0,0,0,0,0,0)';
      PINUSE='GROUND';
      NO_LOAD_CHECK='Both';
      NO_IO_CHECK='Both';
      NO_ASSERT_CHECK='TRUE';
      NO_DIR_CHECK='TRUE';
      ALLOW_CONNECT='TRUE';
    'VSS'<1146>:
      PIN_NUMBER='(0,0,0,0,0,0,0,0,0,0,0,0,0,0,0,0,0,0,0,0,0,0,E76,0,0,0,0,0,0,0)';
      PINUSE='GROUND';
      NO_LOAD_CHECK='Both';
      NO_IO_CHECK='Both';
      NO_ASSERT_CHECK='TRUE';
      NO_DIR_CHECK='TRUE';
      ALLOW_CONNECT='TRUE';
    'VSS'<1145>:
      PIN_NUMBER='(0,0,0,0,0,0,0,0,0,0,0,0,0,0,0,0,0,0,0,0,0,0,F5,0,0,0,0,0,0,0)';
      PINUSE='GROUND';
      NO_LOAD_CHECK='Both';
      NO_IO_CHECK='Both';
      NO_ASSERT_CHECK='TRUE';
      NO_DIR_CHECK='TRUE';
      ALLOW_CONNECT='TRUE';
    'VSS'<1144>:
      PIN_NUMBER='(0,0,0,0,0,0,0,0,0,0,0,0,0,0,0,0,0,0,0,0,0,0,F17,0,0,0,0,0,0,0)';
      PINUSE='GROUND';
      NO_LOAD_CHECK='Both';
      NO_IO_CHECK='Both';
      NO_ASSERT_CHECK='TRUE';
      NO_DIR_CHECK='TRUE';
      ALLOW_CONNECT='TRUE';
    'VSS'<1143>:
      PIN_NUMBER='(0,0,0,0,0,0,0,0,0,0,0,0,0,0,0,0,0,0,0,0,0,0,F19,0,0,0,0,0,0,0)';
      PINUSE='GROUND';
      NO_LOAD_CHECK='Both';
      NO_IO_CHECK='Both';
      NO_ASSERT_CHECK='TRUE';
      NO_DIR_CHECK='TRUE';
      ALLOW_CONNECT='TRUE';
    'VSS'<1142>:
      PIN_NUMBER='(0,0,0,0,0,0,0,0,0,0,0,0,0,0,0,0,0,0,0,0,0,0,F25,0,0,0,0,0,0,0)';
      PINUSE='GROUND';
      NO_LOAD_CHECK='Both';
      NO_IO_CHECK='Both';
      NO_ASSERT_CHECK='TRUE';
      NO_DIR_CHECK='TRUE';
      ALLOW_CONNECT='TRUE';
    'VSS'<1141>:
      PIN_NUMBER='(0,0,0,0,0,0,0,0,0,0,0,0,0,0,0,0,0,0,0,0,0,0,F31,0,0,0,0,0,0,0)';
      PINUSE='GROUND';
      NO_LOAD_CHECK='Both';
      NO_IO_CHECK='Both';
      NO_ASSERT_CHECK='TRUE';
      NO_DIR_CHECK='TRUE';
      ALLOW_CONNECT='TRUE';
    'VSS'<1140>:
      PIN_NUMBER='(0,0,0,0,0,0,0,0,0,0,0,0,0,0,0,0,0,0,0,0,0,0,F37,0,0,0,0,0,0,0)';
      PINUSE='GROUND';
      NO_LOAD_CHECK='Both';
      NO_IO_CHECK='Both';
      NO_ASSERT_CHECK='TRUE';
      NO_DIR_CHECK='TRUE';
      ALLOW_CONNECT='TRUE';
    'VSS'<1139>:
      PIN_NUMBER='(0,0,0,0,0,0,0,0,0,0,0,0,0,0,0,0,0,0,0,0,0,0,F43,0,0,0,0,0,0,0)';
      PINUSE='GROUND';
      NO_LOAD_CHECK='Both';
      NO_IO_CHECK='Both';
      NO_ASSERT_CHECK='TRUE';
      NO_DIR_CHECK='TRUE';
      ALLOW_CONNECT='TRUE';
    'VSS'<1138>:
      PIN_NUMBER='(0,0,0,0,0,0,0,0,0,0,0,0,0,0,0,0,0,0,0,0,0,0,F67,0,0,0,0,0,0,0)';
      PINUSE='GROUND';
      NO_LOAD_CHECK='Both';
      NO_IO_CHECK='Both';
      NO_ASSERT_CHECK='TRUE';
      NO_DIR_CHECK='TRUE';
      ALLOW_CONNECT='TRUE';
    'VSS'<1137>:
      PIN_NUMBER='(0,0,0,0,0,0,0,0,0,0,0,0,0,0,0,0,0,0,0,0,0,0,F69,0,0,0,0,0,0,0)';
      PINUSE='GROUND';
      NO_LOAD_CHECK='Both';
      NO_IO_CHECK='Both';
      NO_ASSERT_CHECK='TRUE';
      NO_DIR_CHECK='TRUE';
      ALLOW_CONNECT='TRUE';
    'VSS'<1136>:
      PIN_NUMBER='(0,0,0,0,0,0,0,0,0,0,0,0,0,0,0,0,0,0,0,0,0,0,G4,0,0,0,0,0,0,0)';
      PINUSE='GROUND';
      NO_LOAD_CHECK='Both';
      NO_IO_CHECK='Both';
      NO_ASSERT_CHECK='TRUE';
      NO_DIR_CHECK='TRUE';
      ALLOW_CONNECT='TRUE';
    'VSS'<1135>:
      PIN_NUMBER='(0,0,0,0,0,0,0,0,0,0,0,0,0,0,0,0,0,0,0,0,0,0,G8,0,0,0,0,0,0,0)';
      PINUSE='GROUND';
      NO_LOAD_CHECK='Both';
      NO_IO_CHECK='Both';
      NO_ASSERT_CHECK='TRUE';
      NO_DIR_CHECK='TRUE';
      ALLOW_CONNECT='TRUE';
    'VSS'<1134>:
      PIN_NUMBER='(0,0,0,0,0,0,0,0,0,0,0,0,0,0,0,0,0,0,0,0,0,0,G22,0,0,0,0,0,0,0)';
      PINUSE='GROUND';
      NO_LOAD_CHECK='Both';
      NO_IO_CHECK='Both';
      NO_ASSERT_CHECK='TRUE';
      NO_DIR_CHECK='TRUE';
      ALLOW_CONNECT='TRUE';
    'VSS'<1133>:
      PIN_NUMBER='(0,0,0,0,0,0,0,0,0,0,0,0,0,0,0,0,0,0,0,0,0,0,G24,0,0,0,0,0,0,0)';
      PINUSE='GROUND';
      NO_LOAD_CHECK='Both';
      NO_IO_CHECK='Both';
      NO_ASSERT_CHECK='TRUE';
      NO_DIR_CHECK='TRUE';
      ALLOW_CONNECT='TRUE';
    'VSS'<1132>:
      PIN_NUMBER='(0,0,0,0,0,0,0,0,0,0,0,0,0,0,0,0,0,0,0,0,0,0,G26,0,0,0,0,0,0,0)';
      PINUSE='GROUND';
      NO_LOAD_CHECK='Both';
      NO_IO_CHECK='Both';
      NO_ASSERT_CHECK='TRUE';
      NO_DIR_CHECK='TRUE';
      ALLOW_CONNECT='TRUE';
    'VSS'<1131>:
      PIN_NUMBER='(0,0,0,0,0,0,0,0,0,0,0,0,0,0,0,0,0,0,0,0,0,0,G30,0,0,0,0,0,0,0)';
      PINUSE='GROUND';
      NO_LOAD_CHECK='Both';
      NO_IO_CHECK='Both';
      NO_ASSERT_CHECK='TRUE';
      NO_DIR_CHECK='TRUE';
      ALLOW_CONNECT='TRUE';
    'VSS'<1130>:
      PIN_NUMBER='(0,0,0,0,0,0,0,0,0,0,0,0,0,0,0,0,0,0,0,0,0,0,G32,0,0,0,0,0,0,0)';
      PINUSE='GROUND';
      NO_LOAD_CHECK='Both';
      NO_IO_CHECK='Both';
      NO_ASSERT_CHECK='TRUE';
      NO_DIR_CHECK='TRUE';
      ALLOW_CONNECT='TRUE';
    'VSS'<1129>:
      PIN_NUMBER='(0,0,0,0,0,0,0,0,0,0,0,0,0,0,0,0,0,0,0,0,0,0,G36,0,0,0,0,0,0,0)';
      PINUSE='GROUND';
      NO_LOAD_CHECK='Both';
      NO_IO_CHECK='Both';
      NO_ASSERT_CHECK='TRUE';
      NO_DIR_CHECK='TRUE';
      ALLOW_CONNECT='TRUE';
    'VSS'<1128>:
      PIN_NUMBER='(0,0,0,0,0,0,0,0,0,0,0,0,0,0,0,0,0,0,0,0,0,0,G38,0,0,0,0,0,0,0)';
      PINUSE='GROUND';
      NO_LOAD_CHECK='Both';
      NO_IO_CHECK='Both';
      NO_ASSERT_CHECK='TRUE';
      NO_DIR_CHECK='TRUE';
      ALLOW_CONNECT='TRUE';
    'VSS'<1127>:
      PIN_NUMBER='(0,0,0,0,0,0,0,0,0,0,0,0,0,0,0,0,0,0,0,0,0,0,G42,0,0,0,0,0,0,0)';
      PINUSE='GROUND';
      NO_LOAD_CHECK='Both';
      NO_IO_CHECK='Both';
      NO_ASSERT_CHECK='TRUE';
      NO_DIR_CHECK='TRUE';
      ALLOW_CONNECT='TRUE';
    'VSS'<1126>:
      PIN_NUMBER='(0,0,0,0,0,0,0,0,0,0,0,0,0,0,0,0,0,0,0,0,0,0,G66,0,0,0,0,0,0,0)';
      PINUSE='GROUND';
      NO_LOAD_CHECK='Both';
      NO_IO_CHECK='Both';
      NO_ASSERT_CHECK='TRUE';
      NO_DIR_CHECK='TRUE';
      ALLOW_CONNECT='TRUE';
    'VSS'<1125>:
      PIN_NUMBER='(0,0,0,0,0,0,0,0,0,0,0,0,0,0,0,0,0,0,0,0,0,0,G70,0,0,0,0,0,0,0)';
      PINUSE='GROUND';
      NO_LOAD_CHECK='Both';
      NO_IO_CHECK='Both';
      NO_ASSERT_CHECK='TRUE';
      NO_DIR_CHECK='TRUE';
      ALLOW_CONNECT='TRUE';
    'VSS'<1124>:
      PIN_NUMBER='(0,0,0,0,0,0,0,0,0,0,0,0,0,0,0,0,0,0,0,0,0,0,G76,0,0,0,0,0,0,0)';
      PINUSE='GROUND';
      NO_LOAD_CHECK='Both';
      NO_IO_CHECK='Both';
      NO_ASSERT_CHECK='TRUE';
      NO_DIR_CHECK='TRUE';
      ALLOW_CONNECT='TRUE';
    'VSS'<1123>:
      PIN_NUMBER='(0,0,0,0,0,0,0,0,0,0,0,0,0,0,0,0,0,0,0,0,0,0,G78,0,0,0,0,0,0,0)';
      PINUSE='GROUND';
      NO_LOAD_CHECK='Both';
      NO_IO_CHECK='Both';
      NO_ASSERT_CHECK='TRUE';
      NO_DIR_CHECK='TRUE';
      ALLOW_CONNECT='TRUE';
    'VSS'<1122>:
      PIN_NUMBER='(0,0,0,0,0,0,0,0,0,0,0,0,0,0,0,0,0,0,0,0,0,0,G80,0,0,0,0,0,0,0)';
      PINUSE='GROUND';
      NO_LOAD_CHECK='Both';
      NO_IO_CHECK='Both';
      NO_ASSERT_CHECK='TRUE';
      NO_DIR_CHECK='TRUE';
      ALLOW_CONNECT='TRUE';
    'VSS'<1121>:
      PIN_NUMBER='(0,0,0,0,0,0,0,0,0,0,0,0,0,0,0,0,0,0,0,0,0,0,G82,0,0,0,0,0,0,0)';
      PINUSE='GROUND';
      NO_LOAD_CHECK='Both';
      NO_IO_CHECK='Both';
      NO_ASSERT_CHECK='TRUE';
      NO_DIR_CHECK='TRUE';
      ALLOW_CONNECT='TRUE';
    'VSS'<1120>:
      PIN_NUMBER='(0,0,0,0,0,0,0,0,0,0,0,0,0,0,0,0,0,0,0,0,0,0,H3,0,0,0,0,0,0,0)';
      PINUSE='GROUND';
      NO_LOAD_CHECK='Both';
      NO_IO_CHECK='Both';
      NO_ASSERT_CHECK='TRUE';
      NO_DIR_CHECK='TRUE';
      ALLOW_CONNECT='TRUE';
    'VSS'<1119>:
      PIN_NUMBER='(0,0,0,0,0,0,0,0,0,0,0,0,0,0,0,0,0,0,0,0,0,0,H11,0,0,0,0,0,0,0)';
      PINUSE='GROUND';
      NO_LOAD_CHECK='Both';
      NO_IO_CHECK='Both';
      NO_ASSERT_CHECK='TRUE';
      NO_DIR_CHECK='TRUE';
      ALLOW_CONNECT='TRUE';
    'VSS'<1118>:
      PIN_NUMBER='(0,0,0,0,0,0,0,0,0,0,0,0,0,0,0,0,0,0,0,0,0,0,H25,0,0,0,0,0,0,0)';
      PINUSE='GROUND';
      NO_LOAD_CHECK='Both';
      NO_IO_CHECK='Both';
      NO_ASSERT_CHECK='TRUE';
      NO_DIR_CHECK='TRUE';
      ALLOW_CONNECT='TRUE';
    'VSS'<1117>:
      PIN_NUMBER='(0,0,0,0,0,0,0,0,0,0,0,0,0,0,0,0,0,0,0,0,0,0,H27,0,0,0,0,0,0,0)';
      PINUSE='GROUND';
      NO_LOAD_CHECK='Both';
      NO_IO_CHECK='Both';
      NO_ASSERT_CHECK='TRUE';
      NO_DIR_CHECK='TRUE';
      ALLOW_CONNECT='TRUE';
    'VSS'<1116>:
      PIN_NUMBER='(0,0,0,0,0,0,0,0,0,0,0,0,0,0,0,0,0,0,0,0,0,0,H29,0,0,0,0,0,0,0)';
      PINUSE='GROUND';
      NO_LOAD_CHECK='Both';
      NO_IO_CHECK='Both';
      NO_ASSERT_CHECK='TRUE';
      NO_DIR_CHECK='TRUE';
      ALLOW_CONNECT='TRUE';
    'VSS'<1115>:
      PIN_NUMBER='(0,0,0,0,0,0,0,0,0,0,0,0,0,0,0,0,0,0,0,0,0,0,H31,0,0,0,0,0,0,0)';
      PINUSE='GROUND';
      NO_LOAD_CHECK='Both';
      NO_IO_CHECK='Both';
      NO_ASSERT_CHECK='TRUE';
      NO_DIR_CHECK='TRUE';
      ALLOW_CONNECT='TRUE';
    'VSS'<1114>:
      PIN_NUMBER='(0,0,0,0,0,0,0,0,0,0,0,0,0,0,0,0,0,0,0,0,0,0,H33,0,0,0,0,0,0,0)';
      PINUSE='GROUND';
      NO_LOAD_CHECK='Both';
      NO_IO_CHECK='Both';
      NO_ASSERT_CHECK='TRUE';
      NO_DIR_CHECK='TRUE';
      ALLOW_CONNECT='TRUE';
    'VSS'<1113>:
      PIN_NUMBER='(0,0,0,0,0,0,0,0,0,0,0,0,0,0,0,0,0,0,0,0,0,0,H35,0,0,0,0,0,0,0)';
      PINUSE='GROUND';
      NO_LOAD_CHECK='Both';
      NO_IO_CHECK='Both';
      NO_ASSERT_CHECK='TRUE';
      NO_DIR_CHECK='TRUE';
      ALLOW_CONNECT='TRUE';
    'VSS'<1112>:
      PIN_NUMBER='(0,0,0,0,0,0,0,0,0,0,0,0,0,0,0,0,0,0,0,0,0,0,H37,0,0,0,0,0,0,0)';
      PINUSE='GROUND';
      NO_LOAD_CHECK='Both';
      NO_IO_CHECK='Both';
      NO_ASSERT_CHECK='TRUE';
      NO_DIR_CHECK='TRUE';
      ALLOW_CONNECT='TRUE';
    'VSS'<1111>:
      PIN_NUMBER='(0,0,0,0,0,0,0,0,0,0,0,0,0,0,0,0,0,0,0,0,0,0,H39,0,0,0,0,0,0,0)';
      PINUSE='GROUND';
      NO_LOAD_CHECK='Both';
      NO_IO_CHECK='Both';
      NO_ASSERT_CHECK='TRUE';
      NO_DIR_CHECK='TRUE';
      ALLOW_CONNECT='TRUE';
    'VSS'<1110>:
      PIN_NUMBER='(0,0,0,0,0,0,0,0,0,0,0,0,0,0,0,0,0,0,0,0,0,0,H41,0,0,0,0,0,0,0)';
      PINUSE='GROUND';
      NO_LOAD_CHECK='Both';
      NO_IO_CHECK='Both';
      NO_ASSERT_CHECK='TRUE';
      NO_DIR_CHECK='TRUE';
      ALLOW_CONNECT='TRUE';
    'VSS'<1109>:
      PIN_NUMBER='(0,0,0,0,0,0,0,0,0,0,0,0,0,0,0,0,0,0,0,0,0,0,H65,0,0,0,0,0,0,0)';
      PINUSE='GROUND';
      NO_LOAD_CHECK='Both';
      NO_IO_CHECK='Both';
      NO_ASSERT_CHECK='TRUE';
      NO_DIR_CHECK='TRUE';
      ALLOW_CONNECT='TRUE';
    'VSS'<1108>:
      PIN_NUMBER='(0,0,0,0,0,0,0,0,0,0,0,0,0,0,0,0,0,0,0,0,0,0,H71,0,0,0,0,0,0,0)';
      PINUSE='GROUND';
      NO_LOAD_CHECK='Both';
      NO_IO_CHECK='Both';
      NO_ASSERT_CHECK='TRUE';
      NO_DIR_CHECK='TRUE';
      ALLOW_CONNECT='TRUE';
    'VSS'<1107>:
      PIN_NUMBER='(0,0,0,0,0,0,0,0,0,0,0,0,0,0,0,0,0,0,0,0,0,0,H75,0,0,0,0,0,0,0)';
      PINUSE='GROUND';
      NO_LOAD_CHECK='Both';
      NO_IO_CHECK='Both';
      NO_ASSERT_CHECK='TRUE';
      NO_DIR_CHECK='TRUE';
      ALLOW_CONNECT='TRUE';
    'VSS'<1106>:
      PIN_NUMBER='(0,0,0,0,0,0,0,0,0,0,0,0,0,0,0,0,0,0,0,0,0,0,DN44,0,0,0,0,0,0,0)';
      PINUSE='GROUND';
      NO_LOAD_CHECK='Both';
      NO_IO_CHECK='Both';
      NO_ASSERT_CHECK='TRUE';
      NO_DIR_CHECK='TRUE';
      ALLOW_CONNECT='TRUE';
    'VSS'<1105>:
      PIN_NUMBER='(0,0,0,0,0,0,0,0,0,0,0,0,0,0,0,0,0,0,0,0,0,0,J4,0,0,0,0,0,0,0)';
      PINUSE='GROUND';
      NO_LOAD_CHECK='Both';
      NO_IO_CHECK='Both';
      NO_ASSERT_CHECK='TRUE';
      NO_DIR_CHECK='TRUE';
      ALLOW_CONNECT='TRUE';
    'VSS'<1104>:
      PIN_NUMBER='(0,0,0,0,0,0,0,0,0,0,0,0,0,0,0,0,0,0,0,0,0,0,J12,0,0,0,0,0,0,0)';
      PINUSE='GROUND';
      NO_LOAD_CHECK='Both';
      NO_IO_CHECK='Both';
      NO_ASSERT_CHECK='TRUE';
      NO_DIR_CHECK='TRUE';
      ALLOW_CONNECT='TRUE';
    'VSS'<1103>:
      PIN_NUMBER='(0,0,0,0,0,0,0,0,0,0,0,0,0,0,0,0,0,0,0,0,0,0,J14,0,0,0,0,0,0,0)';
      PINUSE='GROUND';
      NO_LOAD_CHECK='Both';
      NO_IO_CHECK='Both';
      NO_ASSERT_CHECK='TRUE';
      NO_DIR_CHECK='TRUE';
      ALLOW_CONNECT='TRUE';
    'VSS'<1102>:
      PIN_NUMBER='(0,0,0,0,0,0,0,0,0,0,0,0,0,0,0,0,0,0,0,0,0,0,J22,0,0,0,0,0,0,0)';
      PINUSE='GROUND';
      NO_LOAD_CHECK='Both';
      NO_IO_CHECK='Both';
      NO_ASSERT_CHECK='TRUE';
      NO_DIR_CHECK='TRUE';
      ALLOW_CONNECT='TRUE';
    'VSS'<1101>:
      PIN_NUMBER='(0,0,0,0,0,0,0,0,0,0,0,0,0,0,0,0,0,0,0,0,0,0,J26,0,0,0,0,0,0,0)';
      PINUSE='GROUND';
      NO_LOAD_CHECK='Both';
      NO_IO_CHECK='Both';
      NO_ASSERT_CHECK='TRUE';
      NO_DIR_CHECK='TRUE';
      ALLOW_CONNECT='TRUE';
    'VSS'<1100>:
      PIN_NUMBER='(0,0,0,0,0,0,0,0,0,0,0,0,0,0,0,0,0,0,0,0,0,0,J28,0,0,0,0,0,0,0)';
      PINUSE='GROUND';
      NO_LOAD_CHECK='Both';
      NO_IO_CHECK='Both';
      NO_ASSERT_CHECK='TRUE';
      NO_DIR_CHECK='TRUE';
      ALLOW_CONNECT='TRUE';
    'VSS'<1099>:
      PIN_NUMBER='(0,0,0,0,0,0,0,0,0,0,0,0,0,0,0,0,0,0,0,0,0,0,J32,0,0,0,0,0,0,0)';
      PINUSE='GROUND';
      NO_LOAD_CHECK='Both';
      NO_IO_CHECK='Both';
      NO_ASSERT_CHECK='TRUE';
      NO_DIR_CHECK='TRUE';
      ALLOW_CONNECT='TRUE';
    'VSS'<1098>:
      PIN_NUMBER='(0,0,0,0,0,0,0,0,0,0,0,0,0,0,0,0,0,0,0,0,0,0,J34,0,0,0,0,0,0,0)';
      PINUSE='GROUND';
      NO_LOAD_CHECK='Both';
      NO_IO_CHECK='Both';
      NO_ASSERT_CHECK='TRUE';
      NO_DIR_CHECK='TRUE';
      ALLOW_CONNECT='TRUE';
    'VSS'<1097>:
      PIN_NUMBER='(0,0,0,0,0,0,0,0,0,0,0,0,0,0,0,0,0,0,0,0,0,0,J38,0,0,0,0,0,0,0)';
      PINUSE='GROUND';
      NO_LOAD_CHECK='Both';
      NO_IO_CHECK='Both';
      NO_ASSERT_CHECK='TRUE';
      NO_DIR_CHECK='TRUE';
      ALLOW_CONNECT='TRUE';
    'VSS'<1096>:
      PIN_NUMBER='(0,0,0,0,0,0,0,0,0,0,0,0,0,0,0,0,0,0,0,0,0,0,J40,0,0,0,0,0,0,0)';
      PINUSE='GROUND';
      NO_LOAD_CHECK='Both';
      NO_IO_CHECK='Both';
      NO_ASSERT_CHECK='TRUE';
      NO_DIR_CHECK='TRUE';
      ALLOW_CONNECT='TRUE';
    'VSS'<1095>:
      PIN_NUMBER='(0,0,0,0,0,0,0,0,0,0,0,0,0,0,0,0,0,0,0,0,0,0,J72,0,0,0,0,0,0,0)';
      PINUSE='GROUND';
      NO_LOAD_CHECK='Both';
      NO_IO_CHECK='Both';
      NO_ASSERT_CHECK='TRUE';
      NO_DIR_CHECK='TRUE';
      ALLOW_CONNECT='TRUE';
    'VSS'<1094>:
      PIN_NUMBER='(0,0,0,0,0,0,0,0,0,0,0,0,0,0,0,0,0,0,0,0,0,0,J74,0,0,0,0,0,0,0)';
      PINUSE='GROUND';
      NO_LOAD_CHECK='Both';
      NO_IO_CHECK='Both';
      NO_ASSERT_CHECK='TRUE';
      NO_DIR_CHECK='TRUE';
      ALLOW_CONNECT='TRUE';
    'VSS'<1093>:
      PIN_NUMBER='(0,0,0,0,0,0,0,0,0,0,0,0,0,0,0,0,0,0,0,0,0,0,0,J76,0,0,0,0,0,0)';
      PINUSE='GROUND';
      NO_LOAD_CHECK='Both';
      NO_IO_CHECK='Both';
      NO_ASSERT_CHECK='TRUE';
      NO_DIR_CHECK='TRUE';
      ALLOW_CONNECT='TRUE';
    'VSS'<1092>:
      PIN_NUMBER='(0,0,0,0,0,0,0,0,0,0,0,0,0,0,0,0,0,0,0,0,0,0,0,J82,0,0,0,0,0,0)';
      PINUSE='GROUND';
      NO_LOAD_CHECK='Both';
      NO_IO_CHECK='Both';
      NO_ASSERT_CHECK='TRUE';
      NO_DIR_CHECK='TRUE';
      ALLOW_CONNECT='TRUE';
    'VSS'<1091>:
      PIN_NUMBER='(0,0,0,0,0,0,0,0,0,0,0,0,0,0,0,0,0,0,0,0,0,0,0,J84,0,0,0,0,0,0)';
      PINUSE='GROUND';
      NO_LOAD_CHECK='Both';
      NO_IO_CHECK='Both';
      NO_ASSERT_CHECK='TRUE';
      NO_DIR_CHECK='TRUE';
      ALLOW_CONNECT='TRUE';
    'VSS'<1090>:
      PIN_NUMBER='(0,0,0,0,0,0,0,0,0,0,0,0,0,0,0,0,0,0,0,0,0,0,0,K1,0,0,0,0,0,0)';
      PINUSE='GROUND';
      NO_LOAD_CHECK='Both';
      NO_IO_CHECK='Both';
      NO_ASSERT_CHECK='TRUE';
      NO_DIR_CHECK='TRUE';
      ALLOW_CONNECT='TRUE';
    'VSS'<1089>:
      PIN_NUMBER='(0,0,0,0,0,0,0,0,0,0,0,0,0,0,0,0,0,0,0,0,0,0,0,K11,0,0,0,0,0,0)';
      PINUSE='GROUND';
      NO_LOAD_CHECK='Both';
      NO_IO_CHECK='Both';
      NO_ASSERT_CHECK='TRUE';
      NO_DIR_CHECK='TRUE';
      ALLOW_CONNECT='TRUE';
    'VSS'<1088>:
      PIN_NUMBER='(0,0,0,0,0,0,0,0,0,0,0,0,0,0,0,0,0,0,0,0,0,0,0,K13,0,0,0,0,0,0)';
      PINUSE='GROUND';
      NO_LOAD_CHECK='Both';
      NO_IO_CHECK='Both';
      NO_ASSERT_CHECK='TRUE';
      NO_DIR_CHECK='TRUE';
      ALLOW_CONNECT='TRUE';
    'VSS'<1087>:
      PIN_NUMBER='(0,0,0,0,0,0,0,0,0,0,0,0,0,0,0,0,0,0,0,0,0,0,0,K17,0,0,0,0,0,0)';
      PINUSE='GROUND';
      NO_LOAD_CHECK='Both';
      NO_IO_CHECK='Both';
      NO_ASSERT_CHECK='TRUE';
      NO_DIR_CHECK='TRUE';
      ALLOW_CONNECT='TRUE';
    'VSS'<1086>:
      PIN_NUMBER='(0,0,0,0,0,0,0,0,0,0,0,0,0,0,0,0,0,0,0,0,0,0,0,DB7,0,0,0,0,0,0)';
      PINUSE='GROUND';
      NO_LOAD_CHECK='Both';
      NO_IO_CHECK='Both';
      NO_ASSERT_CHECK='TRUE';
      NO_DIR_CHECK='TRUE';
      ALLOW_CONNECT='TRUE';
    'VSS'<1085>:
      PIN_NUMBER='(0,0,0,0,0,0,0,0,0,0,0,0,0,0,0,0,0,0,0,0,0,0,0,K27,0,0,0,0,0,0)';
      PINUSE='GROUND';
      NO_LOAD_CHECK='Both';
      NO_IO_CHECK='Both';
      NO_ASSERT_CHECK='TRUE';
      NO_DIR_CHECK='TRUE';
      ALLOW_CONNECT='TRUE';
    'VSS'<1084>:
      PIN_NUMBER='(0,0,0,0,0,0,0,0,0,0,0,0,0,0,0,0,0,0,0,0,0,0,0,K33,0,0,0,0,0,0)';
      PINUSE='GROUND';
      NO_LOAD_CHECK='Both';
      NO_IO_CHECK='Both';
      NO_ASSERT_CHECK='TRUE';
      NO_DIR_CHECK='TRUE';
      ALLOW_CONNECT='TRUE';
    'VSS'<1083>:
      PIN_NUMBER='(0,0,0,0,0,0,0,0,0,0,0,0,0,0,0,0,0,0,0,0,0,0,0,K39,0,0,0,0,0,0)';
      PINUSE='GROUND';
      NO_LOAD_CHECK='Both';
      NO_IO_CHECK='Both';
      NO_ASSERT_CHECK='TRUE';
      NO_DIR_CHECK='TRUE';
      ALLOW_CONNECT='TRUE';
    'VSS'<1082>:
      PIN_NUMBER='(0,0,0,0,0,0,0,0,0,0,0,0,0,0,0,0,0,0,0,0,0,0,0,K65,0,0,0,0,0,0)';
      PINUSE='GROUND';
      NO_LOAD_CHECK='Both';
      NO_IO_CHECK='Both';
      NO_ASSERT_CHECK='TRUE';
      NO_DIR_CHECK='TRUE';
      ALLOW_CONNECT='TRUE';
    'VSS'<1081>:
      PIN_NUMBER='(0,0,0,0,0,0,0,0,0,0,0,0,0,0,0,0,0,0,0,0,0,0,0,K67,0,0,0,0,0,0)';
      PINUSE='GROUND';
      NO_LOAD_CHECK='Both';
      NO_IO_CHECK='Both';
      NO_ASSERT_CHECK='TRUE';
      NO_DIR_CHECK='TRUE';
      ALLOW_CONNECT='TRUE';
    'VSS'<1080>:
      PIN_NUMBER='(0,0,0,0,0,0,0,0,0,0,0,0,0,0,0,0,0,0,0,0,0,0,0,K69,0,0,0,0,0,0)';
      PINUSE='GROUND';
      NO_LOAD_CHECK='Both';
      NO_IO_CHECK='Both';
      NO_ASSERT_CHECK='TRUE';
      NO_DIR_CHECK='TRUE';
      ALLOW_CONNECT='TRUE';
    'VSS'<1079>:
      PIN_NUMBER='(0,0,0,0,0,0,0,0,0,0,0,0,0,0,0,0,0,0,0,0,0,0,0,K71,0,0,0,0,0,0)';
      PINUSE='GROUND';
      NO_LOAD_CHECK='Both';
      NO_IO_CHECK='Both';
      NO_ASSERT_CHECK='TRUE';
      NO_DIR_CHECK='TRUE';
      ALLOW_CONNECT='TRUE';
    'VSS'<1078>:
      PIN_NUMBER='(0,0,0,0,0,0,0,0,0,0,0,0,0,0,0,0,0,0,0,0,0,0,0,K73,0,0,0,0,0,0)';
      PINUSE='GROUND';
      NO_LOAD_CHECK='Both';
      NO_IO_CHECK='Both';
      NO_ASSERT_CHECK='TRUE';
      NO_DIR_CHECK='TRUE';
      ALLOW_CONNECT='TRUE';
    'VSS'<1077>:
      PIN_NUMBER='(0,0,0,0,0,0,0,0,0,0,0,0,0,0,0,0,0,0,0,0,0,0,0,K77,0,0,0,0,0,0)';
      PINUSE='GROUND';
      NO_LOAD_CHECK='Both';
      NO_IO_CHECK='Both';
      NO_ASSERT_CHECK='TRUE';
      NO_DIR_CHECK='TRUE';
      ALLOW_CONNECT='TRUE';
    'VSS'<1076>:
      PIN_NUMBER='(0,0,0,0,0,0,0,0,0,0,0,0,0,0,0,0,0,0,0,0,0,0,0,K81,0,0,0,0,0,0)';
      PINUSE='GROUND';
      NO_LOAD_CHECK='Both';
      NO_IO_CHECK='Both';
      NO_ASSERT_CHECK='TRUE';
      NO_DIR_CHECK='TRUE';
      ALLOW_CONNECT='TRUE';
    'VSS'<1075>:
      PIN_NUMBER='(0,0,0,0,0,0,0,0,0,0,0,0,0,0,0,0,0,0,0,0,0,0,0,K83,0,0,0,0,0,0)';
      PINUSE='GROUND';
      NO_LOAD_CHECK='Both';
      NO_IO_CHECK='Both';
      NO_ASSERT_CHECK='TRUE';
      NO_DIR_CHECK='TRUE';
      ALLOW_CONNECT='TRUE';
    'VSS'<1074>:
      PIN_NUMBER='(0,0,0,0,0,0,0,0,0,0,0,0,0,0,0,0,0,0,0,0,0,0,0,K85,0,0,0,0,0,0)';
      PINUSE='GROUND';
      NO_LOAD_CHECK='Both';
      NO_IO_CHECK='Both';
      NO_ASSERT_CHECK='TRUE';
      NO_DIR_CHECK='TRUE';
      ALLOW_CONNECT='TRUE';
    'VSS'<1073>:
      PIN_NUMBER='(0,0,0,0,0,0,0,0,0,0,0,0,0,0,0,0,0,0,0,0,0,0,0,L10,0,0,0,0,0,0)';
      PINUSE='GROUND';
      NO_LOAD_CHECK='Both';
      NO_IO_CHECK='Both';
      NO_ASSERT_CHECK='TRUE';
      NO_DIR_CHECK='TRUE';
      ALLOW_CONNECT='TRUE';
    'VSS'<1072>:
      PIN_NUMBER='(0,0,0,0,0,0,0,0,0,0,0,0,0,0,0,0,0,0,0,0,0,0,0,L2,0,0,0,0,0,0)';
      PINUSE='GROUND';
      NO_LOAD_CHECK='Both';
      NO_IO_CHECK='Both';
      NO_ASSERT_CHECK='TRUE';
      NO_DIR_CHECK='TRUE';
      ALLOW_CONNECT='TRUE';
    'VSS'<1071>:
      PIN_NUMBER='(0,0,0,0,0,0,0,0,0,0,0,0,0,0,0,0,0,0,0,0,0,0,0,L6,0,0,0,0,0,0)';
      PINUSE='GROUND';
      NO_LOAD_CHECK='Both';
      NO_IO_CHECK='Both';
      NO_ASSERT_CHECK='TRUE';
      NO_DIR_CHECK='TRUE';
      ALLOW_CONNECT='TRUE';
    'VSS'<1070>:
      PIN_NUMBER='(0,0,0,0,0,0,0,0,0,0,0,0,0,0,0,0,0,0,0,0,0,0,0,L20,0,0,0,0,0,0)';
      PINUSE='GROUND';
      NO_LOAD_CHECK='Both';
      NO_IO_CHECK='Both';
      NO_ASSERT_CHECK='TRUE';
      NO_DIR_CHECK='TRUE';
      ALLOW_CONNECT='TRUE';
    'VSS'<1069>:
      PIN_NUMBER='(0,0,0,0,0,0,0,0,0,0,0,0,0,0,0,0,0,0,0,0,0,0,0,L22,0,0,0,0,0,0)';
      PINUSE='GROUND';
      NO_LOAD_CHECK='Both';
      NO_IO_CHECK='Both';
      NO_ASSERT_CHECK='TRUE';
      NO_DIR_CHECK='TRUE';
      ALLOW_CONNECT='TRUE';
    'VSS'<1068>:
      PIN_NUMBER='(0,0,0,0,0,0,0,0,0,0,0,0,0,0,0,0,0,0,0,0,0,0,0,L72,0,0,0,0,0,0)';
      PINUSE='GROUND';
      NO_LOAD_CHECK='Both';
      NO_IO_CHECK='Both';
      NO_ASSERT_CHECK='TRUE';
      NO_DIR_CHECK='TRUE';
      ALLOW_CONNECT='TRUE';
    'VSS'<1067>:
      PIN_NUMBER='(0,0,0,0,0,0,0,0,0,0,0,0,0,0,0,0,0,0,0,0,0,0,0,L78,0,0,0,0,0,0)';
      PINUSE='GROUND';
      NO_LOAD_CHECK='Both';
      NO_IO_CHECK='Both';
      NO_ASSERT_CHECK='TRUE';
      NO_DIR_CHECK='TRUE';
      ALLOW_CONNECT='TRUE';
    'VSS'<1066>:
      PIN_NUMBER='(0,0,0,0,0,0,0,0,0,0,0,0,0,0,0,0,0,0,0,0,0,0,0,L80,0,0,0,0,0,0)';
      PINUSE='GROUND';
      NO_LOAD_CHECK='Both';
      NO_IO_CHECK='Both';
      NO_ASSERT_CHECK='TRUE';
      NO_DIR_CHECK='TRUE';
      ALLOW_CONNECT='TRUE';
    'VSS'<1065>:
      PIN_NUMBER='(0,0,0,0,0,0,0,0,0,0,0,0,0,0,0,0,0,0,0,0,0,0,0,L82,0,0,0,0,0,0)';
      PINUSE='GROUND';
      NO_LOAD_CHECK='Both';
      NO_IO_CHECK='Both';
      NO_ASSERT_CHECK='TRUE';
      NO_DIR_CHECK='TRUE';
      ALLOW_CONNECT='TRUE';
    'VSS'<1064>:
      PIN_NUMBER='(0,0,0,0,0,0,0,0,0,0,0,0,0,0,0,0,0,0,0,0,0,0,0,BT9,0,0,0,0,0,0)';
      PINUSE='GROUND';
      NO_LOAD_CHECK='Both';
      NO_IO_CHECK='Both';
      NO_ASSERT_CHECK='TRUE';
      NO_DIR_CHECK='TRUE';
      ALLOW_CONNECT='TRUE';
    'VSS'<1063>:
      PIN_NUMBER='(0,0,0,0,0,0,0,0,0,0,0,0,0,0,0,0,0,0,0,0,0,0,0,CT7,0,0,0,0,0,0)';
      PINUSE='GROUND';
      NO_LOAD_CHECK='Both';
      NO_IO_CHECK='Both';
      NO_ASSERT_CHECK='TRUE';
      NO_DIR_CHECK='TRUE';
      ALLOW_CONNECT='TRUE';
    'VSS'<1062>:
      PIN_NUMBER='(0,0,0,0,0,0,0,0,0,0,0,0,0,0,0,0,0,0,0,0,0,0,0,M15,0,0,0,0,0,0)';
      PINUSE='GROUND';
      NO_LOAD_CHECK='Both';
      NO_IO_CHECK='Both';
      NO_ASSERT_CHECK='TRUE';
      NO_DIR_CHECK='TRUE';
      ALLOW_CONNECT='TRUE';
    'VSS'<1061>:
      PIN_NUMBER='(0,0,0,0,0,0,0,0,0,0,0,0,0,0,0,0,0,0,0,0,0,0,0,M17,0,0,0,0,0,0)';
      PINUSE='GROUND';
      NO_LOAD_CHECK='Both';
      NO_IO_CHECK='Both';
      NO_ASSERT_CHECK='TRUE';
      NO_DIR_CHECK='TRUE';
      ALLOW_CONNECT='TRUE';
    'VSS'<1060>:
      PIN_NUMBER='(0,0,0,0,0,0,0,0,0,0,0,0,0,0,0,0,0,0,0,0,0,0,0,M19,0,0,0,0,0,0)';
      PINUSE='GROUND';
      NO_LOAD_CHECK='Both';
      NO_IO_CHECK='Both';
      NO_ASSERT_CHECK='TRUE';
      NO_DIR_CHECK='TRUE';
      ALLOW_CONNECT='TRUE';
    'VSS'<1059>:
      PIN_NUMBER='(0,0,0,0,0,0,0,0,0,0,0,0,0,0,0,0,0,0,0,0,0,0,0,M23,0,0,0,0,0,0)';
      PINUSE='GROUND';
      NO_LOAD_CHECK='Both';
      NO_IO_CHECK='Both';
      NO_ASSERT_CHECK='TRUE';
      NO_DIR_CHECK='TRUE';
      ALLOW_CONNECT='TRUE';
    'VSS'<1058>:
      PIN_NUMBER='(0,0,0,0,0,0,0,0,0,0,0,0,0,0,0,0,0,0,0,0,0,0,0,M25,0,0,0,0,0,0)';
      PINUSE='GROUND';
      NO_LOAD_CHECK='Both';
      NO_IO_CHECK='Both';
      NO_ASSERT_CHECK='TRUE';
      NO_DIR_CHECK='TRUE';
      ALLOW_CONNECT='TRUE';
    'VSS'<1057>:
      PIN_NUMBER='(0,0,0,0,0,0,0,0,0,0,0,0,0,0,0,0,0,0,0,0,0,0,0,M27,0,0,0,0,0,0)';
      PINUSE='GROUND';
      NO_LOAD_CHECK='Both';
      NO_IO_CHECK='Both';
      NO_ASSERT_CHECK='TRUE';
      NO_DIR_CHECK='TRUE';
      ALLOW_CONNECT='TRUE';
    'VSS'<1056>:
      PIN_NUMBER='(0,0,0,0,0,0,0,0,0,0,0,0,0,0,0,0,0,0,0,0,0,0,0,M29,0,0,0,0,0,0)';
      PINUSE='GROUND';
      NO_LOAD_CHECK='Both';
      NO_IO_CHECK='Both';
      NO_ASSERT_CHECK='TRUE';
      NO_DIR_CHECK='TRUE';
      ALLOW_CONNECT='TRUE';
    'VSS'<1055>:
      PIN_NUMBER='(0,0,0,0,0,0,0,0,0,0,0,0,0,0,0,0,0,0,0,0,0,0,0,M31,0,0,0,0,0,0)';
      PINUSE='GROUND';
      NO_LOAD_CHECK='Both';
      NO_IO_CHECK='Both';
      NO_ASSERT_CHECK='TRUE';
      NO_DIR_CHECK='TRUE';
      ALLOW_CONNECT='TRUE';
    'VSS'<1054>:
      PIN_NUMBER='(0,0,0,0,0,0,0,0,0,0,0,0,0,0,0,0,0,0,0,0,0,0,0,M33,0,0,0,0,0,0)';
      PINUSE='GROUND';
      NO_LOAD_CHECK='Both';
      NO_IO_CHECK='Both';
      NO_ASSERT_CHECK='TRUE';
      NO_DIR_CHECK='TRUE';
      ALLOW_CONNECT='TRUE';
    'VSS'<1053>:
      PIN_NUMBER='(0,0,0,0,0,0,0,0,0,0,0,0,0,0,0,0,0,0,0,0,0,0,0,M35,0,0,0,0,0,0)';
      PINUSE='GROUND';
      NO_LOAD_CHECK='Both';
      NO_IO_CHECK='Both';
      NO_ASSERT_CHECK='TRUE';
      NO_DIR_CHECK='TRUE';
      ALLOW_CONNECT='TRUE';
    'VSS'<1052>:
      PIN_NUMBER='(0,0,0,0,0,0,0,0,0,0,0,0,0,0,0,0,0,0,0,0,0,0,0,M37,0,0,0,0,0,0)';
      PINUSE='GROUND';
      NO_LOAD_CHECK='Both';
      NO_IO_CHECK='Both';
      NO_ASSERT_CHECK='TRUE';
      NO_DIR_CHECK='TRUE';
      ALLOW_CONNECT='TRUE';
    'VSS'<1051>:
      PIN_NUMBER='(0,0,0,0,0,0,0,0,0,0,0,0,0,0,0,0,0,0,0,0,0,0,0,M39,0,0,0,0,0,0)';
      PINUSE='GROUND';
      NO_LOAD_CHECK='Both';
      NO_IO_CHECK='Both';
      NO_ASSERT_CHECK='TRUE';
      NO_DIR_CHECK='TRUE';
      ALLOW_CONNECT='TRUE';
    'VSS'<1050>:
      PIN_NUMBER='(0,0,0,0,0,0,0,0,0,0,0,0,0,0,0,0,0,0,0,0,0,0,0,M41,0,0,0,0,0,0)';
      PINUSE='GROUND';
      NO_LOAD_CHECK='Both';
      NO_IO_CHECK='Both';
      NO_ASSERT_CHECK='TRUE';
      NO_DIR_CHECK='TRUE';
      ALLOW_CONNECT='TRUE';
    'VSS'<1049>:
      PIN_NUMBER='(0,0,0,0,0,0,0,0,0,0,0,0,0,0,0,0,0,0,0,0,0,0,0,M43,0,0,0,0,0,0)';
      PINUSE='GROUND';
      NO_LOAD_CHECK='Both';
      NO_IO_CHECK='Both';
      NO_ASSERT_CHECK='TRUE';
      NO_DIR_CHECK='TRUE';
      ALLOW_CONNECT='TRUE';
    'VSS'<1048>:
      PIN_NUMBER='(0,0,0,0,0,0,0,0,0,0,0,0,0,0,0,0,0,0,0,0,0,0,0,M65,0,0,0,0,0,0)';
      PINUSE='GROUND';
      NO_LOAD_CHECK='Both';
      NO_IO_CHECK='Both';
      NO_ASSERT_CHECK='TRUE';
      NO_DIR_CHECK='TRUE';
      ALLOW_CONNECT='TRUE';
    'VSS'<1047>:
      PIN_NUMBER='(0,0,0,0,0,0,0,0,0,0,0,0,0,0,0,0,0,0,0,0,0,0,0,M71,0,0,0,0,0,0)';
      PINUSE='GROUND';
      NO_LOAD_CHECK='Both';
      NO_IO_CHECK='Both';
      NO_ASSERT_CHECK='TRUE';
      NO_DIR_CHECK='TRUE';
      ALLOW_CONNECT='TRUE';
    'VSS'<1046>:
      PIN_NUMBER='(0,0,0,0,0,0,0,0,0,0,0,0,0,0,0,0,0,0,0,0,0,0,0,M79,0,0,0,0,0,0)';
      PINUSE='GROUND';
      NO_LOAD_CHECK='Both';
      NO_IO_CHECK='Both';
      NO_ASSERT_CHECK='TRUE';
      NO_DIR_CHECK='TRUE';
      ALLOW_CONNECT='TRUE';
    'VSS'<1045>:
      PIN_NUMBER='(0,0,0,0,0,0,0,0,0,0,0,0,0,0,0,0,0,0,0,0,0,0,0,M83,0,0,0,0,0,0)';
      PINUSE='GROUND';
      NO_LOAD_CHECK='Both';
      NO_IO_CHECK='Both';
      NO_ASSERT_CHECK='TRUE';
      NO_DIR_CHECK='TRUE';
      ALLOW_CONNECT='TRUE';
    'VSS'<1044>:
      PIN_NUMBER='(0,0,0,0,0,0,0,0,0,0,0,0,0,0,0,0,0,0,0,0,0,0,0,M85,0,0,0,0,0,0)';
      PINUSE='GROUND';
      NO_LOAD_CHECK='Both';
      NO_IO_CHECK='Both';
      NO_ASSERT_CHECK='TRUE';
      NO_DIR_CHECK='TRUE';
      ALLOW_CONNECT='TRUE';
    'VSS'<1043>:
      PIN_NUMBER='(0,0,0,0,0,0,0,0,0,0,0,0,0,0,0,0,0,0,0,0,0,0,0,DM19,0,0,0,0,0,0)';
      PINUSE='GROUND';
      NO_LOAD_CHECK='Both';
      NO_IO_CHECK='Both';
      NO_ASSERT_CHECK='TRUE';
      NO_DIR_CHECK='TRUE';
      ALLOW_CONNECT='TRUE';
    'VSS'<1042>:
      PIN_NUMBER='(0,0,0,0,0,0,0,0,0,0,0,0,0,0,0,0,0,0,0,0,0,0,0,N20,0,0,0,0,0,0)';
      PINUSE='GROUND';
      NO_LOAD_CHECK='Both';
      NO_IO_CHECK='Both';
      NO_ASSERT_CHECK='TRUE';
      NO_DIR_CHECK='TRUE';
      ALLOW_CONNECT='TRUE';
    'VSS'<1041>:
      PIN_NUMBER='(0,0,0,0,0,0,0,0,0,0,0,0,0,0,0,0,0,0,0,0,0,0,0,N22,0,0,0,0,0,0)';
      PINUSE='GROUND';
      NO_LOAD_CHECK='Both';
      NO_IO_CHECK='Both';
      NO_ASSERT_CHECK='TRUE';
      NO_DIR_CHECK='TRUE';
      ALLOW_CONNECT='TRUE';
    'VSS'<1040>:
      PIN_NUMBER='(0,0,0,0,0,0,0,0,0,0,0,0,0,0,0,0,0,0,0,0,0,0,0,N6,0,0,0,0,0,0)';
      PINUSE='GROUND';
      NO_LOAD_CHECK='Both';
      NO_IO_CHECK='Both';
      NO_ASSERT_CHECK='TRUE';
      NO_DIR_CHECK='TRUE';
      ALLOW_CONNECT='TRUE';
    'VSS'<1039>:
      PIN_NUMBER='(0,0,0,0,0,0,0,0,0,0,0,0,0,0,0,0,0,0,0,0,0,0,0,N66,0,0,0,0,0,0)';
      PINUSE='GROUND';
      NO_LOAD_CHECK='Both';
      NO_IO_CHECK='Both';
      NO_ASSERT_CHECK='TRUE';
      NO_DIR_CHECK='TRUE';
      ALLOW_CONNECT='TRUE';
    'VSS'<1038>:
      PIN_NUMBER='(0,0,0,0,0,0,0,0,0,0,0,0,0,0,0,0,0,0,0,0,0,0,0,N70,0,0,0,0,0,0)';
      PINUSE='GROUND';
      NO_LOAD_CHECK='Both';
      NO_IO_CHECK='Both';
      NO_ASSERT_CHECK='TRUE';
      NO_DIR_CHECK='TRUE';
      ALLOW_CONNECT='TRUE';
    'VSS'<1037>:
      PIN_NUMBER='(0,0,0,0,0,0,0,0,0,0,0,0,0,0,0,0,0,0,0,0,0,0,0,N72,0,0,0,0,0,0)';
      PINUSE='GROUND';
      NO_LOAD_CHECK='Both';
      NO_IO_CHECK='Both';
      NO_ASSERT_CHECK='TRUE';
      NO_DIR_CHECK='TRUE';
      ALLOW_CONNECT='TRUE';
    'VSS'<1036>:
      PIN_NUMBER='(0,0,0,0,0,0,0,0,0,0,0,0,0,0,0,0,0,0,0,0,0,0,0,N74,0,0,0,0,0,0)';
      PINUSE='GROUND';
      NO_LOAD_CHECK='Both';
      NO_IO_CHECK='Both';
      NO_ASSERT_CHECK='TRUE';
      NO_DIR_CHECK='TRUE';
      ALLOW_CONNECT='TRUE';
    'VSS'<1035>:
      PIN_NUMBER='(0,0,0,0,0,0,0,0,0,0,0,0,0,0,0,0,0,0,0,0,0,0,0,N76,0,0,0,0,0,0)';
      PINUSE='GROUND';
      NO_LOAD_CHECK='Both';
      NO_IO_CHECK='Both';
      NO_ASSERT_CHECK='TRUE';
      NO_DIR_CHECK='TRUE';
      ALLOW_CONNECT='TRUE';
    'VSS'<1034>:
      PIN_NUMBER='(0,0,0,0,0,0,0,0,0,0,0,0,0,0,0,0,0,0,0,0,0,0,0,N78,0,0,0,0,0,0)';
      PINUSE='GROUND';
      NO_LOAD_CHECK='Both';
      NO_IO_CHECK='Both';
      NO_ASSERT_CHECK='TRUE';
      NO_DIR_CHECK='TRUE';
      ALLOW_CONNECT='TRUE';
    'VSS'<1033>:
      PIN_NUMBER='(0,0,0,0,0,0,0,0,0,0,0,0,0,0,0,0,0,0,0,0,0,0,0,N4,0,0,0,0,0,0)';
      PINUSE='GROUND';
      NO_LOAD_CHECK='Both';
      NO_IO_CHECK='Both';
      NO_ASSERT_CHECK='TRUE';
      NO_DIR_CHECK='TRUE';
      ALLOW_CONNECT='TRUE';
    'VSS'<1032>:
      PIN_NUMBER='(0,0,0,0,0,0,0,0,0,0,0,0,0,0,0,0,0,0,0,0,0,0,0,N8,0,0,0,0,0,0)';
      PINUSE='GROUND';
      NO_LOAD_CHECK='Both';
      NO_IO_CHECK='Both';
      NO_ASSERT_CHECK='TRUE';
      NO_DIR_CHECK='TRUE';
      ALLOW_CONNECT='TRUE';
    'VSS'<1031>:
      PIN_NUMBER='(0,0,0,0,0,0,0,0,0,0,0,0,0,0,0,0,0,0,0,0,0,0,0,P11,0,0,0,0,0,0)';
      PINUSE='GROUND';
      NO_LOAD_CHECK='Both';
      NO_IO_CHECK='Both';
      NO_ASSERT_CHECK='TRUE';
      NO_DIR_CHECK='TRUE';
      ALLOW_CONNECT='TRUE';
    'VSS'<1030>:
      PIN_NUMBER='(0,0,0,0,0,0,0,0,0,0,0,0,0,0,0,0,0,0,0,0,0,0,0,P15,0,0,0,0,0,0)';
      PINUSE='GROUND';
      NO_LOAD_CHECK='Both';
      NO_IO_CHECK='Both';
      NO_ASSERT_CHECK='TRUE';
      NO_DIR_CHECK='TRUE';
      ALLOW_CONNECT='TRUE';
    'VSS'<1029>:
      PIN_NUMBER='(0,0,0,0,0,0,0,0,0,0,0,0,0,0,0,0,0,0,0,0,0,0,0,P27,0,0,0,0,0,0)';
      PINUSE='GROUND';
      NO_LOAD_CHECK='Both';
      NO_IO_CHECK='Both';
      NO_ASSERT_CHECK='TRUE';
      NO_DIR_CHECK='TRUE';
      ALLOW_CONNECT='TRUE';
    'VSS'<1028>:
      PIN_NUMBER='(0,0,0,0,0,0,0,0,0,0,0,0,0,0,0,0,0,0,0,0,0,0,0,P33,0,0,0,0,0,0)';
      PINUSE='GROUND';
      NO_LOAD_CHECK='Both';
      NO_IO_CHECK='Both';
      NO_ASSERT_CHECK='TRUE';
      NO_DIR_CHECK='TRUE';
      ALLOW_CONNECT='TRUE';
    'VSS'<1027>:
      PIN_NUMBER='(0,0,0,0,0,0,0,0,0,0,0,0,0,0,0,0,0,0,0,0,0,0,0,P39,0,0,0,0,0,0)';
      PINUSE='GROUND';
      NO_LOAD_CHECK='Both';
      NO_IO_CHECK='Both';
      NO_ASSERT_CHECK='TRUE';
      NO_DIR_CHECK='TRUE';
      ALLOW_CONNECT='TRUE';
    'VSS'<1026>:
      PIN_NUMBER='(0,0,0,0,0,0,0,0,0,0,0,0,0,0,0,0,0,0,0,0,0,0,0,P67,0,0,0,0,0,0)';
      PINUSE='GROUND';
      NO_LOAD_CHECK='Both';
      NO_IO_CHECK='Both';
      NO_ASSERT_CHECK='TRUE';
      NO_DIR_CHECK='TRUE';
      ALLOW_CONNECT='TRUE';
    'VSS'<1025>:
      PIN_NUMBER='(0,0,0,0,0,0,0,0,0,0,0,0,0,0,0,0,0,0,0,0,0,0,0,P69,0,0,0,0,0,0)';
      PINUSE='GROUND';
      NO_LOAD_CHECK='Both';
      NO_IO_CHECK='Both';
      NO_ASSERT_CHECK='TRUE';
      NO_DIR_CHECK='TRUE';
      ALLOW_CONNECT='TRUE';
    'VSS'<1024>:
      PIN_NUMBER='(0,0,0,0,0,0,0,0,0,0,0,0,0,0,0,0,0,0,0,0,0,0,0,P71,0,0,0,0,0,0)';
      PINUSE='GROUND';
      NO_LOAD_CHECK='Both';
      NO_IO_CHECK='Both';
      NO_ASSERT_CHECK='TRUE';
      NO_DIR_CHECK='TRUE';
      ALLOW_CONNECT='TRUE';
    'VSS'<1023>:
      PIN_NUMBER='(0,0,0,0,0,0,0,0,0,0,0,0,0,0,0,0,0,0,0,0,0,0,0,P81,0,0,0,0,0,0)';
      PINUSE='GROUND';
      NO_LOAD_CHECK='Both';
      NO_IO_CHECK='Both';
      NO_ASSERT_CHECK='TRUE';
      NO_DIR_CHECK='TRUE';
      ALLOW_CONNECT='TRUE';
    'VSS'<1022>:
      PIN_NUMBER='(0,0,0,0,0,0,0,0,0,0,0,0,0,0,0,0,0,0,0,0,0,0,0,P83,0,0,0,0,0,0)';
      PINUSE='GROUND';
      NO_LOAD_CHECK='Both';
      NO_IO_CHECK='Both';
      NO_ASSERT_CHECK='TRUE';
      NO_DIR_CHECK='TRUE';
      ALLOW_CONNECT='TRUE';
    'VSS'<1021>:
      PIN_NUMBER='(0,0,0,0,0,0,0,0,0,0,0,0,0,0,0,0,0,0,0,0,0,0,0,R14,0,0,0,0,0,0)';
      PINUSE='GROUND';
      NO_LOAD_CHECK='Both';
      NO_IO_CHECK='Both';
      NO_ASSERT_CHECK='TRUE';
      NO_DIR_CHECK='TRUE';
      ALLOW_CONNECT='TRUE';
    'VSS'<1020>:
      PIN_NUMBER='(0,0,0,0,0,0,0,0,0,0,0,0,0,0,0,0,0,0,0,0,0,0,0,R18,0,0,0,0,0,0)';
      PINUSE='GROUND';
      NO_LOAD_CHECK='Both';
      NO_IO_CHECK='Both';
      NO_ASSERT_CHECK='TRUE';
      NO_DIR_CHECK='TRUE';
      ALLOW_CONNECT='TRUE';
    'VSS'<1019>:
      PIN_NUMBER='(0,0,0,0,0,0,0,0,0,0,0,0,0,0,0,0,0,0,0,0,0,0,0,R2,0,0,0,0,0,0)';
      PINUSE='GROUND';
      NO_LOAD_CHECK='Both';
      NO_IO_CHECK='Both';
      NO_ASSERT_CHECK='TRUE';
      NO_DIR_CHECK='TRUE';
      ALLOW_CONNECT='TRUE';
    'VSS'<1018>:
      PIN_NUMBER='(0,0,0,0,0,0,0,0,0,0,0,0,0,0,0,0,0,0,0,0,0,0,0,R4,0,0,0,0,0,0)';
      PINUSE='GROUND';
      NO_LOAD_CHECK='Both';
      NO_IO_CHECK='Both';
      NO_ASSERT_CHECK='TRUE';
      NO_DIR_CHECK='TRUE';
      ALLOW_CONNECT='TRUE';
    'VSS'<1017>:
      PIN_NUMBER='(0,0,0,0,0,0,0,0,0,0,0,0,0,0,0,0,0,0,0,0,0,0,0,R22,0,0,0,0,0,0)';
      PINUSE='GROUND';
      NO_LOAD_CHECK='Both';
      NO_IO_CHECK='Both';
      NO_ASSERT_CHECK='TRUE';
      NO_DIR_CHECK='TRUE';
      ALLOW_CONNECT='TRUE';
    'VSS'<1016>:
      PIN_NUMBER='(0,0,0,0,0,0,0,0,0,0,0,0,0,0,0,0,0,0,0,0,0,0,0,R26,0,0,0,0,0,0)';
      PINUSE='GROUND';
      NO_LOAD_CHECK='Both';
      NO_IO_CHECK='Both';
      NO_ASSERT_CHECK='TRUE';
      NO_DIR_CHECK='TRUE';
      ALLOW_CONNECT='TRUE';
    'VSS'<1015>:
      PIN_NUMBER='(0,0,0,0,0,0,0,0,0,0,0,0,0,0,0,0,0,0,0,0,0,0,0,R28,0,0,0,0,0,0)';
      PINUSE='GROUND';
      NO_LOAD_CHECK='Both';
      NO_IO_CHECK='Both';
      NO_ASSERT_CHECK='TRUE';
      NO_DIR_CHECK='TRUE';
      ALLOW_CONNECT='TRUE';
    'VSS'<1014>:
      PIN_NUMBER='(0,0,0,0,0,0,0,0,0,0,0,0,0,0,0,0,0,0,0,0,0,0,0,R32,0,0,0,0,0,0)';
      PINUSE='GROUND';
      NO_LOAD_CHECK='Both';
      NO_IO_CHECK='Both';
      NO_ASSERT_CHECK='TRUE';
      NO_DIR_CHECK='TRUE';
      ALLOW_CONNECT='TRUE';
    'VSS'<1013>:
      PIN_NUMBER='(0,0,0,0,0,0,0,0,0,0,0,0,0,0,0,0,0,0,0,0,0,0,0,R34,0,0,0,0,0,0)';
      PINUSE='GROUND';
      NO_LOAD_CHECK='Both';
      NO_IO_CHECK='Both';
      NO_ASSERT_CHECK='TRUE';
      NO_DIR_CHECK='TRUE';
      ALLOW_CONNECT='TRUE';
    'VSS'<1012>:
      PIN_NUMBER='(0,0,0,0,0,0,0,0,0,0,0,0,0,0,0,0,0,0,0,0,0,0,0,R38,0,0,0,0,0,0)';
      PINUSE='GROUND';
      NO_LOAD_CHECK='Both';
      NO_IO_CHECK='Both';
      NO_ASSERT_CHECK='TRUE';
      NO_DIR_CHECK='TRUE';
      ALLOW_CONNECT='TRUE';
    'VSS'<1011>:
      PIN_NUMBER='(0,0,0,0,0,0,0,0,0,0,0,0,0,0,0,0,0,0,0,0,0,0,0,R40,0,0,0,0,0,0)';
      PINUSE='GROUND';
      NO_LOAD_CHECK='Both';
      NO_IO_CHECK='Both';
      NO_ASSERT_CHECK='TRUE';
      NO_DIR_CHECK='TRUE';
      ALLOW_CONNECT='TRUE';
    'VSS'<1010>:
      PIN_NUMBER='(0,0,0,0,0,0,0,0,0,0,0,0,0,0,0,0,0,0,0,0,0,0,0,R68,0,0,0,0,0,0)';
      PINUSE='GROUND';
      NO_LOAD_CHECK='Both';
      NO_IO_CHECK='Both';
      NO_ASSERT_CHECK='TRUE';
      NO_DIR_CHECK='TRUE';
      ALLOW_CONNECT='TRUE';
    'VSS'<1009>:
      PIN_NUMBER='(0,0,0,0,0,0,0,0,0,0,0,0,0,0,0,0,0,0,0,0,0,0,0,R72,0,0,0,0,0,0)';
      PINUSE='GROUND';
      NO_LOAD_CHECK='Both';
      NO_IO_CHECK='Both';
      NO_ASSERT_CHECK='TRUE';
      NO_DIR_CHECK='TRUE';
      ALLOW_CONNECT='TRUE';
    'VSS'<1008>:
      PIN_NUMBER='(0,0,0,0,0,0,0,0,0,0,0,0,0,0,0,0,0,0,0,0,0,0,0,R78,0,0,0,0,0,0)';
      PINUSE='GROUND';
      NO_LOAD_CHECK='Both';
      NO_IO_CHECK='Both';
      NO_ASSERT_CHECK='TRUE';
      NO_DIR_CHECK='TRUE';
      ALLOW_CONNECT='TRUE';
    'VSS'<1007>:
      PIN_NUMBER='(0,0,0,0,0,0,0,0,0,0,0,0,0,0,0,0,0,0,0,0,0,0,0,R86,0,0,0,0,0,0)';
      PINUSE='GROUND';
      NO_LOAD_CHECK='Both';
      NO_IO_CHECK='Both';
      NO_ASSERT_CHECK='TRUE';
      NO_DIR_CHECK='TRUE';
      ALLOW_CONNECT='TRUE';
    'VSS'<1006>:
      PIN_NUMBER='(0,0,0,0,0,0,0,0,0,0,0,0,0,0,0,0,0,0,0,0,0,0,0,T13,0,0,0,0,0,0)';
      PINUSE='GROUND';
      NO_LOAD_CHECK='Both';
      NO_IO_CHECK='Both';
      NO_ASSERT_CHECK='TRUE';
      NO_DIR_CHECK='TRUE';
      ALLOW_CONNECT='TRUE';
    'VSS'<1005>:
      PIN_NUMBER='(0,0,0,0,0,0,0,0,0,0,0,0,0,0,0,0,0,0,0,0,0,0,0,T17,0,0,0,0,0,0)';
      PINUSE='GROUND';
      NO_LOAD_CHECK='Both';
      NO_IO_CHECK='Both';
      NO_ASSERT_CHECK='TRUE';
      NO_DIR_CHECK='TRUE';
      ALLOW_CONNECT='TRUE';
    'VSS'<1004>:
      PIN_NUMBER='(0,0,0,0,0,0,0,0,0,0,0,0,0,0,0,0,0,0,0,0,0,0,0,T25,0,0,0,0,0,0)';
      PINUSE='GROUND';
      NO_LOAD_CHECK='Both';
      NO_IO_CHECK='Both';
      NO_ASSERT_CHECK='TRUE';
      NO_DIR_CHECK='TRUE';
      ALLOW_CONNECT='TRUE';
    'VSS'<1003>:
      PIN_NUMBER='(0,0,0,0,0,0,0,0,0,0,0,0,0,0,0,0,0,0,0,0,0,0,0,T29,0,0,0,0,0,0)';
      PINUSE='GROUND';
      NO_LOAD_CHECK='Both';
      NO_IO_CHECK='Both';
      NO_ASSERT_CHECK='TRUE';
      NO_DIR_CHECK='TRUE';
      ALLOW_CONNECT='TRUE';
    'VSS'<1002>:
      PIN_NUMBER='(0,0,0,0,0,0,0,0,0,0,0,0,0,0,0,0,0,0,0,0,0,0,0,T31,0,0,0,0,0,0)';
      PINUSE='GROUND';
      NO_LOAD_CHECK='Both';
      NO_IO_CHECK='Both';
      NO_ASSERT_CHECK='TRUE';
      NO_DIR_CHECK='TRUE';
      ALLOW_CONNECT='TRUE';
    'VSS'<1001>:
      PIN_NUMBER='(0,0,0,0,0,0,0,0,0,0,0,0,0,0,0,0,0,0,0,0,0,0,0,T35,0,0,0,0,0,0)';
      PINUSE='GROUND';
      NO_LOAD_CHECK='Both';
      NO_IO_CHECK='Both';
      NO_ASSERT_CHECK='TRUE';
      NO_DIR_CHECK='TRUE';
      ALLOW_CONNECT='TRUE';
    'VSS'<1000>:
      PIN_NUMBER='(0,0,0,0,0,0,0,0,0,0,0,0,0,0,0,0,0,0,0,0,0,0,0,T37,0,0,0,0,0,0)';
      PINUSE='GROUND';
      NO_LOAD_CHECK='Both';
      NO_IO_CHECK='Both';
      NO_ASSERT_CHECK='TRUE';
      NO_DIR_CHECK='TRUE';
      ALLOW_CONNECT='TRUE';
    'VSS'<999>:
      PIN_NUMBER='(0,0,0,0,0,0,0,0,0,0,0,0,0,0,0,0,0,0,0,0,0,0,0,T41,0,0,0,0,0,0)';
      PINUSE='GROUND';
      NO_LOAD_CHECK='Both';
      NO_IO_CHECK='Both';
      NO_ASSERT_CHECK='TRUE';
      NO_DIR_CHECK='TRUE';
      ALLOW_CONNECT='TRUE';
    'VSS'<998>:
      PIN_NUMBER='(0,0,0,0,0,0,0,0,0,0,0,0,0,0,0,0,0,0,0,0,0,0,0,T65,0,0,0,0,0,0)';
      PINUSE='GROUND';
      NO_LOAD_CHECK='Both';
      NO_IO_CHECK='Both';
      NO_ASSERT_CHECK='TRUE';
      NO_DIR_CHECK='TRUE';
      ALLOW_CONNECT='TRUE';
    'VSS'<997>:
      PIN_NUMBER='(0,0,0,0,0,0,0,0,0,0,0,0,0,0,0,0,0,0,0,0,0,0,0,T73,0,0,0,0,0,0)';
      PINUSE='GROUND';
      NO_LOAD_CHECK='Both';
      NO_IO_CHECK='Both';
      NO_ASSERT_CHECK='TRUE';
      NO_DIR_CHECK='TRUE';
      ALLOW_CONNECT='TRUE';
    'VSS'<996>:
      PIN_NUMBER='(0,0,0,0,0,0,0,0,0,0,0,0,0,0,0,0,0,0,0,0,0,0,0,T77,0,0,0,0,0,0)';
      PINUSE='GROUND';
      NO_LOAD_CHECK='Both';
      NO_IO_CHECK='Both';
      NO_ASSERT_CHECK='TRUE';
      NO_DIR_CHECK='TRUE';
      ALLOW_CONNECT='TRUE';
    'VSS'<995>:
      PIN_NUMBER='(0,0,0,0,0,0,0,0,0,0,0,0,0,0,0,0,0,0,0,0,0,0,0,T83,0,0,0,0,0,0)';
      PINUSE='GROUND';
      NO_LOAD_CHECK='Both';
      NO_IO_CHECK='Both';
      NO_ASSERT_CHECK='TRUE';
      NO_DIR_CHECK='TRUE';
      ALLOW_CONNECT='TRUE';
    'VSS'<994>:
      PIN_NUMBER='(0,0,0,0,0,0,0,0,0,0,0,0,0,0,0,0,0,0,0,0,0,0,0,T85,0,0,0,0,0,0)';
      PINUSE='GROUND';
      NO_LOAD_CHECK='Both';
      NO_IO_CHECK='Both';
      NO_ASSERT_CHECK='TRUE';
      NO_DIR_CHECK='TRUE';
      ALLOW_CONNECT='TRUE';
    'VSS'<993>:
      PIN_NUMBER='(0,0,0,0,0,0,0,0,0,0,0,0,0,0,0,0,0,0,0,0,0,0,0,U2,0,0,0,0,0,0)';
      PINUSE='GROUND';
      NO_LOAD_CHECK='Both';
      NO_IO_CHECK='Both';
      NO_ASSERT_CHECK='TRUE';
      NO_DIR_CHECK='TRUE';
      ALLOW_CONNECT='TRUE';
    'VSS'<992>:
      PIN_NUMBER='(0,0,0,0,0,0,0,0,0,0,0,0,0,0,0,0,0,0,0,0,0,0,0,U4,0,0,0,0,0,0)';
      PINUSE='GROUND';
      NO_LOAD_CHECK='Both';
      NO_IO_CHECK='Both';
      NO_ASSERT_CHECK='TRUE';
      NO_DIR_CHECK='TRUE';
      ALLOW_CONNECT='TRUE';
    'VSS'<991>:
      PIN_NUMBER='(0,0,0,0,0,0,0,0,0,0,0,0,0,0,0,0,0,0,0,0,0,0,0,U6,0,0,0,0,0,0)';
      PINUSE='GROUND';
      NO_LOAD_CHECK='Both';
      NO_IO_CHECK='Both';
      NO_ASSERT_CHECK='TRUE';
      NO_DIR_CHECK='TRUE';
      ALLOW_CONNECT='TRUE';
    'VSS'<990>:
      PIN_NUMBER='(0,0,0,0,0,0,0,0,0,0,0,0,0,0,0,0,0,0,0,0,0,0,0,U20,0,0,0,0,0,0)';
      PINUSE='GROUND';
      NO_LOAD_CHECK='Both';
      NO_IO_CHECK='Both';
      NO_ASSERT_CHECK='TRUE';
      NO_DIR_CHECK='TRUE';
      ALLOW_CONNECT='TRUE';
    'VSS'<989>:
      PIN_NUMBER='(0,0,0,0,0,0,0,0,0,0,0,0,0,0,0,0,0,0,0,0,0,0,0,U22,0,0,0,0,0,0)';
      PINUSE='GROUND';
      NO_LOAD_CHECK='Both';
      NO_IO_CHECK='Both';
      NO_ASSERT_CHECK='TRUE';
      NO_DIR_CHECK='TRUE';
      ALLOW_CONNECT='TRUE';
    'VSS'<988>:
      PIN_NUMBER='(0,0,0,0,0,0,0,0,0,0,0,0,0,0,0,0,0,0,0,0,0,0,0,U24,0,0,0,0,0,0)';
      PINUSE='GROUND';
      NO_LOAD_CHECK='Both';
      NO_IO_CHECK='Both';
      NO_ASSERT_CHECK='TRUE';
      NO_DIR_CHECK='TRUE';
      ALLOW_CONNECT='TRUE';
    'VSS'<987>:
      PIN_NUMBER='(0,0,0,0,0,0,0,0,0,0,0,0,0,0,0,0,0,0,0,0,0,0,0,U30,0,0,0,0,0,0)';
      PINUSE='GROUND';
      NO_LOAD_CHECK='Both';
      NO_IO_CHECK='Both';
      NO_ASSERT_CHECK='TRUE';
      NO_DIR_CHECK='TRUE';
      ALLOW_CONNECT='TRUE';
    'VSS'<986>:
      PIN_NUMBER='(0,0,0,0,0,0,0,0,0,0,0,0,0,0,0,0,0,0,0,0,0,0,0,U36,0,0,0,0,0,0)';
      PINUSE='GROUND';
      NO_LOAD_CHECK='Both';
      NO_IO_CHECK='Both';
      NO_ASSERT_CHECK='TRUE';
      NO_DIR_CHECK='TRUE';
      ALLOW_CONNECT='TRUE';
    'VSS'<985>:
      PIN_NUMBER='(0,0,0,0,0,0,0,0,0,0,0,0,0,0,0,0,0,0,0,0,0,0,0,U42,0,0,0,0,0,0)';
      PINUSE='GROUND';
      NO_LOAD_CHECK='Both';
      NO_IO_CHECK='Both';
      NO_ASSERT_CHECK='TRUE';
      NO_DIR_CHECK='TRUE';
      ALLOW_CONNECT='TRUE';
    'VSS'<984>:
      PIN_NUMBER='(0,0,0,0,0,0,0,0,0,0,0,0,0,0,0,0,0,0,0,0,0,0,0,U68,0,0,0,0,0,0)';
      PINUSE='GROUND';
      NO_LOAD_CHECK='Both';
      NO_IO_CHECK='Both';
      NO_ASSERT_CHECK='TRUE';
      NO_DIR_CHECK='TRUE';
      ALLOW_CONNECT='TRUE';
    'VSS'<983>:
      PIN_NUMBER='(0,0,0,0,0,0,0,0,0,0,0,0,0,0,0,0,0,0,0,0,0,0,0,U70,0,0,0,0,0,0)';
      PINUSE='GROUND';
      NO_LOAD_CHECK='Both';
      NO_IO_CHECK='Both';
      NO_ASSERT_CHECK='TRUE';
      NO_DIR_CHECK='TRUE';
      ALLOW_CONNECT='TRUE';
    'VSS'<982>:
      PIN_NUMBER='(0,0,0,0,0,0,0,0,0,0,0,0,0,0,0,0,0,0,0,0,0,0,0,U74,0,0,0,0,0,0)';
      PINUSE='GROUND';
      NO_LOAD_CHECK='Both';
      NO_IO_CHECK='Both';
      NO_ASSERT_CHECK='TRUE';
      NO_DIR_CHECK='TRUE';
      ALLOW_CONNECT='TRUE';
    'VSS'<981>:
      PIN_NUMBER='(0,0,0,0,0,0,0,0,0,0,0,0,0,0,0,0,0,0,0,0,0,0,0,U76,0,0,0,0,0,0)';
      PINUSE='GROUND';
      NO_LOAD_CHECK='Both';
      NO_IO_CHECK='Both';
      NO_ASSERT_CHECK='TRUE';
      NO_DIR_CHECK='TRUE';
      ALLOW_CONNECT='TRUE';
    'VSS'<980>:
      PIN_NUMBER='(0,0,0,0,0,0,0,0,0,0,0,0,0,0,0,0,0,0,0,0,0,0,0,U78,0,0,0,0,0,0)';
      PINUSE='GROUND';
      NO_LOAD_CHECK='Both';
      NO_IO_CHECK='Both';
      NO_ASSERT_CHECK='TRUE';
      NO_DIR_CHECK='TRUE';
      ALLOW_CONNECT='TRUE';
    'VSS'<979>:
      PIN_NUMBER='(0,0,0,0,0,0,0,0,0,0,0,0,0,0,0,0,0,0,0,0,0,0,0,U80,0,0,0,0,0,0)';
      PINUSE='GROUND';
      NO_LOAD_CHECK='Both';
      NO_IO_CHECK='Both';
      NO_ASSERT_CHECK='TRUE';
      NO_DIR_CHECK='TRUE';
      ALLOW_CONNECT='TRUE';
    'VSS'<978>:
      PIN_NUMBER='(0,0,0,0,0,0,0,0,0,0,0,0,0,0,0,0,0,0,0,0,0,0,0,U86,0,0,0,0,0,0)';
      PINUSE='GROUND';
      NO_LOAD_CHECK='Both';
      NO_IO_CHECK='Both';
      NO_ASSERT_CHECK='TRUE';
      NO_DIR_CHECK='TRUE';
      ALLOW_CONNECT='TRUE';
    'VSS'<977>:
      PIN_NUMBER='(0,0,0,0,0,0,0,0,0,0,0,0,0,0,0,0,0,0,0,0,0,0,0,V1,0,0,0,0,0,0)';
      PINUSE='GROUND';
      NO_LOAD_CHECK='Both';
      NO_IO_CHECK='Both';
      NO_ASSERT_CHECK='TRUE';
      NO_DIR_CHECK='TRUE';
      ALLOW_CONNECT='TRUE';
    'VSS'<976>:
      PIN_NUMBER='(0,0,0,0,0,0,0,0,0,0,0,0,0,0,0,0,0,0,0,0,0,0,0,V5,0,0,0,0,0,0)';
      PINUSE='GROUND';
      NO_LOAD_CHECK='Both';
      NO_IO_CHECK='Both';
      NO_ASSERT_CHECK='TRUE';
      NO_DIR_CHECK='TRUE';
      ALLOW_CONNECT='TRUE';
    'VSS'<975>:
      PIN_NUMBER='(0,0,0,0,0,0,0,0,0,0,0,0,0,0,0,0,0,0,0,0,0,0,0,V9,0,0,0,0,0,0)';
      PINUSE='GROUND';
      NO_LOAD_CHECK='Both';
      NO_IO_CHECK='Both';
      NO_ASSERT_CHECK='TRUE';
      NO_DIR_CHECK='TRUE';
      ALLOW_CONNECT='TRUE';
    'VSS'<974>:
      PIN_NUMBER='(0,0,0,0,0,0,0,0,0,0,0,0,0,0,0,0,0,0,0,0,0,0,0,V13,0,0,0,0,0,0)';
      PINUSE='GROUND';
      NO_LOAD_CHECK='Both';
      NO_IO_CHECK='Both';
      NO_ASSERT_CHECK='TRUE';
      NO_DIR_CHECK='TRUE';
      ALLOW_CONNECT='TRUE';
    'VSS'<973>:
      PIN_NUMBER='(0,0,0,0,0,0,0,0,0,0,0,0,0,0,0,0,0,0,0,0,0,0,0,V15,0,0,0,0,0,0)';
      PINUSE='GROUND';
      NO_LOAD_CHECK='Both';
      NO_IO_CHECK='Both';
      NO_ASSERT_CHECK='TRUE';
      NO_DIR_CHECK='TRUE';
      ALLOW_CONNECT='TRUE';
    'VSS'<972>:
      PIN_NUMBER='(0,0,0,0,0,0,0,0,0,0,0,0,0,0,0,0,0,0,0,0,0,0,0,V21,0,0,0,0,0,0)';
      PINUSE='GROUND';
      NO_LOAD_CHECK='Both';
      NO_IO_CHECK='Both';
      NO_ASSERT_CHECK='TRUE';
      NO_DIR_CHECK='TRUE';
      ALLOW_CONNECT='TRUE';
    'VSS'<971>:
      PIN_NUMBER='(0,0,0,0,0,0,0,0,0,0,0,0,0,0,0,0,0,0,0,0,0,0,0,V23,0,0,0,0,0,0)';
      PINUSE='GROUND';
      NO_LOAD_CHECK='Both';
      NO_IO_CHECK='Both';
      NO_ASSERT_CHECK='TRUE';
      NO_DIR_CHECK='TRUE';
      ALLOW_CONNECT='TRUE';
    'VSS'<970>:
      PIN_NUMBER='(0,0,0,0,0,0,0,0,0,0,0,0,0,0,0,0,0,0,0,0,0,0,0,V43,0,0,0,0,0,0)';
      PINUSE='GROUND';
      NO_LOAD_CHECK='Both';
      NO_IO_CHECK='Both';
      NO_ASSERT_CHECK='TRUE';
      NO_DIR_CHECK='TRUE';
      ALLOW_CONNECT='TRUE';
    'VSS'<969>:
      PIN_NUMBER='(0,0,0,0,0,0,0,0,0,0,0,0,0,0,0,0,0,0,0,0,0,0,0,V73,0,0,0,0,0,0)';
      PINUSE='GROUND';
      NO_LOAD_CHECK='Both';
      NO_IO_CHECK='Both';
      NO_ASSERT_CHECK='TRUE';
      NO_DIR_CHECK='TRUE';
      ALLOW_CONNECT='TRUE';
    'VSS'<968>:
      PIN_NUMBER='(0,0,0,0,0,0,0,0,0,0,0,0,0,0,0,0,0,0,0,0,0,0,0,V75,0,0,0,0,0,0)';
      PINUSE='GROUND';
      NO_LOAD_CHECK='Both';
      NO_IO_CHECK='Both';
      NO_ASSERT_CHECK='TRUE';
      NO_DIR_CHECK='TRUE';
      ALLOW_CONNECT='TRUE';
    'VSS'<967>:
      PIN_NUMBER='(0,0,0,0,0,0,0,0,0,0,0,0,0,0,0,0,0,0,0,0,0,0,0,V77,0,0,0,0,0,0)';
      PINUSE='GROUND';
      NO_LOAD_CHECK='Both';
      NO_IO_CHECK='Both';
      NO_ASSERT_CHECK='TRUE';
      NO_DIR_CHECK='TRUE';
      ALLOW_CONNECT='TRUE';
    'VSS'<966>:
      PIN_NUMBER='(0,0,0,0,0,0,0,0,0,0,0,0,0,0,0,0,0,0,0,0,0,0,0,V83,0,0,0,0,0,0)';
      PINUSE='GROUND';
      NO_LOAD_CHECK='Both';
      NO_IO_CHECK='Both';
      NO_ASSERT_CHECK='TRUE';
      NO_DIR_CHECK='TRUE';
      ALLOW_CONNECT='TRUE';
    'VSS'<965>:
      PIN_NUMBER='(0,0,0,0,0,0,0,0,0,0,0,0,0,0,0,0,0,0,0,0,0,0,0,W8,0,0,0,0,0,0)';
      PINUSE='GROUND';
      NO_LOAD_CHECK='Both';
      NO_IO_CHECK='Both';
      NO_ASSERT_CHECK='TRUE';
      NO_DIR_CHECK='TRUE';
      ALLOW_CONNECT='TRUE';
    'VSS'<964>:
      PIN_NUMBER='(0,0,0,0,0,0,0,0,0,0,0,0,0,0,0,0,0,0,0,0,0,0,0,AC56,0,0,0,0,0,0)';
      PINUSE='GROUND';
      NO_LOAD_CHECK='Both';
      NO_IO_CHECK='Both';
      NO_ASSERT_CHECK='TRUE';
      NO_DIR_CHECK='TRUE';
      ALLOW_CONNECT='TRUE';
    'VSS'<963>:
      PIN_NUMBER='(0,0,0,0,0,0,0,0,0,0,0,0,0,0,0,0,0,0,0,0,0,0,0,W12,0,0,0,0,0,0)';
      PINUSE='GROUND';
      NO_LOAD_CHECK='Both';
      NO_IO_CHECK='Both';
      NO_ASSERT_CHECK='TRUE';
      NO_DIR_CHECK='TRUE';
      ALLOW_CONNECT='TRUE';
    'VSS'<962>:
      PIN_NUMBER='(0,0,0,0,0,0,0,0,0,0,0,0,0,0,0,0,0,0,0,0,0,0,0,W22,0,0,0,0,0,0)';
      PINUSE='GROUND';
      NO_LOAD_CHECK='Both';
      NO_IO_CHECK='Both';
      NO_ASSERT_CHECK='TRUE';
      NO_DIR_CHECK='TRUE';
      ALLOW_CONNECT='TRUE';
    'VSS'<961>:
      PIN_NUMBER='(0,0,0,0,0,0,0,0,0,0,0,0,0,0,0,0,0,0,0,0,0,0,0,W24,0,0,0,0,0,0)';
      PINUSE='GROUND';
      NO_LOAD_CHECK='Both';
      NO_IO_CHECK='Both';
      NO_ASSERT_CHECK='TRUE';
      NO_DIR_CHECK='TRUE';
      ALLOW_CONNECT='TRUE';
    'VSS'<960>:
      PIN_NUMBER='(0,0,0,0,0,0,0,0,0,0,0,0,0,0,0,0,0,0,0,0,0,0,0,W26,0,0,0,0,0,0)';
      PINUSE='GROUND';
      NO_LOAD_CHECK='Both';
      NO_IO_CHECK='Both';
      NO_ASSERT_CHECK='TRUE';
      NO_DIR_CHECK='TRUE';
      ALLOW_CONNECT='TRUE';
    'VSS'<959>:
      PIN_NUMBER='(0,0,0,0,0,0,0,0,0,0,0,0,0,0,0,0,0,0,0,0,0,0,0,W28,0,0,0,0,0,0)';
      PINUSE='GROUND';
      NO_LOAD_CHECK='Both';
      NO_IO_CHECK='Both';
      NO_ASSERT_CHECK='TRUE';
      NO_DIR_CHECK='TRUE';
      ALLOW_CONNECT='TRUE';
    'VSS'<958>:
      PIN_NUMBER='(0,0,0,0,0,0,0,0,0,0,0,0,0,0,0,0,0,0,0,0,0,0,0,W30,0,0,0,0,0,0)';
      PINUSE='GROUND';
      NO_LOAD_CHECK='Both';
      NO_IO_CHECK='Both';
      NO_ASSERT_CHECK='TRUE';
      NO_DIR_CHECK='TRUE';
      ALLOW_CONNECT='TRUE';
    'VSS'<957>:
      PIN_NUMBER='(0,0,0,0,0,0,0,0,0,0,0,0,0,0,0,0,0,0,0,0,0,0,0,W32,0,0,0,0,0,0)';
      PINUSE='GROUND';
      NO_LOAD_CHECK='Both';
      NO_IO_CHECK='Both';
      NO_ASSERT_CHECK='TRUE';
      NO_DIR_CHECK='TRUE';
      ALLOW_CONNECT='TRUE';
    'VSS'<956>:
      PIN_NUMBER='(0,0,0,0,0,0,0,0,0,0,0,0,0,0,0,0,0,0,0,0,0,0,0,W34,0,0,0,0,0,0)';
      PINUSE='GROUND';
      NO_LOAD_CHECK='Both';
      NO_IO_CHECK='Both';
      NO_ASSERT_CHECK='TRUE';
      NO_DIR_CHECK='TRUE';
      ALLOW_CONNECT='TRUE';
    'VSS'<955>:
      PIN_NUMBER='(0,0,0,0,0,0,0,0,0,0,0,0,0,0,0,0,0,0,0,0,0,0,0,W36,0,0,0,0,0,0)';
      PINUSE='GROUND';
      NO_LOAD_CHECK='Both';
      NO_IO_CHECK='Both';
      NO_ASSERT_CHECK='TRUE';
      NO_DIR_CHECK='TRUE';
      ALLOW_CONNECT='TRUE';
    'VSS'<954>:
      PIN_NUMBER='(0,0,0,0,0,0,0,0,0,0,0,0,0,0,0,0,0,0,0,0,0,0,0,W38,0,0,0,0,0,0)';
      PINUSE='GROUND';
      NO_LOAD_CHECK='Both';
      NO_IO_CHECK='Both';
      NO_ASSERT_CHECK='TRUE';
      NO_DIR_CHECK='TRUE';
      ALLOW_CONNECT='TRUE';
    'VSS'<953>:
      PIN_NUMBER='(0,0,0,0,0,0,0,0,0,0,0,0,0,0,0,0,0,0,0,0,0,0,0,W40,0,0,0,0,0,0)';
      PINUSE='GROUND';
      NO_LOAD_CHECK='Both';
      NO_IO_CHECK='Both';
      NO_ASSERT_CHECK='TRUE';
      NO_DIR_CHECK='TRUE';
      ALLOW_CONNECT='TRUE';
    'VSS'<952>:
      PIN_NUMBER='(0,0,0,0,0,0,0,0,0,0,0,0,0,0,0,0,0,0,0,0,0,0,0,W42,0,0,0,0,0,0)';
      PINUSE='GROUND';
      NO_LOAD_CHECK='Both';
      NO_IO_CHECK='Both';
      NO_ASSERT_CHECK='TRUE';
      NO_DIR_CHECK='TRUE';
      ALLOW_CONNECT='TRUE';
    'VSS'<951>:
      PIN_NUMBER='(0,0,0,0,0,0,0,0,0,0,0,0,0,0,0,0,0,0,0,0,0,0,0,W68,0,0,0,0,0,0)';
      PINUSE='GROUND';
      NO_LOAD_CHECK='Both';
      NO_IO_CHECK='Both';
      NO_ASSERT_CHECK='TRUE';
      NO_DIR_CHECK='TRUE';
      ALLOW_CONNECT='TRUE';
    'VSS'<950>:
      PIN_NUMBER='(0,0,0,0,0,0,0,0,0,0,0,0,0,0,0,0,0,0,0,0,0,0,0,W74,0,0,0,0,0,0)';
      PINUSE='GROUND';
      NO_LOAD_CHECK='Both';
      NO_IO_CHECK='Both';
      NO_ASSERT_CHECK='TRUE';
      NO_DIR_CHECK='TRUE';
      ALLOW_CONNECT='TRUE';
    'VSS'<949>:
      PIN_NUMBER='(0,0,0,0,0,0,0,0,0,0,0,0,0,0,0,0,0,0,0,0,0,0,0,W78,0,0,0,0,0,0)';
      PINUSE='GROUND';
      NO_LOAD_CHECK='Both';
      NO_IO_CHECK='Both';
      NO_ASSERT_CHECK='TRUE';
      NO_DIR_CHECK='TRUE';
      ALLOW_CONNECT='TRUE';
    'VSS'<948>:
      PIN_NUMBER='(0,0,0,0,0,0,0,0,0,0,0,0,0,0,0,0,0,0,0,0,0,0,0,W82,0,0,0,0,0,0)';
      PINUSE='GROUND';
      NO_LOAD_CHECK='Both';
      NO_IO_CHECK='Both';
      NO_ASSERT_CHECK='TRUE';
      NO_DIR_CHECK='TRUE';
      ALLOW_CONNECT='TRUE';
    'VSS'<947>:
      PIN_NUMBER='(0,0,0,0,0,0,0,0,0,0,0,0,0,0,0,0,0,0,0,0,0,0,0,Y15,0,0,0,0,0,0)';
      PINUSE='GROUND';
      NO_LOAD_CHECK='Both';
      NO_IO_CHECK='Both';
      NO_ASSERT_CHECK='TRUE';
      NO_DIR_CHECK='TRUE';
      ALLOW_CONNECT='TRUE';
    'VSS'<946>:
      PIN_NUMBER='(0,0,0,0,0,0,0,0,0,0,0,0,0,0,0,0,0,0,0,0,0,0,0,Y17,0,0,0,0,0,0)';
      PINUSE='GROUND';
      NO_LOAD_CHECK='Both';
      NO_IO_CHECK='Both';
      NO_ASSERT_CHECK='TRUE';
      NO_DIR_CHECK='TRUE';
      ALLOW_CONNECT='TRUE';
    'VSS'<945>:
      PIN_NUMBER='(0,0,0,0,0,0,0,0,0,0,0,0,0,0,0,0,0,0,0,0,0,0,0,Y5,0,0,0,0,0,0)';
      PINUSE='GROUND';
      NO_LOAD_CHECK='Both';
      NO_IO_CHECK='Both';
      NO_ASSERT_CHECK='TRUE';
      NO_DIR_CHECK='TRUE';
      ALLOW_CONNECT='TRUE';
    'VSS'<944>:
      PIN_NUMBER='(0,0,0,0,0,0,0,0,0,0,0,0,0,0,0,0,0,0,0,0,0,0,0,Y67,0,0,0,0,0,0)';
      PINUSE='GROUND';
      NO_LOAD_CHECK='Both';
      NO_IO_CHECK='Both';
      NO_ASSERT_CHECK='TRUE';
      NO_DIR_CHECK='TRUE';
      ALLOW_CONNECT='TRUE';
    'VSS'<943>:
      PIN_NUMBER='(0,0,0,0,0,0,0,0,0,0,0,0,0,0,0,0,0,0,0,0,0,0,0,Y7,0,0,0,0,0,0)';
      PINUSE='GROUND';
      NO_LOAD_CHECK='Both';
      NO_IO_CHECK='Both';
      NO_ASSERT_CHECK='TRUE';
      NO_DIR_CHECK='TRUE';
      ALLOW_CONNECT='TRUE';
    'VSS'<942>:
      PIN_NUMBER='(0,0,0,0,0,0,0,0,0,0,0,0,0,0,0,0,0,0,0,0,0,0,0,Y9,0,0,0,0,0,0)';
      PINUSE='GROUND';
      NO_LOAD_CHECK='Both';
      NO_IO_CHECK='Both';
      NO_ASSERT_CHECK='TRUE';
      NO_DIR_CHECK='TRUE';
      ALLOW_CONNECT='TRUE';
    'VSS'<941>:
      PIN_NUMBER='(0,0,0,0,0,0,0,0,0,0,0,0,0,0,0,0,0,0,0,0,0,0,0,Y71,0,0,0,0,0,0)';
      PINUSE='GROUND';
      NO_LOAD_CHECK='Both';
      NO_IO_CHECK='Both';
      NO_ASSERT_CHECK='TRUE';
      NO_DIR_CHECK='TRUE';
      ALLOW_CONNECT='TRUE';
    'VSS'<940>:
      PIN_NUMBER='(0,0,0,0,0,0,0,0,0,0,0,0,0,0,0,0,0,0,0,0,0,0,0,Y73,0,0,0,0,0,0)';
      PINUSE='GROUND';
      NO_LOAD_CHECK='Both';
      NO_IO_CHECK='Both';
      NO_ASSERT_CHECK='TRUE';
      NO_DIR_CHECK='TRUE';
      ALLOW_CONNECT='TRUE';
    'VSS'<939>:
      PIN_NUMBER='(0,0,0,0,0,0,0,0,0,0,0,0,0,0,0,0,0,0,0,0,0,0,0,Y79,0,0,0,0,0,0)';
      PINUSE='GROUND';
      NO_LOAD_CHECK='Both';
      NO_IO_CHECK='Both';
      NO_ASSERT_CHECK='TRUE';
      NO_DIR_CHECK='TRUE';
      ALLOW_CONNECT='TRUE';
    'VSS'<938>:
      PIN_NUMBER='(0,0,0,0,0,0,0,0,0,0,0,0,0,0,0,0,0,0,0,0,0,0,0,Y81,0,0,0,0,0,0)';
      PINUSE='GROUND';
      NO_LOAD_CHECK='Both';
      NO_IO_CHECK='Both';
      NO_ASSERT_CHECK='TRUE';
      NO_DIR_CHECK='TRUE';
      ALLOW_CONNECT='TRUE';
    'VSS'<937>:
      PIN_NUMBER='(0,0,0,0,0,0,0,0,0,0,0,0,0,0,0,0,0,0,0,0,0,0,0,Y83,0,0,0,0,0,0)';
      PINUSE='GROUND';
      NO_LOAD_CHECK='Both';
      NO_IO_CHECK='Both';
      NO_ASSERT_CHECK='TRUE';
      NO_DIR_CHECK='TRUE';
      ALLOW_CONNECT='TRUE';
    'VSS'<936>:
      PIN_NUMBER='(0,0,0,0,0,0,0,0,0,0,0,0,0,0,0,0,0,0,0,0,0,0,0,Y85,0,0,0,0,0,0)';
      PINUSE='GROUND';
      NO_LOAD_CHECK='Both';
      NO_IO_CHECK='Both';
      NO_ASSERT_CHECK='TRUE';
      NO_DIR_CHECK='TRUE';
      ALLOW_CONNECT='TRUE';
    'VSS'<935>:
      PIN_NUMBER='(0,0,0,0,0,0,0,0,0,0,0,0,0,0,0,0,0,0,0,0,0,0,0,AA4,0,0,0,0,0,0)';
      PINUSE='GROUND';
      NO_LOAD_CHECK='Both';
      NO_IO_CHECK='Both';
      NO_ASSERT_CHECK='TRUE';
      NO_DIR_CHECK='TRUE';
      ALLOW_CONNECT='TRUE';
    'VSS'<934>:
      PIN_NUMBER='(0,0,0,0,0,0,0,0,0,0,0,0,0,0,0,0,0,0,0,0,0,0,0,AA16,0,0,0,0,0,0)';
      PINUSE='GROUND';
      NO_LOAD_CHECK='Both';
      NO_IO_CHECK='Both';
      NO_ASSERT_CHECK='TRUE';
      NO_DIR_CHECK='TRUE';
      ALLOW_CONNECT='TRUE';
    'VSS'<933>:
      PIN_NUMBER='(0,0,0,0,0,0,0,0,0,0,0,0,0,0,0,0,0,0,0,0,0,0,0,0,AA18,0,0,0,0,0)';
      PINUSE='GROUND';
      NO_LOAD_CHECK='Both';
      NO_IO_CHECK='Both';
      NO_ASSERT_CHECK='TRUE';
      NO_DIR_CHECK='TRUE';
      ALLOW_CONNECT='TRUE';
    'VSS'<932>:
      PIN_NUMBER='(0,0,0,0,0,0,0,0,0,0,0,0,0,0,0,0,0,0,0,0,0,0,0,0,AA22,0,0,0,0,0)';
      PINUSE='GROUND';
      NO_LOAD_CHECK='Both';
      NO_IO_CHECK='Both';
      NO_ASSERT_CHECK='TRUE';
      NO_DIR_CHECK='TRUE';
      ALLOW_CONNECT='TRUE';
    'VSS'<931>:
      PIN_NUMBER='(0,0,0,0,0,0,0,0,0,0,0,0,0,0,0,0,0,0,0,0,0,0,0,0,AA24,0,0,0,0,0)';
      PINUSE='GROUND';
      NO_LOAD_CHECK='Both';
      NO_IO_CHECK='Both';
      NO_ASSERT_CHECK='TRUE';
      NO_DIR_CHECK='TRUE';
      ALLOW_CONNECT='TRUE';
    'VSS'<930>:
      PIN_NUMBER='(0,0,0,0,0,0,0,0,0,0,0,0,0,0,0,0,0,0,0,0,0,0,0,0,AA30,0,0,0,0,0)';
      PINUSE='GROUND';
      NO_LOAD_CHECK='Both';
      NO_IO_CHECK='Both';
      NO_ASSERT_CHECK='TRUE';
      NO_DIR_CHECK='TRUE';
      ALLOW_CONNECT='TRUE';
    'VSS'<929>:
      PIN_NUMBER='(0,0,0,0,0,0,0,0,0,0,0,0,0,0,0,0,0,0,0,0,0,0,0,0,AA36,0,0,0,0,0)';
      PINUSE='GROUND';
      NO_LOAD_CHECK='Both';
      NO_IO_CHECK='Both';
      NO_ASSERT_CHECK='TRUE';
      NO_DIR_CHECK='TRUE';
      ALLOW_CONNECT='TRUE';
    'VSS'<928>:
      PIN_NUMBER='(0,0,0,0,0,0,0,0,0,0,0,0,0,0,0,0,0,0,0,0,0,0,0,0,AA42,0,0,0,0,0)';
      PINUSE='GROUND';
      NO_LOAD_CHECK='Both';
      NO_IO_CHECK='Both';
      NO_ASSERT_CHECK='TRUE';
      NO_DIR_CHECK='TRUE';
      ALLOW_CONNECT='TRUE';
    'VSS'<927>:
      PIN_NUMBER='(0,0,0,0,0,0,0,0,0,0,0,0,0,0,0,0,0,0,0,0,0,0,0,0,AA64,0,0,0,0,0)';
      PINUSE='GROUND';
      NO_LOAD_CHECK='Both';
      NO_IO_CHECK='Both';
      NO_ASSERT_CHECK='TRUE';
      NO_DIR_CHECK='TRUE';
      ALLOW_CONNECT='TRUE';
    'VSS'<926>:
      PIN_NUMBER='(0,0,0,0,0,0,0,0,0,0,0,0,0,0,0,0,0,0,0,0,0,0,0,0,AA66,0,0,0,0,0)';
      PINUSE='GROUND';
      NO_LOAD_CHECK='Both';
      NO_IO_CHECK='Both';
      NO_ASSERT_CHECK='TRUE';
      NO_DIR_CHECK='TRUE';
      ALLOW_CONNECT='TRUE';
    'VSS'<925>:
      PIN_NUMBER='(0,0,0,0,0,0,0,0,0,0,0,0,0,0,0,0,0,0,0,0,0,0,0,0,AA68,0,0,0,0,0)';
      PINUSE='GROUND';
      NO_LOAD_CHECK='Both';
      NO_IO_CHECK='Both';
      NO_ASSERT_CHECK='TRUE';
      NO_DIR_CHECK='TRUE';
      ALLOW_CONNECT='TRUE';
    'VSS'<924>:
      PIN_NUMBER='(0,0,0,0,0,0,0,0,0,0,0,0,0,0,0,0,0,0,0,0,0,0,0,0,AA76,0,0,0,0,0)';
      PINUSE='GROUND';
      NO_LOAD_CHECK='Both';
      NO_IO_CHECK='Both';
      NO_ASSERT_CHECK='TRUE';
      NO_DIR_CHECK='TRUE';
      ALLOW_CONNECT='TRUE';
    'VSS'<923>:
      PIN_NUMBER='(0,0,0,0,0,0,0,0,0,0,0,0,0,0,0,0,0,0,0,0,0,0,0,0,AA78,0,0,0,0,0)';
      PINUSE='GROUND';
      NO_LOAD_CHECK='Both';
      NO_IO_CHECK='Both';
      NO_ASSERT_CHECK='TRUE';
      NO_DIR_CHECK='TRUE';
      ALLOW_CONNECT='TRUE';
    'VSS'<922>:
      PIN_NUMBER='(0,0,0,0,0,0,0,0,0,0,0,0,0,0,0,0,0,0,0,0,0,0,0,0,AA80,0,0,0,0,0)';
      PINUSE='GROUND';
      NO_LOAD_CHECK='Both';
      NO_IO_CHECK='Both';
      NO_ASSERT_CHECK='TRUE';
      NO_DIR_CHECK='TRUE';
      ALLOW_CONNECT='TRUE';
    'VSS'<921>:
      PIN_NUMBER='(0,0,0,0,0,0,0,0,0,0,0,0,0,0,0,0,0,0,0,0,0,0,0,0,AA82,0,0,0,0,0)';
      PINUSE='GROUND';
      NO_LOAD_CHECK='Both';
      NO_IO_CHECK='Both';
      NO_ASSERT_CHECK='TRUE';
      NO_DIR_CHECK='TRUE';
      ALLOW_CONNECT='TRUE';
    'VSS'<920>:
      PIN_NUMBER='(0,0,0,0,0,0,0,0,0,0,0,0,0,0,0,0,0,0,0,0,0,0,0,0,AB1,0,0,0,0,0)';
      PINUSE='GROUND';
      NO_LOAD_CHECK='Both';
      NO_IO_CHECK='Both';
      NO_ASSERT_CHECK='TRUE';
      NO_DIR_CHECK='TRUE';
      ALLOW_CONNECT='TRUE';
    'VSS'<919>:
      PIN_NUMBER='(0,0,0,0,0,0,0,0,0,0,0,0,0,0,0,0,0,0,0,0,0,0,0,0,AB5,0,0,0,0,0)';
      PINUSE='GROUND';
      NO_LOAD_CHECK='Both';
      NO_IO_CHECK='Both';
      NO_ASSERT_CHECK='TRUE';
      NO_DIR_CHECK='TRUE';
      ALLOW_CONNECT='TRUE';
    'VSS'<918>:
      PIN_NUMBER='(0,0,0,0,0,0,0,0,0,0,0,0,0,0,0,0,0,0,0,0,0,0,0,0,AB11,0,0,0,0,0)';
      PINUSE='GROUND';
      NO_LOAD_CHECK='Both';
      NO_IO_CHECK='Both';
      NO_ASSERT_CHECK='TRUE';
      NO_DIR_CHECK='TRUE';
      ALLOW_CONNECT='TRUE';
    'VSS'<917>:
      PIN_NUMBER='(0,0,0,0,0,0,0,0,0,0,0,0,0,0,0,0,0,0,0,0,0,0,0,0,AB21,0,0,0,0,0)';
      PINUSE='GROUND';
      NO_LOAD_CHECK='Both';
      NO_IO_CHECK='Both';
      NO_ASSERT_CHECK='TRUE';
      NO_DIR_CHECK='TRUE';
      ALLOW_CONNECT='TRUE';
    'VSS'<916>:
      PIN_NUMBER='(0,0,0,0,0,0,0,0,0,0,0,0,0,0,0,0,0,0,0,0,0,0,0,0,AB23,0,0,0,0,0)';
      PINUSE='GROUND';
      NO_LOAD_CHECK='Both';
      NO_IO_CHECK='Both';
      NO_ASSERT_CHECK='TRUE';
      NO_DIR_CHECK='TRUE';
      ALLOW_CONNECT='TRUE';
    'VSS'<915>:
      PIN_NUMBER='(0,0,0,0,0,0,0,0,0,0,0,0,0,0,0,0,0,0,0,0,0,0,0,0,AB25,0,0,0,0,0)';
      PINUSE='GROUND';
      NO_LOAD_CHECK='Both';
      NO_IO_CHECK='Both';
      NO_ASSERT_CHECK='TRUE';
      NO_DIR_CHECK='TRUE';
      ALLOW_CONNECT='TRUE';
    'VSS'<914>:
      PIN_NUMBER='(0,0,0,0,0,0,0,0,0,0,0,0,0,0,0,0,0,0,0,0,0,0,0,0,AB29,0,0,0,0,0)';
      PINUSE='GROUND';
      NO_LOAD_CHECK='Both';
      NO_IO_CHECK='Both';
      NO_ASSERT_CHECK='TRUE';
      NO_DIR_CHECK='TRUE';
      ALLOW_CONNECT='TRUE';
    'VSS'<913>:
      PIN_NUMBER='(0,0,0,0,0,0,0,0,0,0,0,0,0,0,0,0,0,0,0,0,0,0,0,0,AB31,0,0,0,0,0)';
      PINUSE='GROUND';
      NO_LOAD_CHECK='Both';
      NO_IO_CHECK='Both';
      NO_ASSERT_CHECK='TRUE';
      NO_DIR_CHECK='TRUE';
      ALLOW_CONNECT='TRUE';
    'VSS'<912>:
      PIN_NUMBER='(0,0,0,0,0,0,0,0,0,0,0,0,0,0,0,0,0,0,0,0,0,0,0,0,AB35,0,0,0,0,0)';
      PINUSE='GROUND';
      NO_LOAD_CHECK='Both';
      NO_IO_CHECK='Both';
      NO_ASSERT_CHECK='TRUE';
      NO_DIR_CHECK='TRUE';
      ALLOW_CONNECT='TRUE';
    'VSS'<911>:
      PIN_NUMBER='(0,0,0,0,0,0,0,0,0,0,0,0,0,0,0,0,0,0,0,0,0,0,0,0,AB37,0,0,0,0,0)';
      PINUSE='GROUND';
      NO_LOAD_CHECK='Both';
      NO_IO_CHECK='Both';
      NO_ASSERT_CHECK='TRUE';
      NO_DIR_CHECK='TRUE';
      ALLOW_CONNECT='TRUE';
    'VSS'<910>:
      PIN_NUMBER='(0,0,0,0,0,0,0,0,0,0,0,0,0,0,0,0,0,0,0,0,0,0,0,0,AB41,0,0,0,0,0)';
      PINUSE='GROUND';
      NO_LOAD_CHECK='Both';
      NO_IO_CHECK='Both';
      NO_ASSERT_CHECK='TRUE';
      NO_DIR_CHECK='TRUE';
      ALLOW_CONNECT='TRUE';
    'VSS'<909>:
      PIN_NUMBER='(0,0,0,0,0,0,0,0,0,0,0,0,0,0,0,0,0,0,0,0,0,0,0,0,AB65,0,0,0,0,0)';
      PINUSE='GROUND';
      NO_LOAD_CHECK='Both';
      NO_IO_CHECK='Both';
      NO_ASSERT_CHECK='TRUE';
      NO_DIR_CHECK='TRUE';
      ALLOW_CONNECT='TRUE';
    'VSS'<908>:
      PIN_NUMBER='(0,0,0,0,0,0,0,0,0,0,0,0,0,0,0,0,0,0,0,0,0,0,0,0,AB69,0,0,0,0,0)';
      PINUSE='GROUND';
      NO_LOAD_CHECK='Both';
      NO_IO_CHECK='Both';
      NO_ASSERT_CHECK='TRUE';
      NO_DIR_CHECK='TRUE';
      ALLOW_CONNECT='TRUE';
    'VSS'<907>:
      PIN_NUMBER='(0,0,0,0,0,0,0,0,0,0,0,0,0,0,0,0,0,0,0,0,0,0,0,0,AB73,0,0,0,0,0)';
      PINUSE='GROUND';
      NO_LOAD_CHECK='Both';
      NO_IO_CHECK='Both';
      NO_ASSERT_CHECK='TRUE';
      NO_DIR_CHECK='TRUE';
      ALLOW_CONNECT='TRUE';
    'VSS'<906>:
      PIN_NUMBER='(0,0,0,0,0,0,0,0,0,0,0,0,0,0,0,0,0,0,0,0,0,0,0,0,AB79,0,0,0,0,0)';
      PINUSE='GROUND';
      NO_LOAD_CHECK='Both';
      NO_IO_CHECK='Both';
      NO_ASSERT_CHECK='TRUE';
      NO_DIR_CHECK='TRUE';
      ALLOW_CONNECT='TRUE';
    'VSS'<905>:
      PIN_NUMBER='(0,0,0,0,0,0,0,0,0,0,0,0,0,0,0,0,0,0,0,0,0,0,0,0,AB83,0,0,0,0,0)';
      PINUSE='GROUND';
      NO_LOAD_CHECK='Both';
      NO_IO_CHECK='Both';
      NO_ASSERT_CHECK='TRUE';
      NO_DIR_CHECK='TRUE';
      ALLOW_CONNECT='TRUE';
    'VSS'<904>:
      PIN_NUMBER='(0,0,0,0,0,0,0,0,0,0,0,0,0,0,0,0,0,0,0,0,0,0,0,0,AB85,0,0,0,0,0)';
      PINUSE='GROUND';
      NO_LOAD_CHECK='Both';
      NO_IO_CHECK='Both';
      NO_ASSERT_CHECK='TRUE';
      NO_DIR_CHECK='TRUE';
      ALLOW_CONNECT='TRUE';
    'VSS'<903>:
      PIN_NUMBER='(0,0,0,0,0,0,0,0,0,0,0,0,0,0,0,0,0,0,0,0,0,0,0,0,AC18,0,0,0,0,0)';
      PINUSE='GROUND';
      NO_LOAD_CHECK='Both';
      NO_IO_CHECK='Both';
      NO_ASSERT_CHECK='TRUE';
      NO_DIR_CHECK='TRUE';
      ALLOW_CONNECT='TRUE';
    'VSS'<902>:
      PIN_NUMBER='(0,0,0,0,0,0,0,0,0,0,0,0,0,0,0,0,0,0,0,0,0,0,0,0,AC22,0,0,0,0,0)';
      PINUSE='GROUND';
      NO_LOAD_CHECK='Both';
      NO_IO_CHECK='Both';
      NO_ASSERT_CHECK='TRUE';
      NO_DIR_CHECK='TRUE';
      ALLOW_CONNECT='TRUE';
    'VSS'<901>:
      PIN_NUMBER='(0,0,0,0,0,0,0,0,0,0,0,0,0,0,0,0,0,0,0,0,0,0,0,0,AC26,0,0,0,0,0)';
      PINUSE='GROUND';
      NO_LOAD_CHECK='Both';
      NO_IO_CHECK='Both';
      NO_ASSERT_CHECK='TRUE';
      NO_DIR_CHECK='TRUE';
      ALLOW_CONNECT='TRUE';
    'VSS'<900>:
      PIN_NUMBER='(0,0,0,0,0,0,0,0,0,0,0,0,0,0,0,0,0,0,0,0,0,0,0,0,AC28,0,0,0,0,0)';
      PINUSE='GROUND';
      NO_LOAD_CHECK='Both';
      NO_IO_CHECK='Both';
      NO_ASSERT_CHECK='TRUE';
      NO_DIR_CHECK='TRUE';
      ALLOW_CONNECT='TRUE';
    'VSS'<899>:
      PIN_NUMBER='(0,0,0,0,0,0,0,0,0,0,0,0,0,0,0,0,0,0,0,0,0,0,0,0,AC32,0,0,0,0,0)';
      PINUSE='GROUND';
      NO_LOAD_CHECK='Both';
      NO_IO_CHECK='Both';
      NO_ASSERT_CHECK='TRUE';
      NO_DIR_CHECK='TRUE';
      ALLOW_CONNECT='TRUE';
    'VSS'<898>:
      PIN_NUMBER='(0,0,0,0,0,0,0,0,0,0,0,0,0,0,0,0,0,0,0,0,0,0,0,0,AC34,0,0,0,0,0)';
      PINUSE='GROUND';
      NO_LOAD_CHECK='Both';
      NO_IO_CHECK='Both';
      NO_ASSERT_CHECK='TRUE';
      NO_DIR_CHECK='TRUE';
      ALLOW_CONNECT='TRUE';
    'VSS'<897>:
      PIN_NUMBER='(0,0,0,0,0,0,0,0,0,0,0,0,0,0,0,0,0,0,0,0,0,0,0,0,AC38,0,0,0,0,0)';
      PINUSE='GROUND';
      NO_LOAD_CHECK='Both';
      NO_IO_CHECK='Both';
      NO_ASSERT_CHECK='TRUE';
      NO_DIR_CHECK='TRUE';
      ALLOW_CONNECT='TRUE';
    'VSS'<896>:
      PIN_NUMBER='(0,0,0,0,0,0,0,0,0,0,0,0,0,0,0,0,0,0,0,0,0,0,0,0,AC40,0,0,0,0,0)';
      PINUSE='GROUND';
      NO_LOAD_CHECK='Both';
      NO_IO_CHECK='Both';
      NO_ASSERT_CHECK='TRUE';
      NO_DIR_CHECK='TRUE';
      ALLOW_CONNECT='TRUE';
    'VSS'<895>:
      PIN_NUMBER='(0,0,0,0,0,0,0,0,0,0,0,0,0,0,0,0,0,0,0,0,0,0,0,0,AC64,0,0,0,0,0)';
      PINUSE='GROUND';
      NO_LOAD_CHECK='Both';
      NO_IO_CHECK='Both';
      NO_ASSERT_CHECK='TRUE';
      NO_DIR_CHECK='TRUE';
      ALLOW_CONNECT='TRUE';
    'VSS'<894>:
      PIN_NUMBER='(0,0,0,0,0,0,0,0,0,0,0,0,0,0,0,0,0,0,0,0,0,0,0,0,AC70,0,0,0,0,0)';
      PINUSE='GROUND';
      NO_LOAD_CHECK='Both';
      NO_IO_CHECK='Both';
      NO_ASSERT_CHECK='TRUE';
      NO_DIR_CHECK='TRUE';
      ALLOW_CONNECT='TRUE';
    'VSS'<893>:
      PIN_NUMBER='(0,0,0,0,0,0,0,0,0,0,0,0,0,0,0,0,0,0,0,0,0,0,0,0,AC72,0,0,0,0,0)';
      PINUSE='GROUND';
      NO_LOAD_CHECK='Both';
      NO_IO_CHECK='Both';
      NO_ASSERT_CHECK='TRUE';
      NO_DIR_CHECK='TRUE';
      ALLOW_CONNECT='TRUE';
    'VSS'<892>:
      PIN_NUMBER='(0,0,0,0,0,0,0,0,0,0,0,0,0,0,0,0,0,0,0,0,0,0,0,0,AC78,0,0,0,0,0)';
      PINUSE='GROUND';
      NO_LOAD_CHECK='Both';
      NO_IO_CHECK='Both';
      NO_ASSERT_CHECK='TRUE';
      NO_DIR_CHECK='TRUE';
      ALLOW_CONNECT='TRUE';
    'VSS'<891>:
      PIN_NUMBER='(0,0,0,0,0,0,0,0,0,0,0,0,0,0,0,0,0,0,0,0,0,0,0,0,AC84,0,0,0,0,0)';
      PINUSE='GROUND';
      NO_LOAD_CHECK='Both';
      NO_IO_CHECK='Both';
      NO_ASSERT_CHECK='TRUE';
      NO_DIR_CHECK='TRUE';
      ALLOW_CONNECT='TRUE';
    'VSS'<890>:
      PIN_NUMBER='(0,0,0,0,0,0,0,0,0,0,0,0,0,0,0,0,0,0,0,0,0,0,0,0,AC86,0,0,0,0,0)';
      PINUSE='GROUND';
      NO_LOAD_CHECK='Both';
      NO_IO_CHECK='Both';
      NO_ASSERT_CHECK='TRUE';
      NO_DIR_CHECK='TRUE';
      ALLOW_CONNECT='TRUE';
    'VSS'<889>:
      PIN_NUMBER='(0,0,0,0,0,0,0,0,0,0,0,0,0,0,0,0,0,0,0,0,0,0,0,0,AD3,0,0,0,0,0)';
      PINUSE='GROUND';
      NO_LOAD_CHECK='Both';
      NO_IO_CHECK='Both';
      NO_ASSERT_CHECK='TRUE';
      NO_DIR_CHECK='TRUE';
      ALLOW_CONNECT='TRUE';
    'VSS'<888>:
      PIN_NUMBER='(0,0,0,0,0,0,0,0,0,0,0,0,0,0,0,0,0,0,0,0,0,0,0,0,AD7,0,0,0,0,0)';
      PINUSE='GROUND';
      NO_LOAD_CHECK='Both';
      NO_IO_CHECK='Both';
      NO_ASSERT_CHECK='TRUE';
      NO_DIR_CHECK='TRUE';
      ALLOW_CONNECT='TRUE';
    'VSS'<887>:
      PIN_NUMBER='(0,0,0,0,0,0,0,0,0,0,0,0,0,0,0,0,0,0,0,0,0,0,0,0,AD9,0,0,0,0,0)';
      PINUSE='GROUND';
      NO_LOAD_CHECK='Both';
      NO_IO_CHECK='Both';
      NO_ASSERT_CHECK='TRUE';
      NO_DIR_CHECK='TRUE';
      ALLOW_CONNECT='TRUE';
    'VSS'<886>:
      PIN_NUMBER='(0,0,0,0,0,0,0,0,0,0,0,0,0,0,0,0,0,0,0,0,0,0,0,0,AD11,0,0,0,0,0)';
      PINUSE='GROUND';
      NO_LOAD_CHECK='Both';
      NO_IO_CHECK='Both';
      NO_ASSERT_CHECK='TRUE';
      NO_DIR_CHECK='TRUE';
      ALLOW_CONNECT='TRUE';
    'VSS'<885>:
      PIN_NUMBER='(0,0,0,0,0,0,0,0,0,0,0,0,0,0,0,0,0,0,0,0,0,0,0,0,AD13,0,0,0,0,0)';
      PINUSE='GROUND';
      NO_LOAD_CHECK='Both';
      NO_IO_CHECK='Both';
      NO_ASSERT_CHECK='TRUE';
      NO_DIR_CHECK='TRUE';
      ALLOW_CONNECT='TRUE';
    'VSS'<884>:
      PIN_NUMBER='(0,0,0,0,0,0,0,0,0,0,0,0,0,0,0,0,0,0,0,0,0,0,0,0,AD15,0,0,0,0,0)';
      PINUSE='GROUND';
      NO_LOAD_CHECK='Both';
      NO_IO_CHECK='Both';
      NO_ASSERT_CHECK='TRUE';
      NO_DIR_CHECK='TRUE';
      ALLOW_CONNECT='TRUE';
    'VSS'<883>:
      PIN_NUMBER='(0,0,0,0,0,0,0,0,0,0,0,0,0,0,0,0,0,0,0,0,0,0,0,0,AD19,0,0,0,0,0)';
      PINUSE='GROUND';
      NO_LOAD_CHECK='Both';
      NO_IO_CHECK='Both';
      NO_ASSERT_CHECK='TRUE';
      NO_DIR_CHECK='TRUE';
      ALLOW_CONNECT='TRUE';
    'VSS'<882>:
      PIN_NUMBER='(0,0,0,0,0,0,0,0,0,0,0,0,0,0,0,0,0,0,0,0,0,0,0,0,AD21,0,0,0,0,0)';
      PINUSE='GROUND';
      NO_LOAD_CHECK='Both';
      NO_IO_CHECK='Both';
      NO_ASSERT_CHECK='TRUE';
      NO_DIR_CHECK='TRUE';
      ALLOW_CONNECT='TRUE';
    'VSS'<881>:
      PIN_NUMBER='(0,0,0,0,0,0,0,0,0,0,0,0,0,0,0,0,0,0,0,0,0,0,0,0,AD27,0,0,0,0,0)';
      PINUSE='GROUND';
      NO_LOAD_CHECK='Both';
      NO_IO_CHECK='Both';
      NO_ASSERT_CHECK='TRUE';
      NO_DIR_CHECK='TRUE';
      ALLOW_CONNECT='TRUE';
    'VSS'<880>:
      PIN_NUMBER='(0,0,0,0,0,0,0,0,0,0,0,0,0,0,0,0,0,0,0,0,0,0,0,0,AD33,0,0,0,0,0)';
      PINUSE='GROUND';
      NO_LOAD_CHECK='Both';
      NO_IO_CHECK='Both';
      NO_ASSERT_CHECK='TRUE';
      NO_DIR_CHECK='TRUE';
      ALLOW_CONNECT='TRUE';
    'VSS'<879>:
      PIN_NUMBER='(0,0,0,0,0,0,0,0,0,0,0,0,0,0,0,0,0,0,0,0,0,0,0,0,AD39,0,0,0,0,0)';
      PINUSE='GROUND';
      NO_LOAD_CHECK='Both';
      NO_IO_CHECK='Both';
      NO_ASSERT_CHECK='TRUE';
      NO_DIR_CHECK='TRUE';
      ALLOW_CONNECT='TRUE';
    'VSS'<878>:
      PIN_NUMBER='(0,0,0,0,0,0,0,0,0,0,0,0,0,0,0,0,0,0,0,0,0,0,0,0,AD43,0,0,0,0,0)';
      PINUSE='GROUND';
      NO_LOAD_CHECK='Both';
      NO_IO_CHECK='Both';
      NO_ASSERT_CHECK='TRUE';
      NO_DIR_CHECK='TRUE';
      ALLOW_CONNECT='TRUE';
    'VSS'<877>:
      PIN_NUMBER='(0,0,0,0,0,0,0,0,0,0,0,0,0,0,0,0,0,0,0,0,0,0,0,0,AD71,0,0,0,0,0)';
      PINUSE='GROUND';
      NO_LOAD_CHECK='Both';
      NO_IO_CHECK='Both';
      NO_ASSERT_CHECK='TRUE';
      NO_DIR_CHECK='TRUE';
      ALLOW_CONNECT='TRUE';
    'VSS'<876>:
      PIN_NUMBER='(0,0,0,0,0,0,0,0,0,0,0,0,0,0,0,0,0,0,0,0,0,0,0,0,AD73,0,0,0,0,0)';
      PINUSE='GROUND';
      NO_LOAD_CHECK='Both';
      NO_IO_CHECK='Both';
      NO_ASSERT_CHECK='TRUE';
      NO_DIR_CHECK='TRUE';
      ALLOW_CONNECT='TRUE';
    'VSS'<875>:
      PIN_NUMBER='(0,0,0,0,0,0,0,0,0,0,0,0,0,0,0,0,0,0,0,0,0,0,0,0,AD75,0,0,0,0,0)';
      PINUSE='GROUND';
      NO_LOAD_CHECK='Both';
      NO_IO_CHECK='Both';
      NO_ASSERT_CHECK='TRUE';
      NO_DIR_CHECK='TRUE';
      ALLOW_CONNECT='TRUE';
    'VSS'<874>:
      PIN_NUMBER='(0,0,0,0,0,0,0,0,0,0,0,0,0,0,0,0,0,0,0,0,0,0,0,0,AD81,0,0,0,0,0)';
      PINUSE='GROUND';
      NO_LOAD_CHECK='Both';
      NO_IO_CHECK='Both';
      NO_ASSERT_CHECK='TRUE';
      NO_DIR_CHECK='TRUE';
      ALLOW_CONNECT='TRUE';
    'VSS'<873>:
      PIN_NUMBER='(0,0,0,0,0,0,0,0,0,0,0,0,0,0,0,0,0,0,0,0,0,0,0,0,AD83,0,0,0,0,0)';
      PINUSE='GROUND';
      NO_LOAD_CHECK='Both';
      NO_IO_CHECK='Both';
      NO_ASSERT_CHECK='TRUE';
      NO_DIR_CHECK='TRUE';
      ALLOW_CONNECT='TRUE';
    'VSS'<872>:
      PIN_NUMBER='(0,0,0,0,0,0,0,0,0,0,0,0,0,0,0,0,0,0,0,0,0,0,0,0,AD85,0,0,0,0,0)';
      PINUSE='GROUND';
      NO_LOAD_CHECK='Both';
      NO_IO_CHECK='Both';
      NO_ASSERT_CHECK='TRUE';
      NO_DIR_CHECK='TRUE';
      ALLOW_CONNECT='TRUE';
    'VSS'<871>:
      PIN_NUMBER='(0,0,0,0,0,0,0,0,0,0,0,0,0,0,0,0,0,0,0,0,0,0,0,0,AE4,0,0,0,0,0)';
      PINUSE='GROUND';
      NO_LOAD_CHECK='Both';
      NO_IO_CHECK='Both';
      NO_ASSERT_CHECK='TRUE';
      NO_DIR_CHECK='TRUE';
      ALLOW_CONNECT='TRUE';
    'VSS'<870>:
      PIN_NUMBER='(0,0,0,0,0,0,0,0,0,0,0,0,0,0,0,0,0,0,0,0,0,0,0,0,AE8,0,0,0,0,0)';
      PINUSE='GROUND';
      NO_LOAD_CHECK='Both';
      NO_IO_CHECK='Both';
      NO_ASSERT_CHECK='TRUE';
      NO_DIR_CHECK='TRUE';
      ALLOW_CONNECT='TRUE';
    'VSS'<869>:
      PIN_NUMBER='(0,0,0,0,0,0,0,0,0,0,0,0,0,0,0,0,0,0,0,0,0,0,0,0,AC54,0,0,0,0,0)';
      PINUSE='GROUND';
      NO_LOAD_CHECK='Both';
      NO_IO_CHECK='Both';
      NO_ASSERT_CHECK='TRUE';
      NO_DIR_CHECK='TRUE';
      ALLOW_CONNECT='TRUE';
    'VSS'<868>:
      PIN_NUMBER='(0,0,0,0,0,0,0,0,0,0,0,0,0,0,0,0,0,0,0,0,0,0,0,0,AE16,0,0,0,0,0)';
      PINUSE='GROUND';
      NO_LOAD_CHECK='Both';
      NO_IO_CHECK='Both';
      NO_ASSERT_CHECK='TRUE';
      NO_DIR_CHECK='TRUE';
      ALLOW_CONNECT='TRUE';
    'VSS'<867>:
      PIN_NUMBER='(0,0,0,0,0,0,0,0,0,0,0,0,0,0,0,0,0,0,0,0,0,0,0,0,AE38,0,0,0,0,0)';
      PINUSE='GROUND';
      NO_LOAD_CHECK='Both';
      NO_IO_CHECK='Both';
      NO_ASSERT_CHECK='TRUE';
      NO_DIR_CHECK='TRUE';
      ALLOW_CONNECT='TRUE';
    'VSS'<866>:
      PIN_NUMBER='(0,0,0,0,0,0,0,0,0,0,0,0,0,0,0,0,0,0,0,0,0,0,0,0,AE40,0,0,0,0,0)';
      PINUSE='GROUND';
      NO_LOAD_CHECK='Both';
      NO_IO_CHECK='Both';
      NO_ASSERT_CHECK='TRUE';
      NO_DIR_CHECK='TRUE';
      ALLOW_CONNECT='TRUE';
    'VSS'<865>:
      PIN_NUMBER='(0,0,0,0,0,0,0,0,0,0,0,0,0,0,0,0,0,0,0,0,0,0,0,0,AE42,0,0,0,0,0)';
      PINUSE='GROUND';
      NO_LOAD_CHECK='Both';
      NO_IO_CHECK='Both';
      NO_ASSERT_CHECK='TRUE';
      NO_DIR_CHECK='TRUE';
      ALLOW_CONNECT='TRUE';
    'VSS'<864>:
      PIN_NUMBER='(0,0,0,0,0,0,0,0,0,0,0,0,0,0,0,0,0,0,0,0,0,0,0,0,AE64,0,0,0,0,0)';
      PINUSE='GROUND';
      NO_LOAD_CHECK='Both';
      NO_IO_CHECK='Both';
      NO_ASSERT_CHECK='TRUE';
      NO_DIR_CHECK='TRUE';
      ALLOW_CONNECT='TRUE';
    'VSS'<863>:
      PIN_NUMBER='(0,0,0,0,0,0,0,0,0,0,0,0,0,0,0,0,0,0,0,0,0,0,0,0,AE66,0,0,0,0,0)';
      PINUSE='GROUND';
      NO_LOAD_CHECK='Both';
      NO_IO_CHECK='Both';
      NO_ASSERT_CHECK='TRUE';
      NO_DIR_CHECK='TRUE';
      ALLOW_CONNECT='TRUE';
    'VSS'<862>:
      PIN_NUMBER='(0,0,0,0,0,0,0,0,0,0,0,0,0,0,0,0,0,0,0,0,0,0,0,0,AE68,0,0,0,0,0)';
      PINUSE='GROUND';
      NO_LOAD_CHECK='Both';
      NO_IO_CHECK='Both';
      NO_ASSERT_CHECK='TRUE';
      NO_DIR_CHECK='TRUE';
      ALLOW_CONNECT='TRUE';
    'VSS'<861>:
      PIN_NUMBER='(0,0,0,0,0,0,0,0,0,0,0,0,0,0,0,0,0,0,0,0,0,0,0,0,AE70,0,0,0,0,0)';
      PINUSE='GROUND';
      NO_LOAD_CHECK='Both';
      NO_IO_CHECK='Both';
      NO_ASSERT_CHECK='TRUE';
      NO_DIR_CHECK='TRUE';
      ALLOW_CONNECT='TRUE';
    'VSS'<860>:
      PIN_NUMBER='(0,0,0,0,0,0,0,0,0,0,0,0,0,0,0,0,0,0,0,0,0,0,0,0,AE78,0,0,0,0,0)';
      PINUSE='GROUND';
      NO_LOAD_CHECK='Both';
      NO_IO_CHECK='Both';
      NO_ASSERT_CHECK='TRUE';
      NO_DIR_CHECK='TRUE';
      ALLOW_CONNECT='TRUE';
    'VSS'<859>:
      PIN_NUMBER='(0,0,0,0,0,0,0,0,0,0,0,0,0,0,0,0,0,0,0,0,0,0,0,0,AF1,0,0,0,0,0)';
      PINUSE='GROUND';
      NO_LOAD_CHECK='Both';
      NO_IO_CHECK='Both';
      NO_ASSERT_CHECK='TRUE';
      NO_DIR_CHECK='TRUE';
      ALLOW_CONNECT='TRUE';
    'VSS'<858>:
      PIN_NUMBER='(0,0,0,0,0,0,0,0,0,0,0,0,0,0,0,0,0,0,0,0,0,0,0,0,AC52,0,0,0,0,0)';
      PINUSE='GROUND';
      NO_LOAD_CHECK='Both';
      NO_IO_CHECK='Both';
      NO_ASSERT_CHECK='TRUE';
      NO_DIR_CHECK='TRUE';
      ALLOW_CONNECT='TRUE';
    'VSS'<857>:
      PIN_NUMBER='(0,0,0,0,0,0,0,0,0,0,0,0,0,0,0,0,0,0,0,0,0,0,0,0,AF9,0,0,0,0,0)';
      PINUSE='GROUND';
      NO_LOAD_CHECK='Both';
      NO_IO_CHECK='Both';
      NO_ASSERT_CHECK='TRUE';
      NO_DIR_CHECK='TRUE';
      ALLOW_CONNECT='TRUE';
    'VSS'<856>:
      PIN_NUMBER='(0,0,0,0,0,0,0,0,0,0,0,0,0,0,0,0,0,0,0,0,0,0,0,0,AF21,0,0,0,0,0)';
      PINUSE='GROUND';
      NO_LOAD_CHECK='Both';
      NO_IO_CHECK='Both';
      NO_ASSERT_CHECK='TRUE';
      NO_DIR_CHECK='TRUE';
      ALLOW_CONNECT='TRUE';
    'VSS'<855>:
      PIN_NUMBER='(0,0,0,0,0,0,0,0,0,0,0,0,0,0,0,0,0,0,0,0,0,0,0,0,AF23,0,0,0,0,0)';
      PINUSE='GROUND';
      NO_LOAD_CHECK='Both';
      NO_IO_CHECK='Both';
      NO_ASSERT_CHECK='TRUE';
      NO_DIR_CHECK='TRUE';
      ALLOW_CONNECT='TRUE';
    'VSS'<854>:
      PIN_NUMBER='(0,0,0,0,0,0,0,0,0,0,0,0,0,0,0,0,0,0,0,0,0,0,0,0,AF25,0,0,0,0,0)';
      PINUSE='GROUND';
      NO_LOAD_CHECK='Both';
      NO_IO_CHECK='Both';
      NO_ASSERT_CHECK='TRUE';
      NO_DIR_CHECK='TRUE';
      ALLOW_CONNECT='TRUE';
    'VSS'<853>:
      PIN_NUMBER='(0,0,0,0,0,0,0,0,0,0,0,0,0,0,0,0,0,0,0,0,0,0,0,0,AF27,0,0,0,0,0)';
      PINUSE='GROUND';
      NO_LOAD_CHECK='Both';
      NO_IO_CHECK='Both';
      NO_ASSERT_CHECK='TRUE';
      NO_DIR_CHECK='TRUE';
      ALLOW_CONNECT='TRUE';
    'VSS'<852>:
      PIN_NUMBER='(0,0,0,0,0,0,0,0,0,0,0,0,0,0,0,0,0,0,0,0,0,0,0,0,AF29,0,0,0,0,0)';
      PINUSE='GROUND';
      NO_LOAD_CHECK='Both';
      NO_IO_CHECK='Both';
      NO_ASSERT_CHECK='TRUE';
      NO_DIR_CHECK='TRUE';
      ALLOW_CONNECT='TRUE';
    'VSS'<851>:
      PIN_NUMBER='(0,0,0,0,0,0,0,0,0,0,0,0,0,0,0,0,0,0,0,0,0,0,0,0,AF31,0,0,0,0,0)';
      PINUSE='GROUND';
      NO_LOAD_CHECK='Both';
      NO_IO_CHECK='Both';
      NO_ASSERT_CHECK='TRUE';
      NO_DIR_CHECK='TRUE';
      ALLOW_CONNECT='TRUE';
    'VSS'<850>:
      PIN_NUMBER='(0,0,0,0,0,0,0,0,0,0,0,0,0,0,0,0,0,0,0,0,0,0,0,0,AF33,0,0,0,0,0)';
      PINUSE='GROUND';
      NO_LOAD_CHECK='Both';
      NO_IO_CHECK='Both';
      NO_ASSERT_CHECK='TRUE';
      NO_DIR_CHECK='TRUE';
      ALLOW_CONNECT='TRUE';
    'VSS'<849>:
      PIN_NUMBER='(0,0,0,0,0,0,0,0,0,0,0,0,0,0,0,0,0,0,0,0,0,0,0,0,AF37,0,0,0,0,0)';
      PINUSE='GROUND';
      NO_LOAD_CHECK='Both';
      NO_IO_CHECK='Both';
      NO_ASSERT_CHECK='TRUE';
      NO_DIR_CHECK='TRUE';
      ALLOW_CONNECT='TRUE';
    'VSS'<848>:
      PIN_NUMBER='(0,0,0,0,0,0,0,0,0,0,0,0,0,0,0,0,0,0,0,0,0,0,0,0,AF39,0,0,0,0,0)';
      PINUSE='GROUND';
      NO_LOAD_CHECK='Both';
      NO_IO_CHECK='Both';
      NO_ASSERT_CHECK='TRUE';
      NO_DIR_CHECK='TRUE';
      ALLOW_CONNECT='TRUE';
    'VSS'<847>:
      PIN_NUMBER='(0,0,0,0,0,0,0,0,0,0,0,0,0,0,0,0,0,0,0,0,0,0,0,0,AF41,0,0,0,0,0)';
      PINUSE='GROUND';
      NO_LOAD_CHECK='Both';
      NO_IO_CHECK='Both';
      NO_ASSERT_CHECK='TRUE';
      NO_DIR_CHECK='TRUE';
      ALLOW_CONNECT='TRUE';
    'VSS'<846>:
      PIN_NUMBER='(0,0,0,0,0,0,0,0,0,0,0,0,0,0,0,0,0,0,0,0,0,0,0,0,AF73,0,0,0,0,0)';
      PINUSE='GROUND';
      NO_LOAD_CHECK='Both';
      NO_IO_CHECK='Both';
      NO_ASSERT_CHECK='TRUE';
      NO_DIR_CHECK='TRUE';
      ALLOW_CONNECT='TRUE';
    'VSS'<845>:
      PIN_NUMBER='(0,0,0,0,0,0,0,0,0,0,0,0,0,0,0,0,0,0,0,0,0,0,0,0,AF77,0,0,0,0,0)';
      PINUSE='GROUND';
      NO_LOAD_CHECK='Both';
      NO_IO_CHECK='Both';
      NO_ASSERT_CHECK='TRUE';
      NO_DIR_CHECK='TRUE';
      ALLOW_CONNECT='TRUE';
    'VSS'<844>:
      PIN_NUMBER='(0,0,0,0,0,0,0,0,0,0,0,0,0,0,0,0,0,0,0,0,0,0,0,0,AF83,0,0,0,0,0)';
      PINUSE='GROUND';
      NO_LOAD_CHECK='Both';
      NO_IO_CHECK='Both';
      NO_ASSERT_CHECK='TRUE';
      NO_DIR_CHECK='TRUE';
      ALLOW_CONNECT='TRUE';
    'VSS'<843>:
      PIN_NUMBER='(0,0,0,0,0,0,0,0,0,0,0,0,0,0,0,0,0,0,0,0,0,0,0,0,AF85,0,0,0,0,0)';
      PINUSE='GROUND';
      NO_LOAD_CHECK='Both';
      NO_IO_CHECK='Both';
      NO_ASSERT_CHECK='TRUE';
      NO_DIR_CHECK='TRUE';
      ALLOW_CONNECT='TRUE';
    'VSS'<842>:
      PIN_NUMBER='(0,0,0,0,0,0,0,0,0,0,0,0,0,0,0,0,0,0,0,0,0,0,0,0,AG12,0,0,0,0,0)';
      PINUSE='GROUND';
      NO_LOAD_CHECK='Both';
      NO_IO_CHECK='Both';
      NO_ASSERT_CHECK='TRUE';
      NO_DIR_CHECK='TRUE';
      ALLOW_CONNECT='TRUE';
    'VSS'<841>:
      PIN_NUMBER='(0,0,0,0,0,0,0,0,0,0,0,0,0,0,0,0,0,0,0,0,0,0,0,0,AG14,0,0,0,0,0)';
      PINUSE='GROUND';
      NO_LOAD_CHECK='Both';
      NO_IO_CHECK='Both';
      NO_ASSERT_CHECK='TRUE';
      NO_DIR_CHECK='TRUE';
      ALLOW_CONNECT='TRUE';
    'VSS'<840>:
      PIN_NUMBER='(0,0,0,0,0,0,0,0,0,0,0,0,0,0,0,0,0,0,0,0,0,0,0,0,AG18,0,0,0,0,0)';
      PINUSE='GROUND';
      NO_LOAD_CHECK='Both';
      NO_IO_CHECK='Both';
      NO_ASSERT_CHECK='TRUE';
      NO_DIR_CHECK='TRUE';
      ALLOW_CONNECT='TRUE';
    'VSS'<839>:
      PIN_NUMBER='(0,0,0,0,0,0,0,0,0,0,0,0,0,0,0,0,0,0,0,0,0,0,0,0,AG36,0,0,0,0,0)';
      PINUSE='GROUND';
      NO_LOAD_CHECK='Both';
      NO_IO_CHECK='Both';
      NO_ASSERT_CHECK='TRUE';
      NO_DIR_CHECK='TRUE';
      ALLOW_CONNECT='TRUE';
    'VSS'<838>:
      PIN_NUMBER='(0,0,0,0,0,0,0,0,0,0,0,0,0,0,0,0,0,0,0,0,0,0,0,0,AG64,0,0,0,0,0)';
      PINUSE='GROUND';
      NO_LOAD_CHECK='Both';
      NO_IO_CHECK='Both';
      NO_ASSERT_CHECK='TRUE';
      NO_DIR_CHECK='TRUE';
      ALLOW_CONNECT='TRUE';
    'VSS'<837>:
      PIN_NUMBER='(0,0,0,0,0,0,0,0,0,0,0,0,0,0,0,0,0,0,0,0,0,0,0,0,AG70,0,0,0,0,0)';
      PINUSE='GROUND';
      NO_LOAD_CHECK='Both';
      NO_IO_CHECK='Both';
      NO_ASSERT_CHECK='TRUE';
      NO_DIR_CHECK='TRUE';
      ALLOW_CONNECT='TRUE';
    'VSS'<836>:
      PIN_NUMBER='(0,0,0,0,0,0,0,0,0,0,0,0,0,0,0,0,0,0,0,0,0,0,0,0,AG74,0,0,0,0,0)';
      PINUSE='GROUND';
      NO_LOAD_CHECK='Both';
      NO_IO_CHECK='Both';
      NO_ASSERT_CHECK='TRUE';
      NO_DIR_CHECK='TRUE';
      ALLOW_CONNECT='TRUE';
    'VSS'<835>:
      PIN_NUMBER='(0,0,0,0,0,0,0,0,0,0,0,0,0,0,0,0,0,0,0,0,0,0,0,0,AG76,0,0,0,0,0)';
      PINUSE='GROUND';
      NO_LOAD_CHECK='Both';
      NO_IO_CHECK='Both';
      NO_ASSERT_CHECK='TRUE';
      NO_DIR_CHECK='TRUE';
      ALLOW_CONNECT='TRUE';
    'VSS'<834>:
      PIN_NUMBER='(0,0,0,0,0,0,0,0,0,0,0,0,0,0,0,0,0,0,0,0,0,0,0,0,AG78,0,0,0,0,0)';
      PINUSE='GROUND';
      NO_LOAD_CHECK='Both';
      NO_IO_CHECK='Both';
      NO_ASSERT_CHECK='TRUE';
      NO_DIR_CHECK='TRUE';
      ALLOW_CONNECT='TRUE';
    'VSS'<833>:
      PIN_NUMBER='(0,0,0,0,0,0,0,0,0,0,0,0,0,0,0,0,0,0,0,0,0,0,0,0,AG80,0,0,0,0,0)';
      PINUSE='GROUND';
      NO_LOAD_CHECK='Both';
      NO_IO_CHECK='Both';
      NO_ASSERT_CHECK='TRUE';
      NO_DIR_CHECK='TRUE';
      ALLOW_CONNECT='TRUE';
    'VSS'<832>:
      PIN_NUMBER='(0,0,0,0,0,0,0,0,0,0,0,0,0,0,0,0,0,0,0,0,0,0,0,0,AH1,0,0,0,0,0)';
      PINUSE='GROUND';
      NO_LOAD_CHECK='Both';
      NO_IO_CHECK='Both';
      NO_ASSERT_CHECK='TRUE';
      NO_DIR_CHECK='TRUE';
      ALLOW_CONNECT='TRUE';
    'VSS'<831>:
      PIN_NUMBER='(0,0,0,0,0,0,0,0,0,0,0,0,0,0,0,0,0,0,0,0,0,0,0,0,AH5,0,0,0,0,0)';
      PINUSE='GROUND';
      NO_LOAD_CHECK='Both';
      NO_IO_CHECK='Both';
      NO_ASSERT_CHECK='TRUE';
      NO_DIR_CHECK='TRUE';
      ALLOW_CONNECT='TRUE';
    'VSS'<830>:
      PIN_NUMBER='(0,0,0,0,0,0,0,0,0,0,0,0,0,0,0,0,0,0,0,0,0,0,0,0,AH21,0,0,0,0,0)';
      PINUSE='GROUND';
      NO_LOAD_CHECK='Both';
      NO_IO_CHECK='Both';
      NO_ASSERT_CHECK='TRUE';
      NO_DIR_CHECK='TRUE';
      ALLOW_CONNECT='TRUE';
    'VSS'<829>:
      PIN_NUMBER='(0,0,0,0,0,0,0,0,0,0,0,0,0,0,0,0,0,0,0,0,0,0,0,0,AH27,0,0,0,0,0)';
      PINUSE='GROUND';
      NO_LOAD_CHECK='Both';
      NO_IO_CHECK='Both';
      NO_ASSERT_CHECK='TRUE';
      NO_DIR_CHECK='TRUE';
      ALLOW_CONNECT='TRUE';
    'VSS'<828>:
      PIN_NUMBER='(0,0,0,0,0,0,0,0,0,0,0,0,0,0,0,0,0,0,0,0,0,0,0,0,AH33,0,0,0,0,0)';
      PINUSE='GROUND';
      NO_LOAD_CHECK='Both';
      NO_IO_CHECK='Both';
      NO_ASSERT_CHECK='TRUE';
      NO_DIR_CHECK='TRUE';
      ALLOW_CONNECT='TRUE';
    'VSS'<827>:
      PIN_NUMBER='(0,0,0,0,0,0,0,0,0,0,0,0,0,0,0,0,0,0,0,0,0,0,0,0,AH35,0,0,0,0,0)';
      PINUSE='GROUND';
      NO_LOAD_CHECK='Both';
      NO_IO_CHECK='Both';
      NO_ASSERT_CHECK='TRUE';
      NO_DIR_CHECK='TRUE';
      ALLOW_CONNECT='TRUE';
    'VSS'<826>:
      PIN_NUMBER='(0,0,0,0,0,0,0,0,0,0,0,0,0,0,0,0,0,0,0,0,0,0,0,0,AH45,0,0,0,0,0)';
      PINUSE='GROUND';
      NO_LOAD_CHECK='Both';
      NO_IO_CHECK='Both';
      NO_ASSERT_CHECK='TRUE';
      NO_DIR_CHECK='TRUE';
      ALLOW_CONNECT='TRUE';
    'VSS'<825>:
      PIN_NUMBER='(0,0,0,0,0,0,0,0,0,0,0,0,0,0,0,0,0,0,0,0,0,0,0,0,AH47,0,0,0,0,0)';
      PINUSE='GROUND';
      NO_LOAD_CHECK='Both';
      NO_IO_CHECK='Both';
      NO_ASSERT_CHECK='TRUE';
      NO_DIR_CHECK='TRUE';
      ALLOW_CONNECT='TRUE';
    'VSS'<824>:
      PIN_NUMBER='(0,0,0,0,0,0,0,0,0,0,0,0,0,0,0,0,0,0,0,0,0,0,0,0,AH49,0,0,0,0,0)';
      PINUSE='GROUND';
      NO_LOAD_CHECK='Both';
      NO_IO_CHECK='Both';
      NO_ASSERT_CHECK='TRUE';
      NO_DIR_CHECK='TRUE';
      ALLOW_CONNECT='TRUE';
    'VSS'<823>:
      PIN_NUMBER='(0,0,0,0,0,0,0,0,0,0,0,0,0,0,0,0,0,0,0,0,0,0,0,0,AH51,0,0,0,0,0)';
      PINUSE='GROUND';
      NO_LOAD_CHECK='Both';
      NO_IO_CHECK='Both';
      NO_ASSERT_CHECK='TRUE';
      NO_DIR_CHECK='TRUE';
      ALLOW_CONNECT='TRUE';
    'VSS'<822>:
      PIN_NUMBER='(0,0,0,0,0,0,0,0,0,0,0,0,0,0,0,0,0,0,0,0,0,0,0,0,AH53,0,0,0,0,0)';
      PINUSE='GROUND';
      NO_LOAD_CHECK='Both';
      NO_IO_CHECK='Both';
      NO_ASSERT_CHECK='TRUE';
      NO_DIR_CHECK='TRUE';
      ALLOW_CONNECT='TRUE';
    'VSS'<821>:
      PIN_NUMBER='(0,0,0,0,0,0,0,0,0,0,0,0,0,0,0,0,0,0,0,0,0,0,0,0,AH59,0,0,0,0,0)';
      PINUSE='GROUND';
      NO_LOAD_CHECK='Both';
      NO_IO_CHECK='Both';
      NO_ASSERT_CHECK='TRUE';
      NO_DIR_CHECK='TRUE';
      ALLOW_CONNECT='TRUE';
    'VSS'<820>:
      PIN_NUMBER='(0,0,0,0,0,0,0,0,0,0,0,0,0,0,0,0,0,0,0,0,0,0,0,0,AH61,0,0,0,0,0)';
      PINUSE='GROUND';
      NO_LOAD_CHECK='Both';
      NO_IO_CHECK='Both';
      NO_ASSERT_CHECK='TRUE';
      NO_DIR_CHECK='TRUE';
      ALLOW_CONNECT='TRUE';
    'VSS'<819>:
      PIN_NUMBER='(0,0,0,0,0,0,0,0,0,0,0,0,0,0,0,0,0,0,0,0,0,0,0,0,AH65,0,0,0,0,0)';
      PINUSE='GROUND';
      NO_LOAD_CHECK='Both';
      NO_IO_CHECK='Both';
      NO_ASSERT_CHECK='TRUE';
      NO_DIR_CHECK='TRUE';
      ALLOW_CONNECT='TRUE';
    'VSS'<818>:
      PIN_NUMBER='(0,0,0,0,0,0,0,0,0,0,0,0,0,0,0,0,0,0,0,0,0,0,0,0,AH69,0,0,0,0,0)';
      PINUSE='GROUND';
      NO_LOAD_CHECK='Both';
      NO_IO_CHECK='Both';
      NO_ASSERT_CHECK='TRUE';
      NO_DIR_CHECK='TRUE';
      ALLOW_CONNECT='TRUE';
    'VSS'<817>:
      PIN_NUMBER='(0,0,0,0,0,0,0,0,0,0,0,0,0,0,0,0,0,0,0,0,0,0,0,0,AH75,0,0,0,0,0)';
      PINUSE='GROUND';
      NO_LOAD_CHECK='Both';
      NO_IO_CHECK='Both';
      NO_ASSERT_CHECK='TRUE';
      NO_DIR_CHECK='TRUE';
      ALLOW_CONNECT='TRUE';
    'VSS'<816>:
      PIN_NUMBER='(0,0,0,0,0,0,0,0,0,0,0,0,0,0,0,0,0,0,0,0,0,0,0,0,AH77,0,0,0,0,0)';
      PINUSE='GROUND';
      NO_LOAD_CHECK='Both';
      NO_IO_CHECK='Both';
      NO_ASSERT_CHECK='TRUE';
      NO_DIR_CHECK='TRUE';
      ALLOW_CONNECT='TRUE';
    'VSS'<815>:
      PIN_NUMBER='(0,0,0,0,0,0,0,0,0,0,0,0,0,0,0,0,0,0,0,0,0,0,0,0,AH83,0,0,0,0,0)';
      PINUSE='GROUND';
      NO_LOAD_CHECK='Both';
      NO_IO_CHECK='Both';
      NO_ASSERT_CHECK='TRUE';
      NO_DIR_CHECK='TRUE';
      ALLOW_CONNECT='TRUE';
    'VSS'<814>:
      PIN_NUMBER='(0,0,0,0,0,0,0,0,0,0,0,0,0,0,0,0,0,0,0,0,0,0,0,0,AJ8,0,0,0,0,0)';
      PINUSE='GROUND';
      NO_LOAD_CHECK='Both';
      NO_IO_CHECK='Both';
      NO_ASSERT_CHECK='TRUE';
      NO_DIR_CHECK='TRUE';
      ALLOW_CONNECT='TRUE';
    'VSS'<813>:
      PIN_NUMBER='(0,0,0,0,0,0,0,0,0,0,0,0,0,0,0,0,0,0,0,0,0,0,0,0,AJ22,0,0,0,0,0)';
      PINUSE='GROUND';
      NO_LOAD_CHECK='Both';
      NO_IO_CHECK='Both';
      NO_ASSERT_CHECK='TRUE';
      NO_DIR_CHECK='TRUE';
      ALLOW_CONNECT='TRUE';
    'VSS'<812>:
      PIN_NUMBER='(0,0,0,0,0,0,0,0,0,0,0,0,0,0,0,0,0,0,0,0,0,0,0,0,AJ26,0,0,0,0,0)';
      PINUSE='GROUND';
      NO_LOAD_CHECK='Both';
      NO_IO_CHECK='Both';
      NO_ASSERT_CHECK='TRUE';
      NO_DIR_CHECK='TRUE';
      ALLOW_CONNECT='TRUE';
    'VSS'<811>:
      PIN_NUMBER='(0,0,0,0,0,0,0,0,0,0,0,0,0,0,0,0,0,0,0,0,0,0,0,0,AJ28,0,0,0,0,0)';
      PINUSE='GROUND';
      NO_LOAD_CHECK='Both';
      NO_IO_CHECK='Both';
      NO_ASSERT_CHECK='TRUE';
      NO_DIR_CHECK='TRUE';
      ALLOW_CONNECT='TRUE';
    'VSS'<810>:
      PIN_NUMBER='(0,0,0,0,0,0,0,0,0,0,0,0,0,0,0,0,0,0,0,0,0,0,0,0,AJ32,0,0,0,0,0)';
      PINUSE='GROUND';
      NO_LOAD_CHECK='Both';
      NO_IO_CHECK='Both';
      NO_ASSERT_CHECK='TRUE';
      NO_DIR_CHECK='TRUE';
      ALLOW_CONNECT='TRUE';
    'VSS'<809>:
      PIN_NUMBER='(0,0,0,0,0,0,0,0,0,0,0,0,0,0,0,0,0,0,0,0,0,0,0,0,AJ34,0,0,0,0,0)';
      PINUSE='GROUND';
      NO_LOAD_CHECK='Both';
      NO_IO_CHECK='Both';
      NO_ASSERT_CHECK='TRUE';
      NO_DIR_CHECK='TRUE';
      ALLOW_CONNECT='TRUE';
    'VSS'<808>:
      PIN_NUMBER='(0,0,0,0,0,0,0,0,0,0,0,0,0,0,0,0,0,0,0,0,0,0,0,0,AJ46,0,0,0,0,0)';
      PINUSE='GROUND';
      NO_LOAD_CHECK='Both';
      NO_IO_CHECK='Both';
      NO_ASSERT_CHECK='TRUE';
      NO_DIR_CHECK='TRUE';
      ALLOW_CONNECT='TRUE';
    'VSS'<807>:
      PIN_NUMBER='(0,0,0,0,0,0,0,0,0,0,0,0,0,0,0,0,0,0,0,0,0,0,0,0,AJ48,0,0,0,0,0)';
      PINUSE='GROUND';
      NO_LOAD_CHECK='Both';
      NO_IO_CHECK='Both';
      NO_ASSERT_CHECK='TRUE';
      NO_DIR_CHECK='TRUE';
      ALLOW_CONNECT='TRUE';
    'VSS'<806>:
      PIN_NUMBER='(0,0,0,0,0,0,0,0,0,0,0,0,0,0,0,0,0,0,0,0,0,0,0,0,AJ50,0,0,0,0,0)';
      PINUSE='GROUND';
      NO_LOAD_CHECK='Both';
      NO_IO_CHECK='Both';
      NO_ASSERT_CHECK='TRUE';
      NO_DIR_CHECK='TRUE';
      ALLOW_CONNECT='TRUE';
    'VSS'<805>:
      PIN_NUMBER='(0,0,0,0,0,0,0,0,0,0,0,0,0,0,0,0,0,0,0,0,0,0,0,0,AJ52,0,0,0,0,0)';
      PINUSE='GROUND';
      NO_LOAD_CHECK='Both';
      NO_IO_CHECK='Both';
      NO_ASSERT_CHECK='TRUE';
      NO_DIR_CHECK='TRUE';
      ALLOW_CONNECT='TRUE';
    'VSS'<804>:
      PIN_NUMBER='(0,0,0,0,0,0,0,0,0,0,0,0,0,0,0,0,0,0,0,0,0,0,0,0,AJ54,0,0,0,0,0)';
      PINUSE='GROUND';
      NO_LOAD_CHECK='Both';
      NO_IO_CHECK='Both';
      NO_ASSERT_CHECK='TRUE';
      NO_DIR_CHECK='TRUE';
      ALLOW_CONNECT='TRUE';
    'VSS'<803>:
      PIN_NUMBER='(0,0,0,0,0,0,0,0,0,0,0,0,0,0,0,0,0,0,0,0,0,0,0,0,AJ66,0,0,0,0,0)';
      PINUSE='GROUND';
      NO_LOAD_CHECK='Both';
      NO_IO_CHECK='Both';
      NO_ASSERT_CHECK='TRUE';
      NO_DIR_CHECK='TRUE';
      ALLOW_CONNECT='TRUE';
    'VSS'<802>:
      PIN_NUMBER='(0,0,0,0,0,0,0,0,0,0,0,0,0,0,0,0,0,0,0,0,0,0,0,0,AJ68,0,0,0,0,0)';
      PINUSE='GROUND';
      NO_LOAD_CHECK='Both';
      NO_IO_CHECK='Both';
      NO_ASSERT_CHECK='TRUE';
      NO_DIR_CHECK='TRUE';
      ALLOW_CONNECT='TRUE';
    'VSS'<801>:
      PIN_NUMBER='(0,0,0,0,0,0,0,0,0,0,0,0,0,0,0,0,0,0,0,0,0,0,0,0,AJ74,0,0,0,0,0)';
      PINUSE='GROUND';
      NO_LOAD_CHECK='Both';
      NO_IO_CHECK='Both';
      NO_ASSERT_CHECK='TRUE';
      NO_DIR_CHECK='TRUE';
      ALLOW_CONNECT='TRUE';
    'VSS'<800>:
      PIN_NUMBER='(0,0,0,0,0,0,0,0,0,0,0,0,0,0,0,0,0,0,0,0,0,0,0,0,AJ78,0,0,0,0,0)';
      PINUSE='GROUND';
      NO_LOAD_CHECK='Both';
      NO_IO_CHECK='Both';
      NO_ASSERT_CHECK='TRUE';
      NO_DIR_CHECK='TRUE';
      ALLOW_CONNECT='TRUE';
    'VSS'<799>:
      PIN_NUMBER='(0,0,0,0,0,0,0,0,0,0,0,0,0,0,0,0,0,0,0,0,0,0,0,0,AJ82,0,0,0,0,0)';
      PINUSE='GROUND';
      NO_LOAD_CHECK='Both';
      NO_IO_CHECK='Both';
      NO_ASSERT_CHECK='TRUE';
      NO_DIR_CHECK='TRUE';
      ALLOW_CONNECT='TRUE';
    'VSS'<798>:
      PIN_NUMBER='(0,0,0,0,0,0,0,0,0,0,0,0,0,0,0,0,0,0,0,0,0,0,0,0,AJ86,0,0,0,0,0)';
      PINUSE='GROUND';
      NO_LOAD_CHECK='Both';
      NO_IO_CHECK='Both';
      NO_ASSERT_CHECK='TRUE';
      NO_DIR_CHECK='TRUE';
      ALLOW_CONNECT='TRUE';
    'VSS'<797>:
      PIN_NUMBER='(0,0,0,0,0,0,0,0,0,0,0,0,0,0,0,0,0,0,0,0,0,0,0,0,AK9,0,0,0,0,0)';
      PINUSE='GROUND';
      NO_LOAD_CHECK='Both';
      NO_IO_CHECK='Both';
      NO_ASSERT_CHECK='TRUE';
      NO_DIR_CHECK='TRUE';
      ALLOW_CONNECT='TRUE';
    'VSS'<796>:
      PIN_NUMBER='(0,0,0,0,0,0,0,0,0,0,0,0,0,0,0,0,0,0,0,0,0,0,0,0,AK13,0,0,0,0,0)';
      PINUSE='GROUND';
      NO_LOAD_CHECK='Both';
      NO_IO_CHECK='Both';
      NO_ASSERT_CHECK='TRUE';
      NO_DIR_CHECK='TRUE';
      ALLOW_CONNECT='TRUE';
    'VSS'<795>:
      PIN_NUMBER='(0,0,0,0,0,0,0,0,0,0,0,0,0,0,0,0,0,0,0,0,0,0,0,0,AK19,0,0,0,0,0)';
      PINUSE='GROUND';
      NO_LOAD_CHECK='Both';
      NO_IO_CHECK='Both';
      NO_ASSERT_CHECK='TRUE';
      NO_DIR_CHECK='TRUE';
      ALLOW_CONNECT='TRUE';
    'VSS'<794>:
      PIN_NUMBER='(0,0,0,0,0,0,0,0,0,0,0,0,0,0,0,0,0,0,0,0,0,0,0,0,AK23,0,0,0,0,0)';
      PINUSE='GROUND';
      NO_LOAD_CHECK='Both';
      NO_IO_CHECK='Both';
      NO_ASSERT_CHECK='TRUE';
      NO_DIR_CHECK='TRUE';
      ALLOW_CONNECT='TRUE';
    'VSS'<793>:
      PIN_NUMBER='(0,0,0,0,0,0,0,0,0,0,0,0,0,0,0,0,0,0,0,0,0,0,0,0,AK25,0,0,0,0,0)';
      PINUSE='GROUND';
      NO_LOAD_CHECK='Both';
      NO_IO_CHECK='Both';
      NO_ASSERT_CHECK='TRUE';
      NO_DIR_CHECK='TRUE';
      ALLOW_CONNECT='TRUE';
    'VSS'<792>:
      PIN_NUMBER='(0,0,0,0,0,0,0,0,0,0,0,0,0,0,0,0,0,0,0,0,0,0,0,0,AK29,0,0,0,0,0)';
      PINUSE='GROUND';
      NO_LOAD_CHECK='Both';
      NO_IO_CHECK='Both';
      NO_ASSERT_CHECK='TRUE';
      NO_DIR_CHECK='TRUE';
      ALLOW_CONNECT='TRUE';
    'VSS'<791>:
      PIN_NUMBER='(0,0,0,0,0,0,0,0,0,0,0,0,0,0,0,0,0,0,0,0,0,0,0,0,AK31,0,0,0,0,0)';
      PINUSE='GROUND';
      NO_LOAD_CHECK='Both';
      NO_IO_CHECK='Both';
      NO_ASSERT_CHECK='TRUE';
      NO_DIR_CHECK='TRUE';
      ALLOW_CONNECT='TRUE';
    'VSS'<790>:
      PIN_NUMBER='(0,0,0,0,0,0,0,0,0,0,0,0,0,0,0,0,0,0,0,0,0,0,0,0,AK33,0,0,0,0,0)';
      PINUSE='GROUND';
      NO_LOAD_CHECK='Both';
      NO_IO_CHECK='Both';
      NO_ASSERT_CHECK='TRUE';
      NO_DIR_CHECK='TRUE';
      ALLOW_CONNECT='TRUE';
    'VSS'<789>:
      PIN_NUMBER='(0,0,0,0,0,0,0,0,0,0,0,0,0,0,0,0,0,0,0,0,0,0,0,0,AK55,0,0,0,0,0)';
      PINUSE='GROUND';
      NO_LOAD_CHECK='Both';
      NO_IO_CHECK='Both';
      NO_ASSERT_CHECK='TRUE';
      NO_DIR_CHECK='TRUE';
      ALLOW_CONNECT='TRUE';
    'VSS'<788>:
      PIN_NUMBER='(0,0,0,0,0,0,0,0,0,0,0,0,0,0,0,0,0,0,0,0,0,0,0,0,AK65,0,0,0,0,0)';
      PINUSE='GROUND';
      NO_LOAD_CHECK='Both';
      NO_IO_CHECK='Both';
      NO_ASSERT_CHECK='TRUE';
      NO_DIR_CHECK='TRUE';
      ALLOW_CONNECT='TRUE';
    'VSS'<787>:
      PIN_NUMBER='(0,0,0,0,0,0,0,0,0,0,0,0,0,0,0,0,0,0,0,0,0,0,0,0,AK67,0,0,0,0,0)';
      PINUSE='GROUND';
      NO_LOAD_CHECK='Both';
      NO_IO_CHECK='Both';
      NO_ASSERT_CHECK='TRUE';
      NO_DIR_CHECK='TRUE';
      ALLOW_CONNECT='TRUE';
    'VSS'<786>:
      PIN_NUMBER='(0,0,0,0,0,0,0,0,0,0,0,0,0,0,0,0,0,0,0,0,0,0,0,0,AK73,0,0,0,0,0)';
      PINUSE='GROUND';
      NO_LOAD_CHECK='Both';
      NO_IO_CHECK='Both';
      NO_ASSERT_CHECK='TRUE';
      NO_DIR_CHECK='TRUE';
      ALLOW_CONNECT='TRUE';
    'VSS'<785>:
      PIN_NUMBER='(0,0,0,0,0,0,0,0,0,0,0,0,0,0,0,0,0,0,0,0,0,0,0,0,AK79,0,0,0,0,0)';
      PINUSE='GROUND';
      NO_LOAD_CHECK='Both';
      NO_IO_CHECK='Both';
      NO_ASSERT_CHECK='TRUE';
      NO_DIR_CHECK='TRUE';
      ALLOW_CONNECT='TRUE';
    'VSS'<784>:
      PIN_NUMBER='(0,0,0,0,0,0,0,0,0,0,0,0,0,0,0,0,0,0,0,0,0,0,0,0,AK81,0,0,0,0,0)';
      PINUSE='GROUND';
      NO_LOAD_CHECK='Both';
      NO_IO_CHECK='Both';
      NO_ASSERT_CHECK='TRUE';
      NO_DIR_CHECK='TRUE';
      ALLOW_CONNECT='TRUE';
    'VSS'<783>:
      PIN_NUMBER='(0,0,0,0,0,0,0,0,0,0,0,0,0,0,0,0,0,0,0,0,0,0,0,0,AK83,0,0,0,0,0)';
      PINUSE='GROUND';
      NO_LOAD_CHECK='Both';
      NO_IO_CHECK='Both';
      NO_ASSERT_CHECK='TRUE';
      NO_DIR_CHECK='TRUE';
      ALLOW_CONNECT='TRUE';
    'VSS'<782>:
      PIN_NUMBER='(0,0,0,0,0,0,0,0,0,0,0,0,0,0,0,0,0,0,0,0,0,0,0,0,AK85,0,0,0,0,0)';
      PINUSE='GROUND';
      NO_LOAD_CHECK='Both';
      NO_IO_CHECK='Both';
      NO_ASSERT_CHECK='TRUE';
      NO_DIR_CHECK='TRUE';
      ALLOW_CONNECT='TRUE';
    'VSS'<781>:
      PIN_NUMBER='(0,0,0,0,0,0,0,0,0,0,0,0,0,0,0,0,0,0,0,0,0,0,0,0,AL4,0,0,0,0,0)';
      PINUSE='GROUND';
      NO_LOAD_CHECK='Both';
      NO_IO_CHECK='Both';
      NO_ASSERT_CHECK='TRUE';
      NO_DIR_CHECK='TRUE';
      ALLOW_CONNECT='TRUE';
    'VSS'<780>:
      PIN_NUMBER='(0,0,0,0,0,0,0,0,0,0,0,0,0,0,0,0,0,0,0,0,0,0,0,0,AL10,0,0,0,0,0)';
      PINUSE='GROUND';
      NO_LOAD_CHECK='Both';
      NO_IO_CHECK='Both';
      NO_ASSERT_CHECK='TRUE';
      NO_DIR_CHECK='TRUE';
      ALLOW_CONNECT='TRUE';
    'VSS'<779>:
      PIN_NUMBER='(0,0,0,0,0,0,0,0,0,0,0,0,0,0,0,0,0,0,0,0,0,0,0,0,AL24,0,0,0,0,0)';
      PINUSE='GROUND';
      NO_LOAD_CHECK='Both';
      NO_IO_CHECK='Both';
      NO_ASSERT_CHECK='TRUE';
      NO_DIR_CHECK='TRUE';
      ALLOW_CONNECT='TRUE';
    'VSS'<778>:
      PIN_NUMBER='(0,0,0,0,0,0,0,0,0,0,0,0,0,0,0,0,0,0,0,0,0,0,0,0,AL30,0,0,0,0,0)';
      PINUSE='GROUND';
      NO_LOAD_CHECK='Both';
      NO_IO_CHECK='Both';
      NO_ASSERT_CHECK='TRUE';
      NO_DIR_CHECK='TRUE';
      ALLOW_CONNECT='TRUE';
    'VSS'<777>:
      PIN_NUMBER='(0,0,0,0,0,0,0,0,0,0,0,0,0,0,0,0,0,0,0,0,0,0,0,0,AL32,0,0,0,0,0)';
      PINUSE='GROUND';
      NO_LOAD_CHECK='Both';
      NO_IO_CHECK='Both';
      NO_ASSERT_CHECK='TRUE';
      NO_DIR_CHECK='TRUE';
      ALLOW_CONNECT='TRUE';
    'VSS'<776>:
      PIN_NUMBER='(0,0,0,0,0,0,0,0,0,0,0,0,0,0,0,0,0,0,0,0,0,0,0,0,AL56,0,0,0,0,0)';
      PINUSE='GROUND';
      NO_LOAD_CHECK='Both';
      NO_IO_CHECK='Both';
      NO_ASSERT_CHECK='TRUE';
      NO_DIR_CHECK='TRUE';
      ALLOW_CONNECT='TRUE';
    'VSS'<775>:
      PIN_NUMBER='(0,0,0,0,0,0,0,0,0,0,0,0,0,0,0,0,0,0,0,0,0,0,0,0,AL64,0,0,0,0,0)';
      PINUSE='GROUND';
      NO_LOAD_CHECK='Both';
      NO_IO_CHECK='Both';
      NO_ASSERT_CHECK='TRUE';
      NO_DIR_CHECK='TRUE';
      ALLOW_CONNECT='TRUE';
    'VSS'<774>:
      PIN_NUMBER='(0,0,0,0,0,0,0,0,0,0,0,0,0,0,0,0,0,0,0,0,0,0,0,0,AL68,0,0,0,0,0)';
      PINUSE='GROUND';
      NO_LOAD_CHECK='Both';
      NO_IO_CHECK='Both';
      NO_ASSERT_CHECK='TRUE';
      NO_DIR_CHECK='TRUE';
      ALLOW_CONNECT='TRUE';
    'VSS'<773>:
      PIN_NUMBER='(0,0,0,0,0,0,0,0,0,0,0,0,0,0,0,0,0,0,0,0,0,0,0,0,0,AL76,0,0,0,0)';
      PINUSE='GROUND';
      NO_LOAD_CHECK='Both';
      NO_IO_CHECK='Both';
      NO_ASSERT_CHECK='TRUE';
      NO_DIR_CHECK='TRUE';
      ALLOW_CONNECT='TRUE';
    'VSS'<772>:
      PIN_NUMBER='(0,0,0,0,0,0,0,0,0,0,0,0,0,0,0,0,0,0,0,0,0,0,0,0,0,AL78,0,0,0,0)';
      PINUSE='GROUND';
      NO_LOAD_CHECK='Both';
      NO_IO_CHECK='Both';
      NO_ASSERT_CHECK='TRUE';
      NO_DIR_CHECK='TRUE';
      ALLOW_CONNECT='TRUE';
    'VSS'<771>:
      PIN_NUMBER='(0,0,0,0,0,0,0,0,0,0,0,0,0,0,0,0,0,0,0,0,0,0,0,0,0,AL80,0,0,0,0)';
      PINUSE='GROUND';
      NO_LOAD_CHECK='Both';
      NO_IO_CHECK='Both';
      NO_ASSERT_CHECK='TRUE';
      NO_DIR_CHECK='TRUE';
      ALLOW_CONNECT='TRUE';
    'VSS'<770>:
      PIN_NUMBER='(0,0,0,0,0,0,0,0,0,0,0,0,0,0,0,0,0,0,0,0,0,0,0,0,0,AL82,0,0,0,0)';
      PINUSE='GROUND';
      NO_LOAD_CHECK='Both';
      NO_IO_CHECK='Both';
      NO_ASSERT_CHECK='TRUE';
      NO_DIR_CHECK='TRUE';
      ALLOW_CONNECT='TRUE';
    'VSS'<769>:
      PIN_NUMBER='(0,0,0,0,0,0,0,0,0,0,0,0,0,0,0,0,0,0,0,0,0,0,0,0,0,AL86,0,0,0,0)';
      PINUSE='GROUND';
      NO_LOAD_CHECK='Both';
      NO_IO_CHECK='Both';
      NO_ASSERT_CHECK='TRUE';
      NO_DIR_CHECK='TRUE';
      ALLOW_CONNECT='TRUE';
    'VSS'<768>:
      PIN_NUMBER='(0,0,0,0,0,0,0,0,0,0,0,0,0,0,0,0,0,0,0,0,0,0,0,0,0,AM1,0,0,0,0)';
      PINUSE='GROUND';
      NO_LOAD_CHECK='Both';
      NO_IO_CHECK='Both';
      NO_ASSERT_CHECK='TRUE';
      NO_DIR_CHECK='TRUE';
      ALLOW_CONNECT='TRUE';
    'VSS'<767>:
      PIN_NUMBER='(0,0,0,0,0,0,0,0,0,0,0,0,0,0,0,0,0,0,0,0,0,0,0,0,0,AC50,0,0,0,0)';
      PINUSE='GROUND';
      NO_LOAD_CHECK='Both';
      NO_IO_CHECK='Both';
      NO_ASSERT_CHECK='TRUE';
      NO_DIR_CHECK='TRUE';
      ALLOW_CONNECT='TRUE';
    'VSS'<766>:
      PIN_NUMBER='(0,0,0,0,0,0,0,0,0,0,0,0,0,0,0,0,0,0,0,0,0,0,0,0,0,AM31,0,0,0,0)';
      PINUSE='GROUND';
      NO_LOAD_CHECK='Both';
      NO_IO_CHECK='Both';
      NO_ASSERT_CHECK='TRUE';
      NO_DIR_CHECK='TRUE';
      ALLOW_CONNECT='TRUE';
    'VSS'<765>:
      PIN_NUMBER='(0,0,0,0,0,0,0,0,0,0,0,0,0,0,0,0,0,0,0,0,0,0,0,0,0,AM57,0,0,0,0)';
      PINUSE='GROUND';
      NO_LOAD_CHECK='Both';
      NO_IO_CHECK='Both';
      NO_ASSERT_CHECK='TRUE';
      NO_DIR_CHECK='TRUE';
      ALLOW_CONNECT='TRUE';
    'VSS'<764>:
      PIN_NUMBER='(0,0,0,0,0,0,0,0,0,0,0,0,0,0,0,0,0,0,0,0,0,0,0,0,0,AM63,0,0,0,0)';
      PINUSE='GROUND';
      NO_LOAD_CHECK='Both';
      NO_IO_CHECK='Both';
      NO_ASSERT_CHECK='TRUE';
      NO_DIR_CHECK='TRUE';
      ALLOW_CONNECT='TRUE';
    'VSS'<763>:
      PIN_NUMBER='(0,0,0,0,0,0,0,0,0,0,0,0,0,0,0,0,0,0,0,0,0,0,0,0,0,AM69,0,0,0,0)';
      PINUSE='GROUND';
      NO_LOAD_CHECK='Both';
      NO_IO_CHECK='Both';
      NO_ASSERT_CHECK='TRUE';
      NO_DIR_CHECK='TRUE';
      ALLOW_CONNECT='TRUE';
    'VSS'<762>:
      PIN_NUMBER='(0,0,0,0,0,0,0,0,0,0,0,0,0,0,0,0,0,0,0,0,0,0,0,0,0,AM73,0,0,0,0)';
      PINUSE='GROUND';
      NO_LOAD_CHECK='Both';
      NO_IO_CHECK='Both';
      NO_ASSERT_CHECK='TRUE';
      NO_DIR_CHECK='TRUE';
      ALLOW_CONNECT='TRUE';
    'VSS'<761>:
      PIN_NUMBER='(0,0,0,0,0,0,0,0,0,0,0,0,0,0,0,0,0,0,0,0,0,0,0,0,0,AM79,0,0,0,0)';
      PINUSE='GROUND';
      NO_LOAD_CHECK='Both';
      NO_IO_CHECK='Both';
      NO_ASSERT_CHECK='TRUE';
      NO_DIR_CHECK='TRUE';
      ALLOW_CONNECT='TRUE';
    'VSS'<760>:
      PIN_NUMBER='(0,0,0,0,0,0,0,0,0,0,0,0,0,0,0,0,0,0,0,0,0,0,0,0,0,AM83,0,0,0,0)';
      PINUSE='GROUND';
      NO_LOAD_CHECK='Both';
      NO_IO_CHECK='Both';
      NO_ASSERT_CHECK='TRUE';
      NO_DIR_CHECK='TRUE';
      ALLOW_CONNECT='TRUE';
    'VSS'<759>:
      PIN_NUMBER='(0,0,0,0,0,0,0,0,0,0,0,0,0,0,0,0,0,0,0,0,0,0,0,0,0,AN2,0,0,0,0)';
      PINUSE='GROUND';
      NO_LOAD_CHECK='Both';
      NO_IO_CHECK='Both';
      NO_ASSERT_CHECK='TRUE';
      NO_DIR_CHECK='TRUE';
      ALLOW_CONNECT='TRUE';
    'VSS'<758>:
      PIN_NUMBER='(0,0,0,0,0,0,0,0,0,0,0,0,0,0,0,0,0,0,0,0,0,0,0,0,0,AN6,0,0,0,0)';
      PINUSE='GROUND';
      NO_LOAD_CHECK='Both';
      NO_IO_CHECK='Both';
      NO_ASSERT_CHECK='TRUE';
      NO_DIR_CHECK='TRUE';
      ALLOW_CONNECT='TRUE';
    'VSS'<757>:
      PIN_NUMBER='(0,0,0,0,0,0,0,0,0,0,0,0,0,0,0,0,0,0,0,0,0,0,0,0,0,AN28,0,0,0,0)';
      PINUSE='GROUND';
      NO_LOAD_CHECK='Both';
      NO_IO_CHECK='Both';
      NO_ASSERT_CHECK='TRUE';
      NO_DIR_CHECK='TRUE';
      ALLOW_CONNECT='TRUE';
    'VSS'<756>:
      PIN_NUMBER='(0,0,0,0,0,0,0,0,0,0,0,0,0,0,0,0,0,0,0,0,0,0,0,0,0,AN58,0,0,0,0)';
      PINUSE='GROUND';
      NO_LOAD_CHECK='Both';
      NO_IO_CHECK='Both';
      NO_ASSERT_CHECK='TRUE';
      NO_DIR_CHECK='TRUE';
      ALLOW_CONNECT='TRUE';
    'VSS'<755>:
      PIN_NUMBER='(0,0,0,0,0,0,0,0,0,0,0,0,0,0,0,0,0,0,0,0,0,0,0,0,0,AN78,0,0,0,0)';
      PINUSE='GROUND';
      NO_LOAD_CHECK='Both';
      NO_IO_CHECK='Both';
      NO_ASSERT_CHECK='TRUE';
      NO_DIR_CHECK='TRUE';
      ALLOW_CONNECT='TRUE';
    'VSS'<754>:
      PIN_NUMBER='(0,0,0,0,0,0,0,0,0,0,0,0,0,0,0,0,0,0,0,0,0,0,0,0,0,AP5,0,0,0,0)';
      PINUSE='GROUND';
      NO_LOAD_CHECK='Both';
      NO_IO_CHECK='Both';
      NO_ASSERT_CHECK='TRUE';
      NO_DIR_CHECK='TRUE';
      ALLOW_CONNECT='TRUE';
    'VSS'<753>:
      PIN_NUMBER='(0,0,0,0,0,0,0,0,0,0,0,0,0,0,0,0,0,0,0,0,0,0,0,0,0,AP9,0,0,0,0)';
      PINUSE='GROUND';
      NO_LOAD_CHECK='Both';
      NO_IO_CHECK='Both';
      NO_ASSERT_CHECK='TRUE';
      NO_DIR_CHECK='TRUE';
      ALLOW_CONNECT='TRUE';
    'VSS'<752>:
      PIN_NUMBER='(0,0,0,0,0,0,0,0,0,0,0,0,0,0,0,0,0,0,0,0,0,0,0,0,0,AP13,0,0,0,0)';
      PINUSE='GROUND';
      NO_LOAD_CHECK='Both';
      NO_IO_CHECK='Both';
      NO_ASSERT_CHECK='TRUE';
      NO_DIR_CHECK='TRUE';
      ALLOW_CONNECT='TRUE';
    'VSS'<751>:
      PIN_NUMBER='(0,0,0,0,0,0,0,0,0,0,0,0,0,0,0,0,0,0,0,0,0,0,0,0,0,AP19,0,0,0,0)';
      PINUSE='GROUND';
      NO_LOAD_CHECK='Both';
      NO_IO_CHECK='Both';
      NO_ASSERT_CHECK='TRUE';
      NO_DIR_CHECK='TRUE';
      ALLOW_CONNECT='TRUE';
    'VSS'<750>:
      PIN_NUMBER='(0,0,0,0,0,0,0,0,0,0,0,0,0,0,0,0,0,0,0,0,0,0,0,0,0,AP31,0,0,0,0)';
      PINUSE='GROUND';
      NO_LOAD_CHECK='Both';
      NO_IO_CHECK='Both';
      NO_ASSERT_CHECK='TRUE';
      NO_DIR_CHECK='TRUE';
      ALLOW_CONNECT='TRUE';
    'VSS'<749>:
      PIN_NUMBER='(0,0,0,0,0,0,0,0,0,0,0,0,0,0,0,0,0,0,0,0,0,0,0,0,0,AP59,0,0,0,0)';
      PINUSE='GROUND';
      NO_LOAD_CHECK='Both';
      NO_IO_CHECK='Both';
      NO_ASSERT_CHECK='TRUE';
      NO_DIR_CHECK='TRUE';
      ALLOW_CONNECT='TRUE';
    'VSS'<748>:
      PIN_NUMBER='(0,0,0,0,0,0,0,0,0,0,0,0,0,0,0,0,0,0,0,0,0,0,0,0,0,AP63,0,0,0,0)';
      PINUSE='GROUND';
      NO_LOAD_CHECK='Both';
      NO_IO_CHECK='Both';
      NO_ASSERT_CHECK='TRUE';
      NO_DIR_CHECK='TRUE';
      ALLOW_CONNECT='TRUE';
    'VSS'<747>:
      PIN_NUMBER='(0,0,0,0,0,0,0,0,0,0,0,0,0,0,0,0,0,0,0,0,0,0,0,0,0,AP65,0,0,0,0)';
      PINUSE='GROUND';
      NO_LOAD_CHECK='Both';
      NO_IO_CHECK='Both';
      NO_ASSERT_CHECK='TRUE';
      NO_DIR_CHECK='TRUE';
      ALLOW_CONNECT='TRUE';
    'VSS'<746>:
      PIN_NUMBER='(0,0,0,0,0,0,0,0,0,0,0,0,0,0,0,0,0,0,0,0,0,0,0,0,0,AP67,0,0,0,0)';
      PINUSE='GROUND';
      NO_LOAD_CHECK='Both';
      NO_IO_CHECK='Both';
      NO_ASSERT_CHECK='TRUE';
      NO_DIR_CHECK='TRUE';
      ALLOW_CONNECT='TRUE';
    'VSS'<745>:
      PIN_NUMBER='(0,0,0,0,0,0,0,0,0,0,0,0,0,0,0,0,0,0,0,0,0,0,0,0,0,AP69,0,0,0,0)';
      PINUSE='GROUND';
      NO_LOAD_CHECK='Both';
      NO_IO_CHECK='Both';
      NO_ASSERT_CHECK='TRUE';
      NO_DIR_CHECK='TRUE';
      ALLOW_CONNECT='TRUE';
    'VSS'<744>:
      PIN_NUMBER='(0,0,0,0,0,0,0,0,0,0,0,0,0,0,0,0,0,0,0,0,0,0,0,0,0,AP73,0,0,0,0)';
      PINUSE='GROUND';
      NO_LOAD_CHECK='Both';
      NO_IO_CHECK='Both';
      NO_ASSERT_CHECK='TRUE';
      NO_DIR_CHECK='TRUE';
      ALLOW_CONNECT='TRUE';
    'VSS'<743>:
      PIN_NUMBER='(0,0,0,0,0,0,0,0,0,0,0,0,0,0,0,0,0,0,0,0,0,0,0,0,0,AP75,0,0,0,0)';
      PINUSE='GROUND';
      NO_LOAD_CHECK='Both';
      NO_IO_CHECK='Both';
      NO_ASSERT_CHECK='TRUE';
      NO_DIR_CHECK='TRUE';
      ALLOW_CONNECT='TRUE';
    'VSS'<742>:
      PIN_NUMBER='(0,0,0,0,0,0,0,0,0,0,0,0,0,0,0,0,0,0,0,0,0,0,0,0,0,AP81,0,0,0,0)';
      PINUSE='GROUND';
      NO_LOAD_CHECK='Both';
      NO_IO_CHECK='Both';
      NO_ASSERT_CHECK='TRUE';
      NO_DIR_CHECK='TRUE';
      ALLOW_CONNECT='TRUE';
    'VSS'<741>:
      PIN_NUMBER='(0,0,0,0,0,0,0,0,0,0,0,0,0,0,0,0,0,0,0,0,0,0,0,0,0,AP83,0,0,0,0)';
      PINUSE='GROUND';
      NO_LOAD_CHECK='Both';
      NO_IO_CHECK='Both';
      NO_ASSERT_CHECK='TRUE';
      NO_DIR_CHECK='TRUE';
      ALLOW_CONNECT='TRUE';
    'VSS'<740>:
      PIN_NUMBER='(0,0,0,0,0,0,0,0,0,0,0,0,0,0,0,0,0,0,0,0,0,0,0,0,0,AP85,0,0,0,0)';
      PINUSE='GROUND';
      NO_LOAD_CHECK='Both';
      NO_IO_CHECK='Both';
      NO_ASSERT_CHECK='TRUE';
      NO_DIR_CHECK='TRUE';
      ALLOW_CONNECT='TRUE';
    'VSS'<739>:
      PIN_NUMBER='(0,0,0,0,0,0,0,0,0,0,0,0,0,0,0,0,0,0,0,0,0,0,0,0,0,AR10,0,0,0,0)';
      PINUSE='GROUND';
      NO_LOAD_CHECK='Both';
      NO_IO_CHECK='Both';
      NO_ASSERT_CHECK='TRUE';
      NO_DIR_CHECK='TRUE';
      ALLOW_CONNECT='TRUE';
    'VSS'<738>:
      PIN_NUMBER='(0,0,0,0,0,0,0,0,0,0,0,0,0,0,0,0,0,0,0,0,0,0,0,0,0,AR24,0,0,0,0)';
      PINUSE='GROUND';
      NO_LOAD_CHECK='Both';
      NO_IO_CHECK='Both';
      NO_ASSERT_CHECK='TRUE';
      NO_DIR_CHECK='TRUE';
      ALLOW_CONNECT='TRUE';
    'VSS'<737>:
      PIN_NUMBER='(0,0,0,0,0,0,0,0,0,0,0,0,0,0,0,0,0,0,0,0,0,0,0,0,0,AR30,0,0,0,0)';
      PINUSE='GROUND';
      NO_LOAD_CHECK='Both';
      NO_IO_CHECK='Both';
      NO_ASSERT_CHECK='TRUE';
      NO_DIR_CHECK='TRUE';
      ALLOW_CONNECT='TRUE';
    'VSS'<736>:
      PIN_NUMBER='(0,0,0,0,0,0,0,0,0,0,0,0,0,0,0,0,0,0,0,0,0,0,0,0,0,AR60,0,0,0,0)';
      PINUSE='GROUND';
      NO_LOAD_CHECK='Both';
      NO_IO_CHECK='Both';
      NO_ASSERT_CHECK='TRUE';
      NO_DIR_CHECK='TRUE';
      ALLOW_CONNECT='TRUE';
    'VSS'<735>:
      PIN_NUMBER='(0,0,0,0,0,0,0,0,0,0,0,0,0,0,0,0,0,0,0,0,0,0,0,0,0,AR72,0,0,0,0)';
      PINUSE='GROUND';
      NO_LOAD_CHECK='Both';
      NO_IO_CHECK='Both';
      NO_ASSERT_CHECK='TRUE';
      NO_DIR_CHECK='TRUE';
      ALLOW_CONNECT='TRUE';
    'VSS'<734>:
      PIN_NUMBER='(0,0,0,0,0,0,0,0,0,0,0,0,0,0,0,0,0,0,0,0,0,0,0,0,0,AR78,0,0,0,0)';
      PINUSE='GROUND';
      NO_LOAD_CHECK='Both';
      NO_IO_CHECK='Both';
      NO_ASSERT_CHECK='TRUE';
      NO_DIR_CHECK='TRUE';
      ALLOW_CONNECT='TRUE';
    'VSS'<733>:
      PIN_NUMBER='(0,0,0,0,0,0,0,0,0,0,0,0,0,0,0,0,0,0,0,0,0,0,0,0,0,AC48,0,0,0,0)';
      PINUSE='GROUND';
      NO_LOAD_CHECK='Both';
      NO_IO_CHECK='Both';
      NO_ASSERT_CHECK='TRUE';
      NO_DIR_CHECK='TRUE';
      ALLOW_CONNECT='TRUE';
    'VSS'<732>:
      PIN_NUMBER='(0,0,0,0,0,0,0,0,0,0,0,0,0,0,0,0,0,0,0,0,0,0,0,0,0,P63,0,0,0,0)';
      PINUSE='GROUND';
      NO_LOAD_CHECK='Both';
      NO_IO_CHECK='Both';
      NO_ASSERT_CHECK='TRUE';
      NO_DIR_CHECK='TRUE';
      ALLOW_CONNECT='TRUE';
    'VSS'<731>:
      PIN_NUMBER='(0,0,0,0,0,0,0,0,0,0,0,0,0,0,0,0,0,0,0,0,0,0,0,0,0,AT15,0,0,0,0)';
      PINUSE='GROUND';
      NO_LOAD_CHECK='Both';
      NO_IO_CHECK='Both';
      NO_ASSERT_CHECK='TRUE';
      NO_DIR_CHECK='TRUE';
      ALLOW_CONNECT='TRUE';
    'VSS'<730>:
      PIN_NUMBER='(0,0,0,0,0,0,0,0,0,0,0,0,0,0,0,0,0,0,0,0,0,0,0,0,0,AT17,0,0,0,0)';
      PINUSE='GROUND';
      NO_LOAD_CHECK='Both';
      NO_IO_CHECK='Both';
      NO_ASSERT_CHECK='TRUE';
      NO_DIR_CHECK='TRUE';
      ALLOW_CONNECT='TRUE';
    'VSS'<729>:
      PIN_NUMBER='(0,0,0,0,0,0,0,0,0,0,0,0,0,0,0,0,0,0,0,0,0,0,0,0,0,AT21,0,0,0,0)';
      PINUSE='GROUND';
      NO_LOAD_CHECK='Both';
      NO_IO_CHECK='Both';
      NO_ASSERT_CHECK='TRUE';
      NO_DIR_CHECK='TRUE';
      ALLOW_CONNECT='TRUE';
    'VSS'<728>:
      PIN_NUMBER='(0,0,0,0,0,0,0,0,0,0,0,0,0,0,0,0,0,0,0,0,0,0,0,0,0,AT27,0,0,0,0)';
      PINUSE='GROUND';
      NO_LOAD_CHECK='Both';
      NO_IO_CHECK='Both';
      NO_ASSERT_CHECK='TRUE';
      NO_DIR_CHECK='TRUE';
      ALLOW_CONNECT='TRUE';
    'VSS'<727>:
      PIN_NUMBER='(0,0,0,0,0,0,0,0,0,0,0,0,0,0,0,0,0,0,0,0,0,0,0,0,0,AT61,0,0,0,0)';
      PINUSE='GROUND';
      NO_LOAD_CHECK='Both';
      NO_IO_CHECK='Both';
      NO_ASSERT_CHECK='TRUE';
      NO_DIR_CHECK='TRUE';
      ALLOW_CONNECT='TRUE';
    'VSS'<726>:
      PIN_NUMBER='(0,0,0,0,0,0,0,0,0,0,0,0,0,0,0,0,0,0,0,0,0,0,0,0,0,AT63,0,0,0,0)';
      PINUSE='GROUND';
      NO_LOAD_CHECK='Both';
      NO_IO_CHECK='Both';
      NO_ASSERT_CHECK='TRUE';
      NO_DIR_CHECK='TRUE';
      ALLOW_CONNECT='TRUE';
    'VSS'<725>:
      PIN_NUMBER='(0,0,0,0,0,0,0,0,0,0,0,0,0,0,0,0,0,0,0,0,0,0,0,0,0,AT69,0,0,0,0)';
      PINUSE='GROUND';
      NO_LOAD_CHECK='Both';
      NO_IO_CHECK='Both';
      NO_ASSERT_CHECK='TRUE';
      NO_DIR_CHECK='TRUE';
      ALLOW_CONNECT='TRUE';
    'VSS'<724>:
      PIN_NUMBER='(0,0,0,0,0,0,0,0,0,0,0,0,0,0,0,0,0,0,0,0,0,0,0,0,0,AT73,0,0,0,0)';
      PINUSE='GROUND';
      NO_LOAD_CHECK='Both';
      NO_IO_CHECK='Both';
      NO_ASSERT_CHECK='TRUE';
      NO_DIR_CHECK='TRUE';
      ALLOW_CONNECT='TRUE';
    'VSS'<723>:
      PIN_NUMBER='(0,0,0,0,0,0,0,0,0,0,0,0,0,0,0,0,0,0,0,0,0,0,0,0,0,AT77,0,0,0,0)';
      PINUSE='GROUND';
      NO_LOAD_CHECK='Both';
      NO_IO_CHECK='Both';
      NO_ASSERT_CHECK='TRUE';
      NO_DIR_CHECK='TRUE';
      ALLOW_CONNECT='TRUE';
    'VSS'<722>:
      PIN_NUMBER='(0,0,0,0,0,0,0,0,0,0,0,0,0,0,0,0,0,0,0,0,0,0,0,0,0,AT83,0,0,0,0)';
      PINUSE='GROUND';
      NO_LOAD_CHECK='Both';
      NO_IO_CHECK='Both';
      NO_ASSERT_CHECK='TRUE';
      NO_DIR_CHECK='TRUE';
      ALLOW_CONNECT='TRUE';
    'VSS'<721>:
      PIN_NUMBER='(0,0,0,0,0,0,0,0,0,0,0,0,0,0,0,0,0,0,0,0,0,0,0,0,0,AT85,0,0,0,0)';
      PINUSE='GROUND';
      NO_LOAD_CHECK='Both';
      NO_IO_CHECK='Both';
      NO_ASSERT_CHECK='TRUE';
      NO_DIR_CHECK='TRUE';
      ALLOW_CONNECT='TRUE';
    'VSS'<720>:
      PIN_NUMBER='(0,0,0,0,0,0,0,0,0,0,0,0,0,0,0,0,0,0,0,0,0,0,0,0,0,AU2,0,0,0,0)';
      PINUSE='GROUND';
      NO_LOAD_CHECK='Both';
      NO_IO_CHECK='Both';
      NO_ASSERT_CHECK='TRUE';
      NO_DIR_CHECK='TRUE';
      ALLOW_CONNECT='TRUE';
    'VSS'<719>:
      PIN_NUMBER='(0,0,0,0,0,0,0,0,0,0,0,0,0,0,0,0,0,0,0,0,0,0,0,0,0,AU6,0,0,0,0)';
      PINUSE='GROUND';
      NO_LOAD_CHECK='Both';
      NO_IO_CHECK='Both';
      NO_ASSERT_CHECK='TRUE';
      NO_DIR_CHECK='TRUE';
      ALLOW_CONNECT='TRUE';
    'VSS'<718>:
      PIN_NUMBER='(0,0,0,0,0,0,0,0,0,0,0,0,0,0,0,0,0,0,0,0,0,0,0,0,0,AU26,0,0,0,0)';
      PINUSE='GROUND';
      NO_LOAD_CHECK='Both';
      NO_IO_CHECK='Both';
      NO_ASSERT_CHECK='TRUE';
      NO_DIR_CHECK='TRUE';
      ALLOW_CONNECT='TRUE';
    'VSS'<717>:
      PIN_NUMBER='(0,0,0,0,0,0,0,0,0,0,0,0,0,0,0,0,0,0,0,0,0,0,0,0,0,AU28,0,0,0,0)';
      PINUSE='GROUND';
      NO_LOAD_CHECK='Both';
      NO_IO_CHECK='Both';
      NO_ASSERT_CHECK='TRUE';
      NO_DIR_CHECK='TRUE';
      ALLOW_CONNECT='TRUE';
    'VSS'<716>:
      PIN_NUMBER='(0,0,0,0,0,0,0,0,0,0,0,0,0,0,0,0,0,0,0,0,0,0,0,0,0,AU62,0,0,0,0)';
      PINUSE='GROUND';
      NO_LOAD_CHECK='Both';
      NO_IO_CHECK='Both';
      NO_ASSERT_CHECK='TRUE';
      NO_DIR_CHECK='TRUE';
      ALLOW_CONNECT='TRUE';
    'VSS'<715>:
      PIN_NUMBER='(0,0,0,0,0,0,0,0,0,0,0,0,0,0,0,0,0,0,0,0,0,0,0,0,0,AU64,0,0,0,0)';
      PINUSE='GROUND';
      NO_LOAD_CHECK='Both';
      NO_IO_CHECK='Both';
      NO_ASSERT_CHECK='TRUE';
      NO_DIR_CHECK='TRUE';
      ALLOW_CONNECT='TRUE';
    'VSS'<714>:
      PIN_NUMBER='(0,0,0,0,0,0,0,0,0,0,0,0,0,0,0,0,0,0,0,0,0,0,0,0,0,AU68,0,0,0,0)';
      PINUSE='GROUND';
      NO_LOAD_CHECK='Both';
      NO_IO_CHECK='Both';
      NO_ASSERT_CHECK='TRUE';
      NO_DIR_CHECK='TRUE';
      ALLOW_CONNECT='TRUE';
    'VSS'<713>:
      PIN_NUMBER='(0,0,0,0,0,0,0,0,0,0,0,0,0,0,0,0,0,0,0,0,0,0,0,0,0,AU74,0,0,0,0)';
      PINUSE='GROUND';
      NO_LOAD_CHECK='Both';
      NO_IO_CHECK='Both';
      NO_ASSERT_CHECK='TRUE';
      NO_DIR_CHECK='TRUE';
      ALLOW_CONNECT='TRUE';
    'VSS'<712>:
      PIN_NUMBER='(0,0,0,0,0,0,0,0,0,0,0,0,0,0,0,0,0,0,0,0,0,0,0,0,0,AU76,0,0,0,0)';
      PINUSE='GROUND';
      NO_LOAD_CHECK='Both';
      NO_IO_CHECK='Both';
      NO_ASSERT_CHECK='TRUE';
      NO_DIR_CHECK='TRUE';
      ALLOW_CONNECT='TRUE';
    'VSS'<711>:
      PIN_NUMBER='(0,0,0,0,0,0,0,0,0,0,0,0,0,0,0,0,0,0,0,0,0,0,0,0,0,AU78,0,0,0,0)';
      PINUSE='GROUND';
      NO_LOAD_CHECK='Both';
      NO_IO_CHECK='Both';
      NO_ASSERT_CHECK='TRUE';
      NO_DIR_CHECK='TRUE';
      ALLOW_CONNECT='TRUE';
    'VSS'<710>:
      PIN_NUMBER='(0,0,0,0,0,0,0,0,0,0,0,0,0,0,0,0,0,0,0,0,0,0,0,0,0,AU80,0,0,0,0)';
      PINUSE='GROUND';
      NO_LOAD_CHECK='Both';
      NO_IO_CHECK='Both';
      NO_ASSERT_CHECK='TRUE';
      NO_DIR_CHECK='TRUE';
      ALLOW_CONNECT='TRUE';
    'VSS'<709>:
      PIN_NUMBER='(0,0,0,0,0,0,0,0,0,0,0,0,0,0,0,0,0,0,0,0,0,0,0,0,0,AU84,0,0,0,0)';
      PINUSE='GROUND';
      NO_LOAD_CHECK='Both';
      NO_IO_CHECK='Both';
      NO_ASSERT_CHECK='TRUE';
      NO_DIR_CHECK='TRUE';
      ALLOW_CONNECT='TRUE';
    'VSS'<708>:
      PIN_NUMBER='(0,0,0,0,0,0,0,0,0,0,0,0,0,0,0,0,0,0,0,0,0,0,0,0,0,AU86,0,0,0,0)';
      PINUSE='GROUND';
      NO_LOAD_CHECK='Both';
      NO_IO_CHECK='Both';
      NO_ASSERT_CHECK='TRUE';
      NO_DIR_CHECK='TRUE';
      ALLOW_CONNECT='TRUE';
    'VSS'<707>:
      PIN_NUMBER='(0,0,0,0,0,0,0,0,0,0,0,0,0,0,0,0,0,0,0,0,0,0,0,0,0,AV1,0,0,0,0)';
      PINUSE='GROUND';
      NO_LOAD_CHECK='Both';
      NO_IO_CHECK='Both';
      NO_ASSERT_CHECK='TRUE';
      NO_DIR_CHECK='TRUE';
      ALLOW_CONNECT='TRUE';
    'VSS'<706>:
      PIN_NUMBER='(0,0,0,0,0,0,0,0,0,0,0,0,0,0,0,0,0,0,0,0,0,0,0,0,0,AV3,0,0,0,0)';
      PINUSE='GROUND';
      NO_LOAD_CHECK='Both';
      NO_IO_CHECK='Both';
      NO_ASSERT_CHECK='TRUE';
      NO_DIR_CHECK='TRUE';
      ALLOW_CONNECT='TRUE';
    'VSS'<705>:
      PIN_NUMBER='(0,0,0,0,0,0,0,0,0,0,0,0,0,0,0,0,0,0,0,0,0,0,0,0,0,AV7,0,0,0,0)';
      PINUSE='GROUND';
      NO_LOAD_CHECK='Both';
      NO_IO_CHECK='Both';
      NO_ASSERT_CHECK='TRUE';
      NO_DIR_CHECK='TRUE';
      ALLOW_CONNECT='TRUE';
    'VSS'<704>:
      PIN_NUMBER='(0,0,0,0,0,0,0,0,0,0,0,0,0,0,0,0,0,0,0,0,0,0,0,0,0,AV11,0,0,0,0)';
      PINUSE='GROUND';
      NO_LOAD_CHECK='Both';
      NO_IO_CHECK='Both';
      NO_ASSERT_CHECK='TRUE';
      NO_DIR_CHECK='TRUE';
      ALLOW_CONNECT='TRUE';
    'VSS'<703>:
      PIN_NUMBER='(0,0,0,0,0,0,0,0,0,0,0,0,0,0,0,0,0,0,0,0,0,0,0,0,0,AV13,0,0,0,0)';
      PINUSE='GROUND';
      NO_LOAD_CHECK='Both';
      NO_IO_CHECK='Both';
      NO_ASSERT_CHECK='TRUE';
      NO_DIR_CHECK='TRUE';
      ALLOW_CONNECT='TRUE';
    'VSS'<702>:
      PIN_NUMBER='(0,0,0,0,0,0,0,0,0,0,0,0,0,0,0,0,0,0,0,0,0,0,0,0,0,AV19,0,0,0,0)';
      PINUSE='GROUND';
      NO_LOAD_CHECK='Both';
      NO_IO_CHECK='Both';
      NO_ASSERT_CHECK='TRUE';
      NO_DIR_CHECK='TRUE';
      ALLOW_CONNECT='TRUE';
    'VSS'<701>:
      PIN_NUMBER='(0,0,0,0,0,0,0,0,0,0,0,0,0,0,0,0,0,0,0,0,0,0,0,0,0,AV23,0,0,0,0)';
      PINUSE='GROUND';
      NO_LOAD_CHECK='Both';
      NO_IO_CHECK='Both';
      NO_ASSERT_CHECK='TRUE';
      NO_DIR_CHECK='TRUE';
      ALLOW_CONNECT='TRUE';
    'VSS'<700>:
      PIN_NUMBER='(0,0,0,0,0,0,0,0,0,0,0,0,0,0,0,0,0,0,0,0,0,0,0,0,0,AV25,0,0,0,0)';
      PINUSE='GROUND';
      NO_LOAD_CHECK='Both';
      NO_IO_CHECK='Both';
      NO_ASSERT_CHECK='TRUE';
      NO_DIR_CHECK='TRUE';
      ALLOW_CONNECT='TRUE';
    'VSS'<699>:
      PIN_NUMBER='(0,0,0,0,0,0,0,0,0,0,0,0,0,0,0,0,0,0,0,0,0,0,0,0,0,AV63,0,0,0,0)';
      PINUSE='GROUND';
      NO_LOAD_CHECK='Both';
      NO_IO_CHECK='Both';
      NO_ASSERT_CHECK='TRUE';
      NO_DIR_CHECK='TRUE';
      ALLOW_CONNECT='TRUE';
    'VSS'<698>:
      PIN_NUMBER='(0,0,0,0,0,0,0,0,0,0,0,0,0,0,0,0,0,0,0,0,0,0,0,0,0,AV65,0,0,0,0)';
      PINUSE='GROUND';
      NO_LOAD_CHECK='Both';
      NO_IO_CHECK='Both';
      NO_ASSERT_CHECK='TRUE';
      NO_DIR_CHECK='TRUE';
      ALLOW_CONNECT='TRUE';
    'VSS'<697>:
      PIN_NUMBER='(0,0,0,0,0,0,0,0,0,0,0,0,0,0,0,0,0,0,0,0,0,0,0,0,0,AV67,0,0,0,0)';
      PINUSE='GROUND';
      NO_LOAD_CHECK='Both';
      NO_IO_CHECK='Both';
      NO_ASSERT_CHECK='TRUE';
      NO_DIR_CHECK='TRUE';
      ALLOW_CONNECT='TRUE';
    'VSS'<696>:
      PIN_NUMBER='(0,0,0,0,0,0,0,0,0,0,0,0,0,0,0,0,0,0,0,0,0,0,0,0,0,AV75,0,0,0,0)';
      PINUSE='GROUND';
      NO_LOAD_CHECK='Both';
      NO_IO_CHECK='Both';
      NO_ASSERT_CHECK='TRUE';
      NO_DIR_CHECK='TRUE';
      ALLOW_CONNECT='TRUE';
    'VSS'<695>:
      PIN_NUMBER='(0,0,0,0,0,0,0,0,0,0,0,0,0,0,0,0,0,0,0,0,0,0,0,0,0,AV83,0,0,0,0)';
      PINUSE='GROUND';
      NO_LOAD_CHECK='Both';
      NO_IO_CHECK='Both';
      NO_ASSERT_CHECK='TRUE';
      NO_DIR_CHECK='TRUE';
      ALLOW_CONNECT='TRUE';
    'VSS'<694>:
      PIN_NUMBER='(0,0,0,0,0,0,0,0,0,0,0,0,0,0,0,0,0,0,0,0,0,0,0,0,0,AW2,0,0,0,0)';
      PINUSE='GROUND';
      NO_LOAD_CHECK='Both';
      NO_IO_CHECK='Both';
      NO_ASSERT_CHECK='TRUE';
      NO_DIR_CHECK='TRUE';
      ALLOW_CONNECT='TRUE';
    'VSS'<693>:
      PIN_NUMBER='(0,0,0,0,0,0,0,0,0,0,0,0,0,0,0,0,0,0,0,0,0,0,0,0,0,AW10,0,0,0,0)';
      PINUSE='GROUND';
      NO_LOAD_CHECK='Both';
      NO_IO_CHECK='Both';
      NO_ASSERT_CHECK='TRUE';
      NO_DIR_CHECK='TRUE';
      ALLOW_CONNECT='TRUE';
    'VSS'<692>:
      PIN_NUMBER='(0,0,0,0,0,0,0,0,0,0,0,0,0,0,0,0,0,0,0,0,0,0,0,0,0,AW62,0,0,0,0)';
      PINUSE='GROUND';
      NO_LOAD_CHECK='Both';
      NO_IO_CHECK='Both';
      NO_ASSERT_CHECK='TRUE';
      NO_DIR_CHECK='TRUE';
      ALLOW_CONNECT='TRUE';
    'VSS'<691>:
      PIN_NUMBER='(0,0,0,0,0,0,0,0,0,0,0,0,0,0,0,0,0,0,0,0,0,0,0,0,0,AW66,0,0,0,0)';
      PINUSE='GROUND';
      NO_LOAD_CHECK='Both';
      NO_IO_CHECK='Both';
      NO_ASSERT_CHECK='TRUE';
      NO_DIR_CHECK='TRUE';
      ALLOW_CONNECT='TRUE';
    'VSS'<690>:
      PIN_NUMBER='(0,0,0,0,0,0,0,0,0,0,0,0,0,0,0,0,0,0,0,0,0,0,0,0,0,AW68,0,0,0,0)';
      PINUSE='GROUND';
      NO_LOAD_CHECK='Both';
      NO_IO_CHECK='Both';
      NO_ASSERT_CHECK='TRUE';
      NO_DIR_CHECK='TRUE';
      ALLOW_CONNECT='TRUE';
    'VSS'<689>:
      PIN_NUMBER='(0,0,0,0,0,0,0,0,0,0,0,0,0,0,0,0,0,0,0,0,0,0,0,0,0,AW70,0,0,0,0)';
      PINUSE='GROUND';
      NO_LOAD_CHECK='Both';
      NO_IO_CHECK='Both';
      NO_ASSERT_CHECK='TRUE';
      NO_DIR_CHECK='TRUE';
      ALLOW_CONNECT='TRUE';
    'VSS'<688>:
      PIN_NUMBER='(0,0,0,0,0,0,0,0,0,0,0,0,0,0,0,0,0,0,0,0,0,0,0,0,0,AW72,0,0,0,0)';
      PINUSE='GROUND';
      NO_LOAD_CHECK='Both';
      NO_IO_CHECK='Both';
      NO_ASSERT_CHECK='TRUE';
      NO_DIR_CHECK='TRUE';
      ALLOW_CONNECT='TRUE';
    'VSS'<687>:
      PIN_NUMBER='(0,0,0,0,0,0,0,0,0,0,0,0,0,0,0,0,0,0,0,0,0,0,0,0,0,AW74,0,0,0,0)';
      PINUSE='GROUND';
      NO_LOAD_CHECK='Both';
      NO_IO_CHECK='Both';
      NO_ASSERT_CHECK='TRUE';
      NO_DIR_CHECK='TRUE';
      ALLOW_CONNECT='TRUE';
    'VSS'<686>:
      PIN_NUMBER='(0,0,0,0,0,0,0,0,0,0,0,0,0,0,0,0,0,0,0,0,0,0,0,0,0,AW78,0,0,0,0)';
      PINUSE='GROUND';
      NO_LOAD_CHECK='Both';
      NO_IO_CHECK='Both';
      NO_ASSERT_CHECK='TRUE';
      NO_DIR_CHECK='TRUE';
      ALLOW_CONNECT='TRUE';
    'VSS'<685>:
      PIN_NUMBER='(0,0,0,0,0,0,0,0,0,0,0,0,0,0,0,0,0,0,0,0,0,0,0,0,0,AW82,0,0,0,0)';
      PINUSE='GROUND';
      NO_LOAD_CHECK='Both';
      NO_IO_CHECK='Both';
      NO_ASSERT_CHECK='TRUE';
      NO_DIR_CHECK='TRUE';
      ALLOW_CONNECT='TRUE';
    'VSS'<684>:
      PIN_NUMBER='(0,0,0,0,0,0,0,0,0,0,0,0,0,0,0,0,0,0,0,0,0,0,0,0,0,AW84,0,0,0,0)';
      PINUSE='GROUND';
      NO_LOAD_CHECK='Both';
      NO_IO_CHECK='Both';
      NO_ASSERT_CHECK='TRUE';
      NO_DIR_CHECK='TRUE';
      ALLOW_CONNECT='TRUE';
    'VSS'<683>:
      PIN_NUMBER='(0,0,0,0,0,0,0,0,0,0,0,0,0,0,0,0,0,0,0,0,0,0,0,0,0,AY5,0,0,0,0)';
      PINUSE='GROUND';
      NO_LOAD_CHECK='Both';
      NO_IO_CHECK='Both';
      NO_ASSERT_CHECK='TRUE';
      NO_DIR_CHECK='TRUE';
      ALLOW_CONNECT='TRUE';
    'VSS'<682>:
      PIN_NUMBER='(0,0,0,0,0,0,0,0,0,0,0,0,0,0,0,0,0,0,0,0,0,0,0,0,0,AY15,0,0,0,0)';
      PINUSE='GROUND';
      NO_LOAD_CHECK='Both';
      NO_IO_CHECK='Both';
      NO_ASSERT_CHECK='TRUE';
      NO_DIR_CHECK='TRUE';
      ALLOW_CONNECT='TRUE';
    'VSS'<681>:
      PIN_NUMBER='(0,0,0,0,0,0,0,0,0,0,0,0,0,0,0,0,0,0,0,0,0,0,0,0,0,AY17,0,0,0,0)';
      PINUSE='GROUND';
      NO_LOAD_CHECK='Both';
      NO_IO_CHECK='Both';
      NO_ASSERT_CHECK='TRUE';
      NO_DIR_CHECK='TRUE';
      ALLOW_CONNECT='TRUE';
    'VSS'<680>:
      PIN_NUMBER='(0,0,0,0,0,0,0,0,0,0,0,0,0,0,0,0,0,0,0,0,0,0,0,0,0,AY21,0,0,0,0)';
      PINUSE='GROUND';
      NO_LOAD_CHECK='Both';
      NO_IO_CHECK='Both';
      NO_ASSERT_CHECK='TRUE';
      NO_DIR_CHECK='TRUE';
      ALLOW_CONNECT='TRUE';
    'VSS'<679>:
      PIN_NUMBER='(0,0,0,0,0,0,0,0,0,0,0,0,0,0,0,0,0,0,0,0,0,0,0,0,0,AY23,0,0,0,0)';
      PINUSE='GROUND';
      NO_LOAD_CHECK='Both';
      NO_IO_CHECK='Both';
      NO_ASSERT_CHECK='TRUE';
      NO_DIR_CHECK='TRUE';
      ALLOW_CONNECT='TRUE';
    'VSS'<678>:
      PIN_NUMBER='(0,0,0,0,0,0,0,0,0,0,0,0,0,0,0,0,0,0,0,0,0,0,0,0,0,AY25,0,0,0,0)';
      PINUSE='GROUND';
      NO_LOAD_CHECK='Both';
      NO_IO_CHECK='Both';
      NO_ASSERT_CHECK='TRUE';
      NO_DIR_CHECK='TRUE';
      ALLOW_CONNECT='TRUE';
    'VSS'<677>:
      PIN_NUMBER='(0,0,0,0,0,0,0,0,0,0,0,0,0,0,0,0,0,0,0,0,0,0,0,0,0,AY63,0,0,0,0)';
      PINUSE='GROUND';
      NO_LOAD_CHECK='Both';
      NO_IO_CHECK='Both';
      NO_ASSERT_CHECK='TRUE';
      NO_DIR_CHECK='TRUE';
      ALLOW_CONNECT='TRUE';
    'VSS'<676>:
      PIN_NUMBER='(0,0,0,0,0,0,0,0,0,0,0,0,0,0,0,0,0,0,0,0,0,0,0,0,0,AY79,0,0,0,0)';
      PINUSE='GROUND';
      NO_LOAD_CHECK='Both';
      NO_IO_CHECK='Both';
      NO_ASSERT_CHECK='TRUE';
      NO_DIR_CHECK='TRUE';
      ALLOW_CONNECT='TRUE';
    'VSS'<675>:
      PIN_NUMBER='(0,0,0,0,0,0,0,0,0,0,0,0,0,0,0,0,0,0,0,0,0,0,0,0,0,AY81,0,0,0,0)';
      PINUSE='GROUND';
      NO_LOAD_CHECK='Both';
      NO_IO_CHECK='Both';
      NO_ASSERT_CHECK='TRUE';
      NO_DIR_CHECK='TRUE';
      ALLOW_CONNECT='TRUE';
    'VSS'<674>:
      PIN_NUMBER='(0,0,0,0,0,0,0,0,0,0,0,0,0,0,0,0,0,0,0,0,0,0,0,0,0,BA2,0,0,0,0)';
      PINUSE='GROUND';
      NO_LOAD_CHECK='Both';
      NO_IO_CHECK='Both';
      NO_ASSERT_CHECK='TRUE';
      NO_DIR_CHECK='TRUE';
      ALLOW_CONNECT='TRUE';
    'VSS'<673>:
      PIN_NUMBER='(0,0,0,0,0,0,0,0,0,0,0,0,0,0,0,0,0,0,0,0,0,0,0,0,0,BA6,0,0,0,0)';
      PINUSE='GROUND';
      NO_LOAD_CHECK='Both';
      NO_IO_CHECK='Both';
      NO_ASSERT_CHECK='TRUE';
      NO_DIR_CHECK='TRUE';
      ALLOW_CONNECT='TRUE';
    'VSS'<672>:
      PIN_NUMBER='(0,0,0,0,0,0,0,0,0,0,0,0,0,0,0,0,0,0,0,0,0,0,0,0,0,BA12,0,0,0,0)';
      PINUSE='GROUND';
      NO_LOAD_CHECK='Both';
      NO_IO_CHECK='Both';
      NO_ASSERT_CHECK='TRUE';
      NO_DIR_CHECK='TRUE';
      ALLOW_CONNECT='TRUE';
    'VSS'<671>:
      PIN_NUMBER='(0,0,0,0,0,0,0,0,0,0,0,0,0,0,0,0,0,0,0,0,0,0,0,0,0,BA62,0,0,0,0)';
      PINUSE='GROUND';
      NO_LOAD_CHECK='Both';
      NO_IO_CHECK='Both';
      NO_ASSERT_CHECK='TRUE';
      NO_DIR_CHECK='TRUE';
      ALLOW_CONNECT='TRUE';
    'VSS'<670>:
      PIN_NUMBER='(0,0,0,0,0,0,0,0,0,0,0,0,0,0,0,0,0,0,0,0,0,0,0,0,0,BA68,0,0,0,0)';
      PINUSE='GROUND';
      NO_LOAD_CHECK='Both';
      NO_IO_CHECK='Both';
      NO_ASSERT_CHECK='TRUE';
      NO_DIR_CHECK='TRUE';
      ALLOW_CONNECT='TRUE';
    'VSS'<669>:
      PIN_NUMBER='(0,0,0,0,0,0,0,0,0,0,0,0,0,0,0,0,0,0,0,0,0,0,0,0,0,BA74,0,0,0,0)';
      PINUSE='GROUND';
      NO_LOAD_CHECK='Both';
      NO_IO_CHECK='Both';
      NO_ASSERT_CHECK='TRUE';
      NO_DIR_CHECK='TRUE';
      ALLOW_CONNECT='TRUE';
    'VSS'<668>:
      PIN_NUMBER='(0,0,0,0,0,0,0,0,0,0,0,0,0,0,0,0,0,0,0,0,0,0,0,0,0,BA80,0,0,0,0)';
      PINUSE='GROUND';
      NO_LOAD_CHECK='Both';
      NO_IO_CHECK='Both';
      NO_ASSERT_CHECK='TRUE';
      NO_DIR_CHECK='TRUE';
      ALLOW_CONNECT='TRUE';
    'VSS'<667>:
      PIN_NUMBER='(0,0,0,0,0,0,0,0,0,0,0,0,0,0,0,0,0,0,0,0,0,0,0,0,0,BA84,0,0,0,0)';
      PINUSE='GROUND';
      NO_LOAD_CHECK='Both';
      NO_IO_CHECK='Both';
      NO_ASSERT_CHECK='TRUE';
      NO_DIR_CHECK='TRUE';
      ALLOW_CONNECT='TRUE';
    'VSS'<666>:
      PIN_NUMBER='(0,0,0,0,0,0,0,0,0,0,0,0,0,0,0,0,0,0,0,0,0,0,0,0,0,BB19,0,0,0,0)';
      PINUSE='GROUND';
      NO_LOAD_CHECK='Both';
      NO_IO_CHECK='Both';
      NO_ASSERT_CHECK='TRUE';
      NO_DIR_CHECK='TRUE';
      ALLOW_CONNECT='TRUE';
    'VSS'<665>:
      PIN_NUMBER='(0,0,0,0,0,0,0,0,0,0,0,0,0,0,0,0,0,0,0,0,0,0,0,0,0,BB23,0,0,0,0)';
      PINUSE='GROUND';
      NO_LOAD_CHECK='Both';
      NO_IO_CHECK='Both';
      NO_ASSERT_CHECK='TRUE';
      NO_DIR_CHECK='TRUE';
      ALLOW_CONNECT='TRUE';
    'VSS'<664>:
      PIN_NUMBER='(0,0,0,0,0,0,0,0,0,0,0,0,0,0,0,0,0,0,0,0,0,0,0,0,0,BB63,0,0,0,0)';
      PINUSE='GROUND';
      NO_LOAD_CHECK='Both';
      NO_IO_CHECK='Both';
      NO_ASSERT_CHECK='TRUE';
      NO_DIR_CHECK='TRUE';
      ALLOW_CONNECT='TRUE';
    'VSS'<663>:
      PIN_NUMBER='(0,0,0,0,0,0,0,0,0,0,0,0,0,0,0,0,0,0,0,0,0,0,0,0,0,BB69,0,0,0,0)';
      PINUSE='GROUND';
      NO_LOAD_CHECK='Both';
      NO_IO_CHECK='Both';
      NO_ASSERT_CHECK='TRUE';
      NO_DIR_CHECK='TRUE';
      ALLOW_CONNECT='TRUE';
    'VSS'<662>:
      PIN_NUMBER='(0,0,0,0,0,0,0,0,0,0,0,0,0,0,0,0,0,0,0,0,0,0,0,0,0,BB73,0,0,0,0)';
      PINUSE='GROUND';
      NO_LOAD_CHECK='Both';
      NO_IO_CHECK='Both';
      NO_ASSERT_CHECK='TRUE';
      NO_DIR_CHECK='TRUE';
      ALLOW_CONNECT='TRUE';
    'VSS'<661>:
      PIN_NUMBER='(0,0,0,0,0,0,0,0,0,0,0,0,0,0,0,0,0,0,0,0,0,0,0,0,0,BB75,0,0,0,0)';
      PINUSE='GROUND';
      NO_LOAD_CHECK='Both';
      NO_IO_CHECK='Both';
      NO_ASSERT_CHECK='TRUE';
      NO_DIR_CHECK='TRUE';
      ALLOW_CONNECT='TRUE';
    'VSS'<660>:
      PIN_NUMBER='(0,0,0,0,0,0,0,0,0,0,0,0,0,0,0,0,0,0,0,0,0,0,0,0,0,BB77,0,0,0,0)';
      PINUSE='GROUND';
      NO_LOAD_CHECK='Both';
      NO_IO_CHECK='Both';
      NO_ASSERT_CHECK='TRUE';
      NO_DIR_CHECK='TRUE';
      ALLOW_CONNECT='TRUE';
    'VSS'<659>:
      PIN_NUMBER='(0,0,0,0,0,0,0,0,0,0,0,0,0,0,0,0,0,0,0,0,0,0,0,0,0,BB79,0,0,0,0)';
      PINUSE='GROUND';
      NO_LOAD_CHECK='Both';
      NO_IO_CHECK='Both';
      NO_ASSERT_CHECK='TRUE';
      NO_DIR_CHECK='TRUE';
      ALLOW_CONNECT='TRUE';
    'VSS'<658>:
      PIN_NUMBER='(0,0,0,0,0,0,0,0,0,0,0,0,0,0,0,0,0,0,0,0,0,0,0,0,0,BB81,0,0,0,0)';
      PINUSE='GROUND';
      NO_LOAD_CHECK='Both';
      NO_IO_CHECK='Both';
      NO_ASSERT_CHECK='TRUE';
      NO_DIR_CHECK='TRUE';
      ALLOW_CONNECT='TRUE';
    'VSS'<657>:
      PIN_NUMBER='(0,0,0,0,0,0,0,0,0,0,0,0,0,0,0,0,0,0,0,0,0,0,0,0,0,BB83,0,0,0,0)';
      PINUSE='GROUND';
      NO_LOAD_CHECK='Both';
      NO_IO_CHECK='Both';
      NO_ASSERT_CHECK='TRUE';
      NO_DIR_CHECK='TRUE';
      ALLOW_CONNECT='TRUE';
    'VSS'<656>:
      PIN_NUMBER='(0,0,0,0,0,0,0,0,0,0,0,0,0,0,0,0,0,0,0,0,0,0,0,0,0,BC4,0,0,0,0)';
      PINUSE='GROUND';
      NO_LOAD_CHECK='Both';
      NO_IO_CHECK='Both';
      NO_ASSERT_CHECK='TRUE';
      NO_DIR_CHECK='TRUE';
      ALLOW_CONNECT='TRUE';
    'VSS'<655>:
      PIN_NUMBER='(0,0,0,0,0,0,0,0,0,0,0,0,0,0,0,0,0,0,0,0,0,0,0,0,0,BC8,0,0,0,0)';
      PINUSE='GROUND';
      NO_LOAD_CHECK='Both';
      NO_IO_CHECK='Both';
      NO_ASSERT_CHECK='TRUE';
      NO_DIR_CHECK='TRUE';
      ALLOW_CONNECT='TRUE';
    'VSS'<654>:
      PIN_NUMBER='(0,0,0,0,0,0,0,0,0,0,0,0,0,0,0,0,0,0,0,0,0,0,0,0,0,BC12,0,0,0,0)';
      PINUSE='GROUND';
      NO_LOAD_CHECK='Both';
      NO_IO_CHECK='Both';
      NO_ASSERT_CHECK='TRUE';
      NO_DIR_CHECK='TRUE';
      ALLOW_CONNECT='TRUE';
    'VSS'<653>:
      PIN_NUMBER='(0,0,0,0,0,0,0,0,0,0,0,0,0,0,0,0,0,0,0,0,0,0,0,0,0,BC16,0,0,0,0)';
      PINUSE='GROUND';
      NO_LOAD_CHECK='Both';
      NO_IO_CHECK='Both';
      NO_ASSERT_CHECK='TRUE';
      NO_DIR_CHECK='TRUE';
      ALLOW_CONNECT='TRUE';
    'VSS'<652>:
      PIN_NUMBER='(0,0,0,0,0,0,0,0,0,0,0,0,0,0,0,0,0,0,0,0,0,0,0,0,0,BC70,0,0,0,0)';
      PINUSE='GROUND';
      NO_LOAD_CHECK='Both';
      NO_IO_CHECK='Both';
      NO_ASSERT_CHECK='TRUE';
      NO_DIR_CHECK='TRUE';
      ALLOW_CONNECT='TRUE';
    'VSS'<651>:
      PIN_NUMBER='(0,0,0,0,0,0,0,0,0,0,0,0,0,0,0,0,0,0,0,0,0,0,0,0,0,BC72,0,0,0,0)';
      PINUSE='GROUND';
      NO_LOAD_CHECK='Both';
      NO_IO_CHECK='Both';
      NO_ASSERT_CHECK='TRUE';
      NO_DIR_CHECK='TRUE';
      ALLOW_CONNECT='TRUE';
    'VSS'<650>:
      PIN_NUMBER='(0,0,0,0,0,0,0,0,0,0,0,0,0,0,0,0,0,0,0,0,0,0,0,0,0,BC74,0,0,0,0)';
      PINUSE='GROUND';
      NO_LOAD_CHECK='Both';
      NO_IO_CHECK='Both';
      NO_ASSERT_CHECK='TRUE';
      NO_DIR_CHECK='TRUE';
      ALLOW_CONNECT='TRUE';
    'VSS'<649>:
      PIN_NUMBER='(0,0,0,0,0,0,0,0,0,0,0,0,0,0,0,0,0,0,0,0,0,0,0,0,0,BC76,0,0,0,0)';
      PINUSE='GROUND';
      NO_LOAD_CHECK='Both';
      NO_IO_CHECK='Both';
      NO_ASSERT_CHECK='TRUE';
      NO_DIR_CHECK='TRUE';
      ALLOW_CONNECT='TRUE';
    'VSS'<648>:
      PIN_NUMBER='(0,0,0,0,0,0,0,0,0,0,0,0,0,0,0,0,0,0,0,0,0,0,0,0,0,BC78,0,0,0,0)';
      PINUSE='GROUND';
      NO_LOAD_CHECK='Both';
      NO_IO_CHECK='Both';
      NO_ASSERT_CHECK='TRUE';
      NO_DIR_CHECK='TRUE';
      ALLOW_CONNECT='TRUE';
    'VSS'<647>:
      PIN_NUMBER='(0,0,0,0,0,0,0,0,0,0,0,0,0,0,0,0,0,0,0,0,0,0,0,0,0,BC80,0,0,0,0)';
      PINUSE='GROUND';
      NO_LOAD_CHECK='Both';
      NO_IO_CHECK='Both';
      NO_ASSERT_CHECK='TRUE';
      NO_DIR_CHECK='TRUE';
      ALLOW_CONNECT='TRUE';
    'VSS'<646>:
      PIN_NUMBER='(0,0,0,0,0,0,0,0,0,0,0,0,0,0,0,0,0,0,0,0,0,0,0,0,0,BC82,0,0,0,0)';
      PINUSE='GROUND';
      NO_LOAD_CHECK='Both';
      NO_IO_CHECK='Both';
      NO_ASSERT_CHECK='TRUE';
      NO_DIR_CHECK='TRUE';
      ALLOW_CONNECT='TRUE';
    'VSS'<645>:
      PIN_NUMBER='(0,0,0,0,0,0,0,0,0,0,0,0,0,0,0,0,0,0,0,0,0,0,0,0,0,BD5,0,0,0,0)';
      PINUSE='GROUND';
      NO_LOAD_CHECK='Both';
      NO_IO_CHECK='Both';
      NO_ASSERT_CHECK='TRUE';
      NO_DIR_CHECK='TRUE';
      ALLOW_CONNECT='TRUE';
    'VSS'<644>:
      PIN_NUMBER='(0,0,0,0,0,0,0,0,0,0,0,0,0,0,0,0,0,0,0,0,0,0,0,0,0,BD11,0,0,0,0)';
      PINUSE='GROUND';
      NO_LOAD_CHECK='Both';
      NO_IO_CHECK='Both';
      NO_ASSERT_CHECK='TRUE';
      NO_DIR_CHECK='TRUE';
      ALLOW_CONNECT='TRUE';
    'VSS'<643>:
      PIN_NUMBER='(0,0,0,0,0,0,0,0,0,0,0,0,0,0,0,0,0,0,0,0,0,0,0,0,0,BD15,0,0,0,0)';
      PINUSE='GROUND';
      NO_LOAD_CHECK='Both';
      NO_IO_CHECK='Both';
      NO_ASSERT_CHECK='TRUE';
      NO_DIR_CHECK='TRUE';
      ALLOW_CONNECT='TRUE';
    'VSS'<642>:
      PIN_NUMBER='(0,0,0,0,0,0,0,0,0,0,0,0,0,0,0,0,0,0,0,0,0,0,0,0,0,BD21,0,0,0,0)';
      PINUSE='GROUND';
      NO_LOAD_CHECK='Both';
      NO_IO_CHECK='Both';
      NO_ASSERT_CHECK='TRUE';
      NO_DIR_CHECK='TRUE';
      ALLOW_CONNECT='TRUE';
    'VSS'<641>:
      PIN_NUMBER='(0,0,0,0,0,0,0,0,0,0,0,0,0,0,0,0,0,0,0,0,0,0,0,0,0,BD27,0,0,0,0)';
      PINUSE='GROUND';
      NO_LOAD_CHECK='Both';
      NO_IO_CHECK='Both';
      NO_ASSERT_CHECK='TRUE';
      NO_DIR_CHECK='TRUE';
      ALLOW_CONNECT='TRUE';
    'VSS'<640>:
      PIN_NUMBER='(0,0,0,0,0,0,0,0,0,0,0,0,0,0,0,0,0,0,0,0,0,0,0,0,0,BD63,0,0,0,0)';
      PINUSE='GROUND';
      NO_LOAD_CHECK='Both';
      NO_IO_CHECK='Both';
      NO_ASSERT_CHECK='TRUE';
      NO_DIR_CHECK='TRUE';
      ALLOW_CONNECT='TRUE';
    'VSS'<639>:
      PIN_NUMBER='(0,0,0,0,0,0,0,0,0,0,0,0,0,0,0,0,0,0,0,0,0,0,0,0,0,BD71,0,0,0,0)';
      PINUSE='GROUND';
      NO_LOAD_CHECK='Both';
      NO_IO_CHECK='Both';
      NO_ASSERT_CHECK='TRUE';
      NO_DIR_CHECK='TRUE';
      ALLOW_CONNECT='TRUE';
    'VSS'<638>:
      PIN_NUMBER='(0,0,0,0,0,0,0,0,0,0,0,0,0,0,0,0,0,0,0,0,0,0,0,0,0,BE4,0,0,0,0)';
      PINUSE='GROUND';
      NO_LOAD_CHECK='Both';
      NO_IO_CHECK='Both';
      NO_ASSERT_CHECK='TRUE';
      NO_DIR_CHECK='TRUE';
      ALLOW_CONNECT='TRUE';
    'VSS'<637>:
      PIN_NUMBER='(0,0,0,0,0,0,0,0,0,0,0,0,0,0,0,0,0,0,0,0,0,0,0,0,0,BE6,0,0,0,0)';
      PINUSE='GROUND';
      NO_LOAD_CHECK='Both';
      NO_IO_CHECK='Both';
      NO_ASSERT_CHECK='TRUE';
      NO_DIR_CHECK='TRUE';
      ALLOW_CONNECT='TRUE';
    'VSS'<636>:
      PIN_NUMBER='(0,0,0,0,0,0,0,0,0,0,0,0,0,0,0,0,0,0,0,0,0,0,0,0,0,BE8,0,0,0,0)';
      PINUSE='GROUND';
      NO_LOAD_CHECK='Both';
      NO_IO_CHECK='Both';
      NO_ASSERT_CHECK='TRUE';
      NO_DIR_CHECK='TRUE';
      ALLOW_CONNECT='TRUE';
    'VSS'<635>:
      PIN_NUMBER='(0,0,0,0,0,0,0,0,0,0,0,0,0,0,0,0,0,0,0,0,0,0,0,0,0,BE10,0,0,0,0)';
      PINUSE='GROUND';
      NO_LOAD_CHECK='Both';
      NO_IO_CHECK='Both';
      NO_ASSERT_CHECK='TRUE';
      NO_DIR_CHECK='TRUE';
      ALLOW_CONNECT='TRUE';
    'VSS'<634>:
      PIN_NUMBER='(0,0,0,0,0,0,0,0,0,0,0,0,0,0,0,0,0,0,0,0,0,0,0,0,0,BE26,0,0,0,0)';
      PINUSE='GROUND';
      NO_LOAD_CHECK='Both';
      NO_IO_CHECK='Both';
      NO_ASSERT_CHECK='TRUE';
      NO_DIR_CHECK='TRUE';
      ALLOW_CONNECT='TRUE';
    'VSS'<633>:
      PIN_NUMBER='(0,0,0,0,0,0,0,0,0,0,0,0,0,0,0,0,0,0,0,0,0,0,0,0,0,BE64,0,0,0,0)';
      PINUSE='GROUND';
      NO_LOAD_CHECK='Both';
      NO_IO_CHECK='Both';
      NO_ASSERT_CHECK='TRUE';
      NO_DIR_CHECK='TRUE';
      ALLOW_CONNECT='TRUE';
    'VSS'<632>:
      PIN_NUMBER='(0,0,0,0,0,0,0,0,0,0,0,0,0,0,0,0,0,0,0,0,0,0,0,0,0,BE66,0,0,0,0)';
      PINUSE='GROUND';
      NO_LOAD_CHECK='Both';
      NO_IO_CHECK='Both';
      NO_ASSERT_CHECK='TRUE';
      NO_DIR_CHECK='TRUE';
      ALLOW_CONNECT='TRUE';
    'VSS'<631>:
      PIN_NUMBER='(0,0,0,0,0,0,0,0,0,0,0,0,0,0,0,0,0,0,0,0,0,0,0,0,0,BE68,0,0,0,0)';
      PINUSE='GROUND';
      NO_LOAD_CHECK='Both';
      NO_IO_CHECK='Both';
      NO_ASSERT_CHECK='TRUE';
      NO_DIR_CHECK='TRUE';
      ALLOW_CONNECT='TRUE';
    'VSS'<630>:
      PIN_NUMBER='(0,0,0,0,0,0,0,0,0,0,0,0,0,0,0,0,0,0,0,0,0,0,0,0,0,BE70,0,0,0,0)';
      PINUSE='GROUND';
      NO_LOAD_CHECK='Both';
      NO_IO_CHECK='Both';
      NO_ASSERT_CHECK='TRUE';
      NO_DIR_CHECK='TRUE';
      ALLOW_CONNECT='TRUE';
    'VSS'<629>:
      PIN_NUMBER='(0,0,0,0,0,0,0,0,0,0,0,0,0,0,0,0,0,0,0,0,0,0,0,0,0,BF9,0,0,0,0)';
      PINUSE='GROUND';
      NO_LOAD_CHECK='Both';
      NO_IO_CHECK='Both';
      NO_ASSERT_CHECK='TRUE';
      NO_DIR_CHECK='TRUE';
      ALLOW_CONNECT='TRUE';
    'VSS'<628>:
      PIN_NUMBER='(0,0,0,0,0,0,0,0,0,0,0,0,0,0,0,0,0,0,0,0,0,0,0,0,0,BF15,0,0,0,0)';
      PINUSE='GROUND';
      NO_LOAD_CHECK='Both';
      NO_IO_CHECK='Both';
      NO_ASSERT_CHECK='TRUE';
      NO_DIR_CHECK='TRUE';
      ALLOW_CONNECT='TRUE';
    'VSS'<627>:
      PIN_NUMBER='(0,0,0,0,0,0,0,0,0,0,0,0,0,0,0,0,0,0,0,0,0,0,0,0,0,BF17,0,0,0,0)';
      PINUSE='GROUND';
      NO_LOAD_CHECK='Both';
      NO_IO_CHECK='Both';
      NO_ASSERT_CHECK='TRUE';
      NO_DIR_CHECK='TRUE';
      ALLOW_CONNECT='TRUE';
    'VSS'<626>:
      PIN_NUMBER='(0,0,0,0,0,0,0,0,0,0,0,0,0,0,0,0,0,0,0,0,0,0,0,0,0,BF19,0,0,0,0)';
      PINUSE='GROUND';
      NO_LOAD_CHECK='Both';
      NO_IO_CHECK='Both';
      NO_ASSERT_CHECK='TRUE';
      NO_DIR_CHECK='TRUE';
      ALLOW_CONNECT='TRUE';
    'VSS'<625>:
      PIN_NUMBER='(0,0,0,0,0,0,0,0,0,0,0,0,0,0,0,0,0,0,0,0,0,0,0,0,0,BF25,0,0,0,0)';
      PINUSE='GROUND';
      NO_LOAD_CHECK='Both';
      NO_IO_CHECK='Both';
      NO_ASSERT_CHECK='TRUE';
      NO_DIR_CHECK='TRUE';
      ALLOW_CONNECT='TRUE';
    'VSS'<624>:
      PIN_NUMBER='(0,0,0,0,0,0,0,0,0,0,0,0,0,0,0,0,0,0,0,0,0,0,0,0,0,BF63,0,0,0,0)';
      PINUSE='GROUND';
      NO_LOAD_CHECK='Both';
      NO_IO_CHECK='Both';
      NO_ASSERT_CHECK='TRUE';
      NO_DIR_CHECK='TRUE';
      ALLOW_CONNECT='TRUE';
    'VSS'<623>:
      PIN_NUMBER='(0,0,0,0,0,0,0,0,0,0,0,0,0,0,0,0,0,0,0,0,0,0,0,0,0,BF65,0,0,0,0)';
      PINUSE='GROUND';
      NO_LOAD_CHECK='Both';
      NO_IO_CHECK='Both';
      NO_ASSERT_CHECK='TRUE';
      NO_DIR_CHECK='TRUE';
      ALLOW_CONNECT='TRUE';
    'VSS'<622>:
      PIN_NUMBER='(0,0,0,0,0,0,0,0,0,0,0,0,0,0,0,0,0,0,0,0,0,0,0,0,0,BF67,0,0,0,0)';
      PINUSE='GROUND';
      NO_LOAD_CHECK='Both';
      NO_IO_CHECK='Both';
      NO_ASSERT_CHECK='TRUE';
      NO_DIR_CHECK='TRUE';
      ALLOW_CONNECT='TRUE';
    'VSS'<621>:
      PIN_NUMBER='(0,0,0,0,0,0,0,0,0,0,0,0,0,0,0,0,0,0,0,0,0,0,0,0,0,BF69,0,0,0,0)';
      PINUSE='GROUND';
      NO_LOAD_CHECK='Both';
      NO_IO_CHECK='Both';
      NO_ASSERT_CHECK='TRUE';
      NO_DIR_CHECK='TRUE';
      ALLOW_CONNECT='TRUE';
    'VSS'<620>:
      PIN_NUMBER='(0,0,0,0,0,0,0,0,0,0,0,0,0,0,0,0,0,0,0,0,0,0,0,0,0,BF71,0,0,0,0)';
      PINUSE='GROUND';
      NO_LOAD_CHECK='Both';
      NO_IO_CHECK='Both';
      NO_ASSERT_CHECK='TRUE';
      NO_DIR_CHECK='TRUE';
      ALLOW_CONNECT='TRUE';
    'VSS'<619>:
      PIN_NUMBER='(0,0,0,0,0,0,0,0,0,0,0,0,0,0,0,0,0,0,0,0,0,0,0,0,0,BG6,0,0,0,0)';
      PINUSE='GROUND';
      NO_LOAD_CHECK='Both';
      NO_IO_CHECK='Both';
      NO_ASSERT_CHECK='TRUE';
      NO_DIR_CHECK='TRUE';
      ALLOW_CONNECT='TRUE';
    'VSS'<618>:
      PIN_NUMBER='(0,0,0,0,0,0,0,0,0,0,0,0,0,0,0,0,0,0,0,0,0,0,0,0,0,BG8,0,0,0,0)';
      PINUSE='GROUND';
      NO_LOAD_CHECK='Both';
      NO_IO_CHECK='Both';
      NO_ASSERT_CHECK='TRUE';
      NO_DIR_CHECK='TRUE';
      ALLOW_CONNECT='TRUE';
    'VSS'<617>:
      PIN_NUMBER='(0,0,0,0,0,0,0,0,0,0,0,0,0,0,0,0,0,0,0,0,0,0,0,0,0,BG10,0,0,0,0)';
      PINUSE='GROUND';
      NO_LOAD_CHECK='Both';
      NO_IO_CHECK='Both';
      NO_ASSERT_CHECK='TRUE';
      NO_DIR_CHECK='TRUE';
      ALLOW_CONNECT='TRUE';
    'VSS'<616>:
      PIN_NUMBER='(0,0,0,0,0,0,0,0,0,0,0,0,0,0,0,0,0,0,0,0,0,0,0,0,0,BG22,0,0,0,0)';
      PINUSE='GROUND';
      NO_LOAD_CHECK='Both';
      NO_IO_CHECK='Both';
      NO_ASSERT_CHECK='TRUE';
      NO_DIR_CHECK='TRUE';
      ALLOW_CONNECT='TRUE';
    'VSS'<615>:
      PIN_NUMBER='(0,0,0,0,0,0,0,0,0,0,0,0,0,0,0,0,0,0,0,0,0,0,0,0,0,BG24,0,0,0,0)';
      PINUSE='GROUND';
      NO_LOAD_CHECK='Both';
      NO_IO_CHECK='Both';
      NO_ASSERT_CHECK='TRUE';
      NO_DIR_CHECK='TRUE';
      ALLOW_CONNECT='TRUE';
    'VSS'<614>:
      PIN_NUMBER='(0,0,0,0,0,0,0,0,0,0,0,0,0,0,0,0,0,0,0,0,0,0,0,0,0,BG72,0,0,0,0)';
      PINUSE='GROUND';
      NO_LOAD_CHECK='Both';
      NO_IO_CHECK='Both';
      NO_ASSERT_CHECK='TRUE';
      NO_DIR_CHECK='TRUE';
      ALLOW_CONNECT='TRUE';
    'VSS'<613>:
      PIN_NUMBER='(0,0,0,0,0,0,0,0,0,0,0,0,0,0,0,0,0,0,0,0,0,0,0,0,0,0,BG74,0,0,0)';
      PINUSE='GROUND';
      NO_LOAD_CHECK='Both';
      NO_IO_CHECK='Both';
      NO_ASSERT_CHECK='TRUE';
      NO_DIR_CHECK='TRUE';
      ALLOW_CONNECT='TRUE';
    'VSS'<612>:
      PIN_NUMBER='(0,0,0,0,0,0,0,0,0,0,0,0,0,0,0,0,0,0,0,0,0,0,0,0,0,0,BG76,0,0,0)';
      PINUSE='GROUND';
      NO_LOAD_CHECK='Both';
      NO_IO_CHECK='Both';
      NO_ASSERT_CHECK='TRUE';
      NO_DIR_CHECK='TRUE';
      ALLOW_CONNECT='TRUE';
    'VSS'<611>:
      PIN_NUMBER='(0,0,0,0,0,0,0,0,0,0,0,0,0,0,0,0,0,0,0,0,0,0,0,0,0,0,BG78,0,0,0)';
      PINUSE='GROUND';
      NO_LOAD_CHECK='Both';
      NO_IO_CHECK='Both';
      NO_ASSERT_CHECK='TRUE';
      NO_DIR_CHECK='TRUE';
      ALLOW_CONNECT='TRUE';
    'VSS'<610>:
      PIN_NUMBER='(0,0,0,0,0,0,0,0,0,0,0,0,0,0,0,0,0,0,0,0,0,0,0,0,0,0,BG80,0,0,0)';
      PINUSE='GROUND';
      NO_LOAD_CHECK='Both';
      NO_IO_CHECK='Both';
      NO_ASSERT_CHECK='TRUE';
      NO_DIR_CHECK='TRUE';
      ALLOW_CONNECT='TRUE';
    'VSS'<609>:
      PIN_NUMBER='(0,0,0,0,0,0,0,0,0,0,0,0,0,0,0,0,0,0,0,0,0,0,0,0,0,0,BG82,0,0,0)';
      PINUSE='GROUND';
      NO_LOAD_CHECK='Both';
      NO_IO_CHECK='Both';
      NO_ASSERT_CHECK='TRUE';
      NO_DIR_CHECK='TRUE';
      ALLOW_CONNECT='TRUE';
    'VSS'<608>:
      PIN_NUMBER='(0,0,0,0,0,0,0,0,0,0,0,0,0,0,0,0,0,0,0,0,0,0,0,0,0,0,BH7,0,0,0)';
      PINUSE='GROUND';
      NO_LOAD_CHECK='Both';
      NO_IO_CHECK='Both';
      NO_ASSERT_CHECK='TRUE';
      NO_DIR_CHECK='TRUE';
      ALLOW_CONNECT='TRUE';
    'VSS'<607>:
      PIN_NUMBER='(0,0,0,0,0,0,0,0,0,0,0,0,0,0,0,0,0,0,0,0,0,0,0,0,0,0,BH9,0,0,0)';
      PINUSE='GROUND';
      NO_LOAD_CHECK='Both';
      NO_IO_CHECK='Both';
      NO_ASSERT_CHECK='TRUE';
      NO_DIR_CHECK='TRUE';
      ALLOW_CONNECT='TRUE';
    'VSS'<606>:
      PIN_NUMBER='(0,0,0,0,0,0,0,0,0,0,0,0,0,0,0,0,0,0,0,0,0,0,0,0,0,0,BH11,0,0,0)';
      PINUSE='GROUND';
      NO_LOAD_CHECK='Both';
      NO_IO_CHECK='Both';
      NO_ASSERT_CHECK='TRUE';
      NO_DIR_CHECK='TRUE';
      ALLOW_CONNECT='TRUE';
    'VSS'<605>:
      PIN_NUMBER='(0,0,0,0,0,0,0,0,0,0,0,0,0,0,0,0,0,0,0,0,0,0,0,0,0,0,BH15,0,0,0)';
      PINUSE='GROUND';
      NO_LOAD_CHECK='Both';
      NO_IO_CHECK='Both';
      NO_ASSERT_CHECK='TRUE';
      NO_DIR_CHECK='TRUE';
      ALLOW_CONNECT='TRUE';
    'VSS'<604>:
      PIN_NUMBER='(0,0,0,0,0,0,0,0,0,0,0,0,0,0,0,0,0,0,0,0,0,0,0,0,0,0,BH21,0,0,0)';
      PINUSE='GROUND';
      NO_LOAD_CHECK='Both';
      NO_IO_CHECK='Both';
      NO_ASSERT_CHECK='TRUE';
      NO_DIR_CHECK='TRUE';
      ALLOW_CONNECT='TRUE';
    'VSS'<603>:
      PIN_NUMBER='(0,0,0,0,0,0,0,0,0,0,0,0,0,0,0,0,0,0,0,0,0,0,0,0,0,0,BJ4,0,0,0)';
      PINUSE='GROUND';
      NO_LOAD_CHECK='Both';
      NO_IO_CHECK='Both';
      NO_ASSERT_CHECK='TRUE';
      NO_DIR_CHECK='TRUE';
      ALLOW_CONNECT='TRUE';
    'VSS'<602>:
      PIN_NUMBER='(0,0,0,0,0,0,0,0,0,0,0,0,0,0,0,0,0,0,0,0,0,0,0,0,0,0,BJ6,0,0,0)';
      PINUSE='GROUND';
      NO_LOAD_CHECK='Both';
      NO_IO_CHECK='Both';
      NO_ASSERT_CHECK='TRUE';
      NO_DIR_CHECK='TRUE';
      ALLOW_CONNECT='TRUE';
    'VSS'<601>:
      PIN_NUMBER='(0,0,0,0,0,0,0,0,0,0,0,0,0,0,0,0,0,0,0,0,0,0,0,0,0,0,BK3,0,0,0)';
      PINUSE='GROUND';
      NO_LOAD_CHECK='Both';
      NO_IO_CHECK='Both';
      NO_ASSERT_CHECK='TRUE';
      NO_DIR_CHECK='TRUE';
      ALLOW_CONNECT='TRUE';
    'VSS'<600>:
      PIN_NUMBER='(0,0,0,0,0,0,0,0,0,0,0,0,0,0,0,0,0,0,0,0,0,0,0,0,0,0,BK7,0,0,0)';
      PINUSE='GROUND';
      NO_LOAD_CHECK='Both';
      NO_IO_CHECK='Both';
      NO_ASSERT_CHECK='TRUE';
      NO_DIR_CHECK='TRUE';
      ALLOW_CONNECT='TRUE';
    'VSS'<599>:
      PIN_NUMBER='(0,0,0,0,0,0,0,0,0,0,0,0,0,0,0,0,0,0,0,0,0,0,0,0,0,0,BK11,0,0,0)';
      PINUSE='GROUND';
      NO_LOAD_CHECK='Both';
      NO_IO_CHECK='Both';
      NO_ASSERT_CHECK='TRUE';
      NO_DIR_CHECK='TRUE';
      ALLOW_CONNECT='TRUE';
    'VSS'<598>:
      PIN_NUMBER='(0,0,0,0,0,0,0,0,0,0,0,0,0,0,0,0,0,0,0,0,0,0,0,0,0,0,BK19,0,0,0)';
      PINUSE='GROUND';
      NO_LOAD_CHECK='Both';
      NO_IO_CHECK='Both';
      NO_ASSERT_CHECK='TRUE';
      NO_DIR_CHECK='TRUE';
      ALLOW_CONNECT='TRUE';
    'VSS'<597>:
      PIN_NUMBER='(0,0,0,0,0,0,0,0,0,0,0,0,0,0,0,0,0,0,0,0,0,0,0,0,0,0,BL6,0,0,0)';
      PINUSE='GROUND';
      NO_LOAD_CHECK='Both';
      NO_IO_CHECK='Both';
      NO_ASSERT_CHECK='TRUE';
      NO_DIR_CHECK='TRUE';
      ALLOW_CONNECT='TRUE';
    'VSS'<596>:
      PIN_NUMBER='(0,0,0,0,0,0,0,0,0,0,0,0,0,0,0,0,0,0,0,0,0,0,0,0,0,0,BL10,0,0,0)';
      PINUSE='GROUND';
      NO_LOAD_CHECK='Both';
      NO_IO_CHECK='Both';
      NO_ASSERT_CHECK='TRUE';
      NO_DIR_CHECK='TRUE';
      ALLOW_CONNECT='TRUE';
    'VSS'<595>:
      PIN_NUMBER='(0,0,0,0,0,0,0,0,0,0,0,0,0,0,0,0,0,0,0,0,0,0,0,0,0,0,BL12,0,0,0)';
      PINUSE='GROUND';
      NO_LOAD_CHECK='Both';
      NO_IO_CHECK='Both';
      NO_ASSERT_CHECK='TRUE';
      NO_DIR_CHECK='TRUE';
      ALLOW_CONNECT='TRUE';
    'VSS'<594>:
      PIN_NUMBER='(0,0,0,0,0,0,0,0,0,0,0,0,0,0,0,0,0,0,0,0,0,0,0,0,0,0,P61,0,0,0)';
      PINUSE='GROUND';
      NO_LOAD_CHECK='Both';
      NO_IO_CHECK='Both';
      NO_ASSERT_CHECK='TRUE';
      NO_DIR_CHECK='TRUE';
      ALLOW_CONNECT='TRUE';
    'VSS'<593>:
      PIN_NUMBER='(0,0,0,0,0,0,0,0,0,0,0,0,0,0,0,0,0,0,0,0,0,0,0,0,0,0,BL22,0,0,0)';
      PINUSE='GROUND';
      NO_LOAD_CHECK='Both';
      NO_IO_CHECK='Both';
      NO_ASSERT_CHECK='TRUE';
      NO_DIR_CHECK='TRUE';
      ALLOW_CONNECT='TRUE';
    'VSS'<592>:
      PIN_NUMBER='(0,0,0,0,0,0,0,0,0,0,0,0,0,0,0,0,0,0,0,0,0,0,0,0,0,0,BL24,0,0,0)';
      PINUSE='GROUND';
      NO_LOAD_CHECK='Both';
      NO_IO_CHECK='Both';
      NO_ASSERT_CHECK='TRUE';
      NO_DIR_CHECK='TRUE';
      ALLOW_CONNECT='TRUE';
    'VSS'<591>:
      PIN_NUMBER='(0,0,0,0,0,0,0,0,0,0,0,0,0,0,0,0,0,0,0,0,0,0,0,0,0,0,BL64,0,0,0)';
      PINUSE='GROUND';
      NO_LOAD_CHECK='Both';
      NO_IO_CHECK='Both';
      NO_ASSERT_CHECK='TRUE';
      NO_DIR_CHECK='TRUE';
      ALLOW_CONNECT='TRUE';
    'VSS'<590>:
      PIN_NUMBER='(0,0,0,0,0,0,0,0,0,0,0,0,0,0,0,0,0,0,0,0,0,0,0,0,0,0,BL66,0,0,0)';
      PINUSE='GROUND';
      NO_LOAD_CHECK='Both';
      NO_IO_CHECK='Both';
      NO_ASSERT_CHECK='TRUE';
      NO_DIR_CHECK='TRUE';
      ALLOW_CONNECT='TRUE';
    'VSS'<589>:
      PIN_NUMBER='(0,0,0,0,0,0,0,0,0,0,0,0,0,0,0,0,0,0,0,0,0,0,0,0,0,0,BL68,0,0,0)';
      PINUSE='GROUND';
      NO_LOAD_CHECK='Both';
      NO_IO_CHECK='Both';
      NO_ASSERT_CHECK='TRUE';
      NO_DIR_CHECK='TRUE';
      ALLOW_CONNECT='TRUE';
    'VSS'<588>:
      PIN_NUMBER='(0,0,0,0,0,0,0,0,0,0,0,0,0,0,0,0,0,0,0,0,0,0,0,0,0,0,BL70,0,0,0)';
      PINUSE='GROUND';
      NO_LOAD_CHECK='Both';
      NO_IO_CHECK='Both';
      NO_ASSERT_CHECK='TRUE';
      NO_DIR_CHECK='TRUE';
      ALLOW_CONNECT='TRUE';
    'VSS'<587>:
      PIN_NUMBER='(0,0,0,0,0,0,0,0,0,0,0,0,0,0,0,0,0,0,0,0,0,0,0,0,0,0,BL72,0,0,0)';
      PINUSE='GROUND';
      NO_LOAD_CHECK='Both';
      NO_IO_CHECK='Both';
      NO_ASSERT_CHECK='TRUE';
      NO_DIR_CHECK='TRUE';
      ALLOW_CONNECT='TRUE';
    'VSS'<586>:
      PIN_NUMBER='(0,0,0,0,0,0,0,0,0,0,0,0,0,0,0,0,0,0,0,0,0,0,0,0,0,0,BL74,0,0,0)';
      PINUSE='GROUND';
      NO_LOAD_CHECK='Both';
      NO_IO_CHECK='Both';
      NO_ASSERT_CHECK='TRUE';
      NO_DIR_CHECK='TRUE';
      ALLOW_CONNECT='TRUE';
    'VSS'<585>:
      PIN_NUMBER='(0,0,0,0,0,0,0,0,0,0,0,0,0,0,0,0,0,0,0,0,0,0,0,0,0,0,BL76,0,0,0)';
      PINUSE='GROUND';
      NO_LOAD_CHECK='Both';
      NO_IO_CHECK='Both';
      NO_ASSERT_CHECK='TRUE';
      NO_DIR_CHECK='TRUE';
      ALLOW_CONNECT='TRUE';
    'VSS'<584>:
      PIN_NUMBER='(0,0,0,0,0,0,0,0,0,0,0,0,0,0,0,0,0,0,0,0,0,0,0,0,0,0,BL78,0,0,0)';
      PINUSE='GROUND';
      NO_LOAD_CHECK='Both';
      NO_IO_CHECK='Both';
      NO_ASSERT_CHECK='TRUE';
      NO_DIR_CHECK='TRUE';
      ALLOW_CONNECT='TRUE';
    'VSS'<583>:
      PIN_NUMBER='(0,0,0,0,0,0,0,0,0,0,0,0,0,0,0,0,0,0,0,0,0,0,0,0,0,0,BL80,0,0,0)';
      PINUSE='GROUND';
      NO_LOAD_CHECK='Both';
      NO_IO_CHECK='Both';
      NO_ASSERT_CHECK='TRUE';
      NO_DIR_CHECK='TRUE';
      ALLOW_CONNECT='TRUE';
    'VSS'<582>:
      PIN_NUMBER='(0,0,0,0,0,0,0,0,0,0,0,0,0,0,0,0,0,0,0,0,0,0,0,0,0,0,BL82,0,0,0)';
      PINUSE='GROUND';
      NO_LOAD_CHECK='Both';
      NO_IO_CHECK='Both';
      NO_ASSERT_CHECK='TRUE';
      NO_DIR_CHECK='TRUE';
      ALLOW_CONNECT='TRUE';
    'VSS'<581>:
      PIN_NUMBER='(0,0,0,0,0,0,0,0,0,0,0,0,0,0,0,0,0,0,0,0,0,0,0,0,0,0,BM9,0,0,0)';
      PINUSE='GROUND';
      NO_LOAD_CHECK='Both';
      NO_IO_CHECK='Both';
      NO_ASSERT_CHECK='TRUE';
      NO_DIR_CHECK='TRUE';
      ALLOW_CONNECT='TRUE';
    'VSS'<580>:
      PIN_NUMBER='(0,0,0,0,0,0,0,0,0,0,0,0,0,0,0,0,0,0,0,0,0,0,0,0,0,0,BM13,0,0,0)';
      PINUSE='GROUND';
      NO_LOAD_CHECK='Both';
      NO_IO_CHECK='Both';
      NO_ASSERT_CHECK='TRUE';
      NO_DIR_CHECK='TRUE';
      ALLOW_CONNECT='TRUE';
    'VSS'<579>:
      PIN_NUMBER='(0,0,0,0,0,0,0,0,0,0,0,0,0,0,0,0,0,0,0,0,0,0,0,0,0,0,BM15,0,0,0)';
      PINUSE='GROUND';
      NO_LOAD_CHECK='Both';
      NO_IO_CHECK='Both';
      NO_ASSERT_CHECK='TRUE';
      NO_DIR_CHECK='TRUE';
      ALLOW_CONNECT='TRUE';
    'VSS'<578>:
      PIN_NUMBER='(0,0,0,0,0,0,0,0,0,0,0,0,0,0,0,0,0,0,0,0,0,0,0,0,0,0,P59,0,0,0)';
      PINUSE='GROUND';
      NO_LOAD_CHECK='Both';
      NO_IO_CHECK='Both';
      NO_ASSERT_CHECK='TRUE';
      NO_DIR_CHECK='TRUE';
      ALLOW_CONNECT='TRUE';
    'VSS'<577>:
      PIN_NUMBER='(0,0,0,0,0,0,0,0,0,0,0,0,0,0,0,0,0,0,0,0,0,0,0,0,0,0,BM25,0,0,0)';
      PINUSE='GROUND';
      NO_LOAD_CHECK='Both';
      NO_IO_CHECK='Both';
      NO_ASSERT_CHECK='TRUE';
      NO_DIR_CHECK='TRUE';
      ALLOW_CONNECT='TRUE';
    'VSS'<576>:
      PIN_NUMBER='(0,0,0,0,0,0,0,0,0,0,0,0,0,0,0,0,0,0,0,0,0,0,0,0,0,0,BN6,0,0,0)';
      PINUSE='GROUND';
      NO_LOAD_CHECK='Both';
      NO_IO_CHECK='Both';
      NO_ASSERT_CHECK='TRUE';
      NO_DIR_CHECK='TRUE';
      ALLOW_CONNECT='TRUE';
    'VSS'<575>:
      PIN_NUMBER='(0,0,0,0,0,0,0,0,0,0,0,0,0,0,0,0,0,0,0,0,0,0,0,0,0,0,BN10,0,0,0)';
      PINUSE='GROUND';
      NO_LOAD_CHECK='Both';
      NO_IO_CHECK='Both';
      NO_ASSERT_CHECK='TRUE';
      NO_DIR_CHECK='TRUE';
      ALLOW_CONNECT='TRUE';
    'VSS'<574>:
      PIN_NUMBER='(0,0,0,0,0,0,0,0,0,0,0,0,0,0,0,0,0,0,0,0,0,0,0,0,0,0,BN20,0,0,0)';
      PINUSE='GROUND';
      NO_LOAD_CHECK='Both';
      NO_IO_CHECK='Both';
      NO_ASSERT_CHECK='TRUE';
      NO_DIR_CHECK='TRUE';
      ALLOW_CONNECT='TRUE';
    'VSS'<573>:
      PIN_NUMBER='(0,0,0,0,0,0,0,0,0,0,0,0,0,0,0,0,0,0,0,0,0,0,0,0,0,0,BN26,0,0,0)';
      PINUSE='GROUND';
      NO_LOAD_CHECK='Both';
      NO_IO_CHECK='Both';
      NO_ASSERT_CHECK='TRUE';
      NO_DIR_CHECK='TRUE';
      ALLOW_CONNECT='TRUE';
    'VSS'<572>:
      PIN_NUMBER='(0,0,0,0,0,0,0,0,0,0,0,0,0,0,0,0,0,0,0,0,0,0,0,0,0,0,BP3,0,0,0)';
      PINUSE='GROUND';
      NO_LOAD_CHECK='Both';
      NO_IO_CHECK='Both';
      NO_ASSERT_CHECK='TRUE';
      NO_DIR_CHECK='TRUE';
      ALLOW_CONNECT='TRUE';
    'VSS'<571>:
      PIN_NUMBER='(0,0,0,0,0,0,0,0,0,0,0,0,0,0,0,0,0,0,0,0,0,0,0,0,0,0,BP27,0,0,0)';
      PINUSE='GROUND';
      NO_LOAD_CHECK='Both';
      NO_IO_CHECK='Both';
      NO_ASSERT_CHECK='TRUE';
      NO_DIR_CHECK='TRUE';
      ALLOW_CONNECT='TRUE';
    'VSS'<570>:
      PIN_NUMBER='(0,0,0,0,0,0,0,0,0,0,0,0,0,0,0,0,0,0,0,0,0,0,0,0,0,0,BR6,0,0,0)';
      PINUSE='GROUND';
      NO_LOAD_CHECK='Both';
      NO_IO_CHECK='Both';
      NO_ASSERT_CHECK='TRUE';
      NO_DIR_CHECK='TRUE';
      ALLOW_CONNECT='TRUE';
    'VSS'<569>:
      PIN_NUMBER='(0,0,0,0,0,0,0,0,0,0,0,0,0,0,0,0,0,0,0,0,0,0,0,0,0,0,BR10,0,0,0)';
      PINUSE='GROUND';
      NO_LOAD_CHECK='Both';
      NO_IO_CHECK='Both';
      NO_ASSERT_CHECK='TRUE';
      NO_DIR_CHECK='TRUE';
      ALLOW_CONNECT='TRUE';
    'VSS'<568>:
      PIN_NUMBER='(0,0,0,0,0,0,0,0,0,0,0,0,0,0,0,0,0,0,0,0,0,0,0,0,0,0,BR16,0,0,0)';
      PINUSE='GROUND';
      NO_LOAD_CHECK='Both';
      NO_IO_CHECK='Both';
      NO_ASSERT_CHECK='TRUE';
      NO_DIR_CHECK='TRUE';
      ALLOW_CONNECT='TRUE';
    'VSS'<567>:
      PIN_NUMBER='(0,0,0,0,0,0,0,0,0,0,0,0,0,0,0,0,0,0,0,0,0,0,0,0,0,0,P57,0,0,0)';
      PINUSE='GROUND';
      NO_LOAD_CHECK='Both';
      NO_IO_CHECK='Both';
      NO_ASSERT_CHECK='TRUE';
      NO_DIR_CHECK='TRUE';
      ALLOW_CONNECT='TRUE';
    'VSS'<566>:
      PIN_NUMBER='(0,0,0,0,0,0,0,0,0,0,0,0,0,0,0,0,0,0,0,0,0,0,0,0,0,0,BR64,0,0,0)';
      PINUSE='GROUND';
      NO_LOAD_CHECK='Both';
      NO_IO_CHECK='Both';
      NO_ASSERT_CHECK='TRUE';
      NO_DIR_CHECK='TRUE';
      ALLOW_CONNECT='TRUE';
    'VSS'<565>:
      PIN_NUMBER='(0,0,0,0,0,0,0,0,0,0,0,0,0,0,0,0,0,0,0,0,0,0,0,0,0,0,BR66,0,0,0)';
      PINUSE='GROUND';
      NO_LOAD_CHECK='Both';
      NO_IO_CHECK='Both';
      NO_ASSERT_CHECK='TRUE';
      NO_DIR_CHECK='TRUE';
      ALLOW_CONNECT='TRUE';
    'VSS'<564>:
      PIN_NUMBER='(0,0,0,0,0,0,0,0,0,0,0,0,0,0,0,0,0,0,0,0,0,0,0,0,0,0,BR68,0,0,0)';
      PINUSE='GROUND';
      NO_LOAD_CHECK='Both';
      NO_IO_CHECK='Both';
      NO_ASSERT_CHECK='TRUE';
      NO_DIR_CHECK='TRUE';
      ALLOW_CONNECT='TRUE';
    'VSS'<563>:
      PIN_NUMBER='(0,0,0,0,0,0,0,0,0,0,0,0,0,0,0,0,0,0,0,0,0,0,0,0,0,0,BR70,0,0,0)';
      PINUSE='GROUND';
      NO_LOAD_CHECK='Both';
      NO_IO_CHECK='Both';
      NO_ASSERT_CHECK='TRUE';
      NO_DIR_CHECK='TRUE';
      ALLOW_CONNECT='TRUE';
    'VSS'<562>:
      PIN_NUMBER='(0,0,0,0,0,0,0,0,0,0,0,0,0,0,0,0,0,0,0,0,0,0,0,0,0,0,BR72,0,0,0)';
      PINUSE='GROUND';
      NO_LOAD_CHECK='Both';
      NO_IO_CHECK='Both';
      NO_ASSERT_CHECK='TRUE';
      NO_DIR_CHECK='TRUE';
      ALLOW_CONNECT='TRUE';
    'VSS'<561>:
      PIN_NUMBER='(0,0,0,0,0,0,0,0,0,0,0,0,0,0,0,0,0,0,0,0,0,0,0,0,0,0,BR74,0,0,0)';
      PINUSE='GROUND';
      NO_LOAD_CHECK='Both';
      NO_IO_CHECK='Both';
      NO_ASSERT_CHECK='TRUE';
      NO_DIR_CHECK='TRUE';
      ALLOW_CONNECT='TRUE';
    'VSS'<560>:
      PIN_NUMBER='(0,0,0,0,0,0,0,0,0,0,0,0,0,0,0,0,0,0,0,0,0,0,0,0,0,0,BR76,0,0,0)';
      PINUSE='GROUND';
      NO_LOAD_CHECK='Both';
      NO_IO_CHECK='Both';
      NO_ASSERT_CHECK='TRUE';
      NO_DIR_CHECK='TRUE';
      ALLOW_CONNECT='TRUE';
    'VSS'<559>:
      PIN_NUMBER='(0,0,0,0,0,0,0,0,0,0,0,0,0,0,0,0,0,0,0,0,0,0,0,0,0,0,BR78,0,0,0)';
      PINUSE='GROUND';
      NO_LOAD_CHECK='Both';
      NO_IO_CHECK='Both';
      NO_ASSERT_CHECK='TRUE';
      NO_DIR_CHECK='TRUE';
      ALLOW_CONNECT='TRUE';
    'VSS'<558>:
      PIN_NUMBER='(0,0,0,0,0,0,0,0,0,0,0,0,0,0,0,0,0,0,0,0,0,0,0,0,0,0,BR80,0,0,0)';
      PINUSE='GROUND';
      NO_LOAD_CHECK='Both';
      NO_IO_CHECK='Both';
      NO_ASSERT_CHECK='TRUE';
      NO_DIR_CHECK='TRUE';
      ALLOW_CONNECT='TRUE';
    'VSS'<557>:
      PIN_NUMBER='(0,0,0,0,0,0,0,0,0,0,0,0,0,0,0,0,0,0,0,0,0,0,0,0,0,0,BR82,0,0,0)';
      PINUSE='GROUND';
      NO_LOAD_CHECK='Both';
      NO_IO_CHECK='Both';
      NO_ASSERT_CHECK='TRUE';
      NO_DIR_CHECK='TRUE';
      ALLOW_CONNECT='TRUE';
    'VSS'<556>:
      PIN_NUMBER='(0,0,0,0,0,0,0,0,0,0,0,0,0,0,0,0,0,0,0,0,0,0,0,0,0,0,BT3,0,0,0)';
      PINUSE='GROUND';
      NO_LOAD_CHECK='Both';
      NO_IO_CHECK='Both';
      NO_ASSERT_CHECK='TRUE';
      NO_DIR_CHECK='TRUE';
      ALLOW_CONNECT='TRUE';
    'VSS'<555>:
      PIN_NUMBER='(0,0,0,0,0,0,0,0,0,0,0,0,0,0,0,0,0,0,0,0,0,0,0,0,0,0,BT5,0,0,0)';
      PINUSE='GROUND';
      NO_LOAD_CHECK='Both';
      NO_IO_CHECK='Both';
      NO_ASSERT_CHECK='TRUE';
      NO_DIR_CHECK='TRUE';
      ALLOW_CONNECT='TRUE';
    'VSS'<554>:
      PIN_NUMBER='(0,0,0,0,0,0,0,0,0,0,0,0,0,0,0,0,0,0,0,0,0,0,0,0,0,0,BT21,0,0,0)';
      PINUSE='GROUND';
      NO_LOAD_CHECK='Both';
      NO_IO_CHECK='Both';
      NO_ASSERT_CHECK='TRUE';
      NO_DIR_CHECK='TRUE';
      ALLOW_CONNECT='TRUE';
    'VSS'<553>:
      PIN_NUMBER='(0,0,0,0,0,0,0,0,0,0,0,0,0,0,0,0,0,0,0,0,0,0,0,0,0,0,BT23,0,0,0)';
      PINUSE='GROUND';
      NO_LOAD_CHECK='Both';
      NO_IO_CHECK='Both';
      NO_ASSERT_CHECK='TRUE';
      NO_DIR_CHECK='TRUE';
      ALLOW_CONNECT='TRUE';
    'VSS'<552>:
      PIN_NUMBER='(0,0,0,0,0,0,0,0,0,0,0,0,0,0,0,0,0,0,0,0,0,0,0,0,0,0,BT25,0,0,0)';
      PINUSE='GROUND';
      NO_LOAD_CHECK='Both';
      NO_IO_CHECK='Both';
      NO_ASSERT_CHECK='TRUE';
      NO_DIR_CHECK='TRUE';
      ALLOW_CONNECT='TRUE';
    'VSS'<551>:
      PIN_NUMBER='(0,0,0,0,0,0,0,0,0,0,0,0,0,0,0,0,0,0,0,0,0,0,0,0,0,0,BU8,0,0,0)';
      PINUSE='GROUND';
      NO_LOAD_CHECK='Both';
      NO_IO_CHECK='Both';
      NO_ASSERT_CHECK='TRUE';
      NO_DIR_CHECK='TRUE';
      ALLOW_CONNECT='TRUE';
    'VSS'<550>:
      PIN_NUMBER='(0,0,0,0,0,0,0,0,0,0,0,0,0,0,0,0,0,0,0,0,0,0,0,0,0,0,BV5,0,0,0)';
      PINUSE='GROUND';
      NO_LOAD_CHECK='Both';
      NO_IO_CHECK='Both';
      NO_ASSERT_CHECK='TRUE';
      NO_DIR_CHECK='TRUE';
      ALLOW_CONNECT='TRUE';
    'VSS'<549>:
      PIN_NUMBER='(0,0,0,0,0,0,0,0,0,0,0,0,0,0,0,0,0,0,0,0,0,0,0,0,0,0,BU10,0,0,0)';
      PINUSE='GROUND';
      NO_LOAD_CHECK='Both';
      NO_IO_CHECK='Both';
      NO_ASSERT_CHECK='TRUE';
      NO_DIR_CHECK='TRUE';
      ALLOW_CONNECT='TRUE';
    'VSS'<548>:
      PIN_NUMBER='(0,0,0,0,0,0,0,0,0,0,0,0,0,0,0,0,0,0,0,0,0,0,0,0,0,0,BV17,0,0,0)';
      PINUSE='GROUND';
      NO_LOAD_CHECK='Both';
      NO_IO_CHECK='Both';
      NO_ASSERT_CHECK='TRUE';
      NO_DIR_CHECK='TRUE';
      ALLOW_CONNECT='TRUE';
    'VSS'<547>:
      PIN_NUMBER='(0,0,0,0,0,0,0,0,0,0,0,0,0,0,0,0,0,0,0,0,0,0,0,0,0,0,BV25,0,0,0)';
      PINUSE='GROUND';
      NO_LOAD_CHECK='Both';
      NO_IO_CHECK='Both';
      NO_ASSERT_CHECK='TRUE';
      NO_DIR_CHECK='TRUE';
      ALLOW_CONNECT='TRUE';
    'VSS'<546>:
      PIN_NUMBER='(0,0,0,0,0,0,0,0,0,0,0,0,0,0,0,0,0,0,0,0,0,0,0,0,0,0,BW6,0,0,0)';
      PINUSE='GROUND';
      NO_LOAD_CHECK='Both';
      NO_IO_CHECK='Both';
      NO_ASSERT_CHECK='TRUE';
      NO_DIR_CHECK='TRUE';
      ALLOW_CONNECT='TRUE';
    'VSS'<545>:
      PIN_NUMBER='(0,0,0,0,0,0,0,0,0,0,0,0,0,0,0,0,0,0,0,0,0,0,0,0,0,0,P55,0,0,0)';
      PINUSE='GROUND';
      NO_LOAD_CHECK='Both';
      NO_IO_CHECK='Both';
      NO_ASSERT_CHECK='TRUE';
      NO_DIR_CHECK='TRUE';
      ALLOW_CONNECT='TRUE';
    'VSS'<544>:
      PIN_NUMBER='(0,0,0,0,0,0,0,0,0,0,0,0,0,0,0,0,0,0,0,0,0,0,0,0,0,0,BW12,0,0,0)';
      PINUSE='GROUND';
      NO_LOAD_CHECK='Both';
      NO_IO_CHECK='Both';
      NO_ASSERT_CHECK='TRUE';
      NO_DIR_CHECK='TRUE';
      ALLOW_CONNECT='TRUE';
    'VSS'<543>:
      PIN_NUMBER='(0,0,0,0,0,0,0,0,0,0,0,0,0,0,0,0,0,0,0,0,0,0,0,0,0,0,BW14,0,0,0)';
      PINUSE='GROUND';
      NO_LOAD_CHECK='Both';
      NO_IO_CHECK='Both';
      NO_ASSERT_CHECK='TRUE';
      NO_DIR_CHECK='TRUE';
      ALLOW_CONNECT='TRUE';
    'VSS'<542>:
      PIN_NUMBER='(0,0,0,0,0,0,0,0,0,0,0,0,0,0,0,0,0,0,0,0,0,0,0,0,0,0,BW16,0,0,0)';
      PINUSE='GROUND';
      NO_LOAD_CHECK='Both';
      NO_IO_CHECK='Both';
      NO_ASSERT_CHECK='TRUE';
      NO_DIR_CHECK='TRUE';
      ALLOW_CONNECT='TRUE';
    'VSS'<541>:
      PIN_NUMBER='(0,0,0,0,0,0,0,0,0,0,0,0,0,0,0,0,0,0,0,0,0,0,0,0,0,0,BW18,0,0,0)';
      PINUSE='GROUND';
      NO_LOAD_CHECK='Both';
      NO_IO_CHECK='Both';
      NO_ASSERT_CHECK='TRUE';
      NO_DIR_CHECK='TRUE';
      ALLOW_CONNECT='TRUE';
    'VSS'<540>:
      PIN_NUMBER='(0,0,0,0,0,0,0,0,0,0,0,0,0,0,0,0,0,0,0,0,0,0,0,0,0,0,BW26,0,0,0)';
      PINUSE='GROUND';
      NO_LOAD_CHECK='Both';
      NO_IO_CHECK='Both';
      NO_ASSERT_CHECK='TRUE';
      NO_DIR_CHECK='TRUE';
      ALLOW_CONNECT='TRUE';
    'VSS'<539>:
      PIN_NUMBER='(0,0,0,0,0,0,0,0,0,0,0,0,0,0,0,0,0,0,0,0,0,0,0,0,0,0,BW72,0,0,0)';
      PINUSE='GROUND';
      NO_LOAD_CHECK='Both';
      NO_IO_CHECK='Both';
      NO_ASSERT_CHECK='TRUE';
      NO_DIR_CHECK='TRUE';
      ALLOW_CONNECT='TRUE';
    'VSS'<538>:
      PIN_NUMBER='(0,0,0,0,0,0,0,0,0,0,0,0,0,0,0,0,0,0,0,0,0,0,0,0,0,0,BW74,0,0,0)';
      PINUSE='GROUND';
      NO_LOAD_CHECK='Both';
      NO_IO_CHECK='Both';
      NO_ASSERT_CHECK='TRUE';
      NO_DIR_CHECK='TRUE';
      ALLOW_CONNECT='TRUE';
    'VSS'<537>:
      PIN_NUMBER='(0,0,0,0,0,0,0,0,0,0,0,0,0,0,0,0,0,0,0,0,0,0,0,0,0,0,BW76,0,0,0)';
      PINUSE='GROUND';
      NO_LOAD_CHECK='Both';
      NO_IO_CHECK='Both';
      NO_ASSERT_CHECK='TRUE';
      NO_DIR_CHECK='TRUE';
      ALLOW_CONNECT='TRUE';
    'VSS'<536>:
      PIN_NUMBER='(0,0,0,0,0,0,0,0,0,0,0,0,0,0,0,0,0,0,0,0,0,0,0,0,0,0,BW78,0,0,0)';
      PINUSE='GROUND';
      NO_LOAD_CHECK='Both';
      NO_IO_CHECK='Both';
      NO_ASSERT_CHECK='TRUE';
      NO_DIR_CHECK='TRUE';
      ALLOW_CONNECT='TRUE';
    'VSS'<535>:
      PIN_NUMBER='(0,0,0,0,0,0,0,0,0,0,0,0,0,0,0,0,0,0,0,0,0,0,0,0,0,0,BW80,0,0,0)';
      PINUSE='GROUND';
      NO_LOAD_CHECK='Both';
      NO_IO_CHECK='Both';
      NO_ASSERT_CHECK='TRUE';
      NO_DIR_CHECK='TRUE';
      ALLOW_CONNECT='TRUE';
    'VSS'<534>:
      PIN_NUMBER='(0,0,0,0,0,0,0,0,0,0,0,0,0,0,0,0,0,0,0,0,0,0,0,0,0,0,BW82,0,0,0)';
      PINUSE='GROUND';
      NO_LOAD_CHECK='Both';
      NO_IO_CHECK='Both';
      NO_ASSERT_CHECK='TRUE';
      NO_DIR_CHECK='TRUE';
      ALLOW_CONNECT='TRUE';
    'VSS'<533>:
      PIN_NUMBER='(0,0,0,0,0,0,0,0,0,0,0,0,0,0,0,0,0,0,0,0,0,0,0,0,0,0,BY11,0,0,0)';
      PINUSE='GROUND';
      NO_LOAD_CHECK='Both';
      NO_IO_CHECK='Both';
      NO_ASSERT_CHECK='TRUE';
      NO_DIR_CHECK='TRUE';
      ALLOW_CONNECT='TRUE';
    'VSS'<532>:
      PIN_NUMBER='(0,0,0,0,0,0,0,0,0,0,0,0,0,0,0,0,0,0,0,0,0,0,0,0,0,0,BY13,0,0,0)';
      PINUSE='GROUND';
      NO_LOAD_CHECK='Both';
      NO_IO_CHECK='Both';
      NO_ASSERT_CHECK='TRUE';
      NO_DIR_CHECK='TRUE';
      ALLOW_CONNECT='TRUE';
    'VSS'<531>:
      PIN_NUMBER='(0,0,0,0,0,0,0,0,0,0,0,0,0,0,0,0,0,0,0,0,0,0,0,0,0,0,BY23,0,0,0)';
      PINUSE='GROUND';
      NO_LOAD_CHECK='Both';
      NO_IO_CHECK='Both';
      NO_ASSERT_CHECK='TRUE';
      NO_DIR_CHECK='TRUE';
      ALLOW_CONNECT='TRUE';
    'VSS'<530>:
      PIN_NUMBER='(0,0,0,0,0,0,0,0,0,0,0,0,0,0,0,0,0,0,0,0,0,0,0,0,0,0,BY63,0,0,0)';
      PINUSE='GROUND';
      NO_LOAD_CHECK='Both';
      NO_IO_CHECK='Both';
      NO_ASSERT_CHECK='TRUE';
      NO_DIR_CHECK='TRUE';
      ALLOW_CONNECT='TRUE';
    'VSS'<529>:
      PIN_NUMBER='(0,0,0,0,0,0,0,0,0,0,0,0,0,0,0,0,0,0,0,0,0,0,0,0,0,0,BY65,0,0,0)';
      PINUSE='GROUND';
      NO_LOAD_CHECK='Both';
      NO_IO_CHECK='Both';
      NO_ASSERT_CHECK='TRUE';
      NO_DIR_CHECK='TRUE';
      ALLOW_CONNECT='TRUE';
    'VSS'<528>:
      PIN_NUMBER='(0,0,0,0,0,0,0,0,0,0,0,0,0,0,0,0,0,0,0,0,0,0,0,0,0,0,BY67,0,0,0)';
      PINUSE='GROUND';
      NO_LOAD_CHECK='Both';
      NO_IO_CHECK='Both';
      NO_ASSERT_CHECK='TRUE';
      NO_DIR_CHECK='TRUE';
      ALLOW_CONNECT='TRUE';
    'VSS'<527>:
      PIN_NUMBER='(0,0,0,0,0,0,0,0,0,0,0,0,0,0,0,0,0,0,0,0,0,0,0,0,0,0,BY69,0,0,0)';
      PINUSE='GROUND';
      NO_LOAD_CHECK='Both';
      NO_IO_CHECK='Both';
      NO_ASSERT_CHECK='TRUE';
      NO_DIR_CHECK='TRUE';
      ALLOW_CONNECT='TRUE';
    'VSS'<526>:
      PIN_NUMBER='(0,0,0,0,0,0,0,0,0,0,0,0,0,0,0,0,0,0,0,0,0,0,0,0,0,0,BY71,0,0,0)';
      PINUSE='GROUND';
      NO_LOAD_CHECK='Both';
      NO_IO_CHECK='Both';
      NO_ASSERT_CHECK='TRUE';
      NO_DIR_CHECK='TRUE';
      ALLOW_CONNECT='TRUE';
    'VSS'<525>:
      PIN_NUMBER='(0,0,0,0,0,0,0,0,0,0,0,0,0,0,0,0,0,0,0,0,0,0,0,0,0,0,CA2,0,0,0)';
      PINUSE='GROUND';
      NO_LOAD_CHECK='Both';
      NO_IO_CHECK='Both';
      NO_ASSERT_CHECK='TRUE';
      NO_DIR_CHECK='TRUE';
      ALLOW_CONNECT='TRUE';
    'VSS'<524>:
      PIN_NUMBER='(0,0,0,0,0,0,0,0,0,0,0,0,0,0,0,0,0,0,0,0,0,0,0,0,0,0,CA6,0,0,0)';
      PINUSE='GROUND';
      NO_LOAD_CHECK='Both';
      NO_IO_CHECK='Both';
      NO_ASSERT_CHECK='TRUE';
      NO_DIR_CHECK='TRUE';
      ALLOW_CONNECT='TRUE';
    'VSS'<523>:
      PIN_NUMBER='(0,0,0,0,0,0,0,0,0,0,0,0,0,0,0,0,0,0,0,0,0,0,0,0,0,0,CA8,0,0,0)';
      PINUSE='GROUND';
      NO_LOAD_CHECK='Both';
      NO_IO_CHECK='Both';
      NO_ASSERT_CHECK='TRUE';
      NO_DIR_CHECK='TRUE';
      ALLOW_CONNECT='TRUE';
    'VSS'<522>:
      PIN_NUMBER='(0,0,0,0,0,0,0,0,0,0,0,0,0,0,0,0,0,0,0,0,0,0,0,0,0,0,CA10,0,0,0)';
      PINUSE='GROUND';
      NO_LOAD_CHECK='Both';
      NO_IO_CHECK='Both';
      NO_ASSERT_CHECK='TRUE';
      NO_DIR_CHECK='TRUE';
      ALLOW_CONNECT='TRUE';
    'VSS'<521>:
      PIN_NUMBER='(0,0,0,0,0,0,0,0,0,0,0,0,0,0,0,0,0,0,0,0,0,0,0,0,0,0,CA14,0,0,0)';
      PINUSE='GROUND';
      NO_LOAD_CHECK='Both';
      NO_IO_CHECK='Both';
      NO_ASSERT_CHECK='TRUE';
      NO_DIR_CHECK='TRUE';
      ALLOW_CONNECT='TRUE';
    'VSS'<520>:
      PIN_NUMBER='(0,0,0,0,0,0,0,0,0,0,0,0,0,0,0,0,0,0,0,0,0,0,0,0,0,0,CA18,0,0,0)';
      PINUSE='GROUND';
      NO_LOAD_CHECK='Both';
      NO_IO_CHECK='Both';
      NO_ASSERT_CHECK='TRUE';
      NO_DIR_CHECK='TRUE';
      ALLOW_CONNECT='TRUE';
    'VSS'<519>:
      PIN_NUMBER='(0,0,0,0,0,0,0,0,0,0,0,0,0,0,0,0,0,0,0,0,0,0,0,0,0,0,CA26,0,0,0)';
      PINUSE='GROUND';
      NO_LOAD_CHECK='Both';
      NO_IO_CHECK='Both';
      NO_ASSERT_CHECK='TRUE';
      NO_DIR_CHECK='TRUE';
      ALLOW_CONNECT='TRUE';
    'VSS'<518>:
      PIN_NUMBER='(0,0,0,0,0,0,0,0,0,0,0,0,0,0,0,0,0,0,0,0,0,0,0,0,0,0,CA64,0,0,0)';
      PINUSE='GROUND';
      NO_LOAD_CHECK='Both';
      NO_IO_CHECK='Both';
      NO_ASSERT_CHECK='TRUE';
      NO_DIR_CHECK='TRUE';
      ALLOW_CONNECT='TRUE';
    'VSS'<517>:
      PIN_NUMBER='(0,0,0,0,0,0,0,0,0,0,0,0,0,0,0,0,0,0,0,0,0,0,0,0,0,0,CA66,0,0,0)';
      PINUSE='GROUND';
      NO_LOAD_CHECK='Both';
      NO_IO_CHECK='Both';
      NO_ASSERT_CHECK='TRUE';
      NO_DIR_CHECK='TRUE';
      ALLOW_CONNECT='TRUE';
    'VSS'<516>:
      PIN_NUMBER='(0,0,0,0,0,0,0,0,0,0,0,0,0,0,0,0,0,0,0,0,0,0,0,0,0,0,CA68,0,0,0)';
      PINUSE='GROUND';
      NO_LOAD_CHECK='Both';
      NO_IO_CHECK='Both';
      NO_ASSERT_CHECK='TRUE';
      NO_DIR_CHECK='TRUE';
      ALLOW_CONNECT='TRUE';
    'VSS'<515>:
      PIN_NUMBER='(0,0,0,0,0,0,0,0,0,0,0,0,0,0,0,0,0,0,0,0,0,0,0,0,0,0,CA70,0,0,0)';
      PINUSE='GROUND';
      NO_LOAD_CHECK='Both';
      NO_IO_CHECK='Both';
      NO_ASSERT_CHECK='TRUE';
      NO_DIR_CHECK='TRUE';
      ALLOW_CONNECT='TRUE';
    'VSS'<514>:
      PIN_NUMBER='(0,0,0,0,0,0,0,0,0,0,0,0,0,0,0,0,0,0,0,0,0,0,0,0,0,0,CB7,0,0,0)';
      PINUSE='GROUND';
      NO_LOAD_CHECK='Both';
      NO_IO_CHECK='Both';
      NO_ASSERT_CHECK='TRUE';
      NO_DIR_CHECK='TRUE';
      ALLOW_CONNECT='TRUE';
    'VSS'<513>:
      PIN_NUMBER='(0,0,0,0,0,0,0,0,0,0,0,0,0,0,0,0,0,0,0,0,0,0,0,0,0,0,CB9,0,0,0)';
      PINUSE='GROUND';
      NO_LOAD_CHECK='Both';
      NO_IO_CHECK='Both';
      NO_ASSERT_CHECK='TRUE';
      NO_DIR_CHECK='TRUE';
      ALLOW_CONNECT='TRUE';
    'VSS'<512>:
      PIN_NUMBER='(0,0,0,0,0,0,0,0,0,0,0,0,0,0,0,0,0,0,0,0,0,0,0,0,0,0,CB27,0,0,0)';
      PINUSE='GROUND';
      NO_LOAD_CHECK='Both';
      NO_IO_CHECK='Both';
      NO_ASSERT_CHECK='TRUE';
      NO_DIR_CHECK='TRUE';
      ALLOW_CONNECT='TRUE';
    'VSS'<511>:
      PIN_NUMBER='(0,0,0,0,0,0,0,0,0,0,0,0,0,0,0,0,0,0,0,0,0,0,0,0,0,0,CB63,0,0,0)';
      PINUSE='GROUND';
      NO_LOAD_CHECK='Both';
      NO_IO_CHECK='Both';
      NO_ASSERT_CHECK='TRUE';
      NO_DIR_CHECK='TRUE';
      ALLOW_CONNECT='TRUE';
    'VSS'<510>:
      PIN_NUMBER='(0,0,0,0,0,0,0,0,0,0,0,0,0,0,0,0,0,0,0,0,0,0,0,0,0,0,CB71,0,0,0)';
      PINUSE='GROUND';
      NO_LOAD_CHECK='Both';
      NO_IO_CHECK='Both';
      NO_ASSERT_CHECK='TRUE';
      NO_DIR_CHECK='TRUE';
      ALLOW_CONNECT='TRUE';
    'VSS'<509>:
      PIN_NUMBER='(0,0,0,0,0,0,0,0,0,0,0,0,0,0,0,0,0,0,0,0,0,0,0,0,0,0,CC4,0,0,0)';
      PINUSE='GROUND';
      NO_LOAD_CHECK='Both';
      NO_IO_CHECK='Both';
      NO_ASSERT_CHECK='TRUE';
      NO_DIR_CHECK='TRUE';
      ALLOW_CONNECT='TRUE';
    'VSS'<508>:
      PIN_NUMBER='(0,0,0,0,0,0,0,0,0,0,0,0,0,0,0,0,0,0,0,0,0,0,0,0,0,0,CC16,0,0,0)';
      PINUSE='GROUND';
      NO_LOAD_CHECK='Both';
      NO_IO_CHECK='Both';
      NO_ASSERT_CHECK='TRUE';
      NO_DIR_CHECK='TRUE';
      ALLOW_CONNECT='TRUE';
    'VSS'<507>:
      PIN_NUMBER='(0,0,0,0,0,0,0,0,0,0,0,0,0,0,0,0,0,0,0,0,0,0,0,0,0,0,CC18,0,0,0)';
      PINUSE='GROUND';
      NO_LOAD_CHECK='Both';
      NO_IO_CHECK='Both';
      NO_ASSERT_CHECK='TRUE';
      NO_DIR_CHECK='TRUE';
      ALLOW_CONNECT='TRUE';
    'VSS'<506>:
      PIN_NUMBER='(0,0,0,0,0,0,0,0,0,0,0,0,0,0,0,0,0,0,0,0,0,0,0,0,0,0,CC24,0,0,0)';
      PINUSE='GROUND';
      NO_LOAD_CHECK='Both';
      NO_IO_CHECK='Both';
      NO_ASSERT_CHECK='TRUE';
      NO_DIR_CHECK='TRUE';
      ALLOW_CONNECT='TRUE';
    'VSS'<505>:
      PIN_NUMBER='(0,0,0,0,0,0,0,0,0,0,0,0,0,0,0,0,0,0,0,0,0,0,0,0,0,0,CC64,0,0,0)';
      PINUSE='GROUND';
      NO_LOAD_CHECK='Both';
      NO_IO_CHECK='Both';
      NO_ASSERT_CHECK='TRUE';
      NO_DIR_CHECK='TRUE';
      ALLOW_CONNECT='TRUE';
    'VSS'<504>:
      PIN_NUMBER='(0,0,0,0,0,0,0,0,0,0,0,0,0,0,0,0,0,0,0,0,0,0,0,0,0,0,CC72,0,0,0)';
      PINUSE='GROUND';
      NO_LOAD_CHECK='Both';
      NO_IO_CHECK='Both';
      NO_ASSERT_CHECK='TRUE';
      NO_DIR_CHECK='TRUE';
      ALLOW_CONNECT='TRUE';
    'VSS'<503>:
      PIN_NUMBER='(0,0,0,0,0,0,0,0,0,0,0,0,0,0,0,0,0,0,0,0,0,0,0,0,0,0,CC74,0,0,0)';
      PINUSE='GROUND';
      NO_LOAD_CHECK='Both';
      NO_IO_CHECK='Both';
      NO_ASSERT_CHECK='TRUE';
      NO_DIR_CHECK='TRUE';
      ALLOW_CONNECT='TRUE';
    'VSS'<502>:
      PIN_NUMBER='(0,0,0,0,0,0,0,0,0,0,0,0,0,0,0,0,0,0,0,0,0,0,0,0,0,0,CC76,0,0,0)';
      PINUSE='GROUND';
      NO_LOAD_CHECK='Both';
      NO_IO_CHECK='Both';
      NO_ASSERT_CHECK='TRUE';
      NO_DIR_CHECK='TRUE';
      ALLOW_CONNECT='TRUE';
    'VSS'<501>:
      PIN_NUMBER='(0,0,0,0,0,0,0,0,0,0,0,0,0,0,0,0,0,0,0,0,0,0,0,0,0,0,CC78,0,0,0)';
      PINUSE='GROUND';
      NO_LOAD_CHECK='Both';
      NO_IO_CHECK='Both';
      NO_ASSERT_CHECK='TRUE';
      NO_DIR_CHECK='TRUE';
      ALLOW_CONNECT='TRUE';
    'VSS'<500>:
      PIN_NUMBER='(0,0,0,0,0,0,0,0,0,0,0,0,0,0,0,0,0,0,0,0,0,0,0,0,0,0,CC80,0,0,0)';
      PINUSE='GROUND';
      NO_LOAD_CHECK='Both';
      NO_IO_CHECK='Both';
      NO_ASSERT_CHECK='TRUE';
      NO_DIR_CHECK='TRUE';
      ALLOW_CONNECT='TRUE';
    'VSS'<499>:
      PIN_NUMBER='(0,0,0,0,0,0,0,0,0,0,0,0,0,0,0,0,0,0,0,0,0,0,0,0,0,0,CC82,0,0,0)';
      PINUSE='GROUND';
      NO_LOAD_CHECK='Both';
      NO_IO_CHECK='Both';
      NO_ASSERT_CHECK='TRUE';
      NO_DIR_CHECK='TRUE';
      ALLOW_CONNECT='TRUE';
    'VSS'<498>:
      PIN_NUMBER='(0,0,0,0,0,0,0,0,0,0,0,0,0,0,0,0,0,0,0,0,0,0,0,0,0,0,CD5,0,0,0)';
      PINUSE='GROUND';
      NO_LOAD_CHECK='Both';
      NO_IO_CHECK='Both';
      NO_ASSERT_CHECK='TRUE';
      NO_DIR_CHECK='TRUE';
      ALLOW_CONNECT='TRUE';
    'VSS'<497>:
      PIN_NUMBER='(0,0,0,0,0,0,0,0,0,0,0,0,0,0,0,0,0,0,0,0,0,0,0,0,0,0,CD13,0,0,0)';
      PINUSE='GROUND';
      NO_LOAD_CHECK='Both';
      NO_IO_CHECK='Both';
      NO_ASSERT_CHECK='TRUE';
      NO_DIR_CHECK='TRUE';
      ALLOW_CONNECT='TRUE';
    'VSS'<496>:
      PIN_NUMBER='(0,0,0,0,0,0,0,0,0,0,0,0,0,0,0,0,0,0,0,0,0,0,0,0,0,0,CD63,0,0,0)';
      PINUSE='GROUND';
      NO_LOAD_CHECK='Both';
      NO_IO_CHECK='Both';
      NO_ASSERT_CHECK='TRUE';
      NO_DIR_CHECK='TRUE';
      ALLOW_CONNECT='TRUE';
    'VSS'<495>:
      PIN_NUMBER='(0,0,0,0,0,0,0,0,0,0,0,0,0,0,0,0,0,0,0,0,0,0,0,0,0,0,CD73,0,0,0)';
      PINUSE='GROUND';
      NO_LOAD_CHECK='Both';
      NO_IO_CHECK='Both';
      NO_ASSERT_CHECK='TRUE';
      NO_DIR_CHECK='TRUE';
      ALLOW_CONNECT='TRUE';
    'VSS'<494>:
      PIN_NUMBER='(0,0,0,0,0,0,0,0,0,0,0,0,0,0,0,0,0,0,0,0,0,0,0,0,0,0,CD75,0,0,0)';
      PINUSE='GROUND';
      NO_LOAD_CHECK='Both';
      NO_IO_CHECK='Both';
      NO_ASSERT_CHECK='TRUE';
      NO_DIR_CHECK='TRUE';
      ALLOW_CONNECT='TRUE';
    'VSS'<493>:
      PIN_NUMBER='(0,0,0,0,0,0,0,0,0,0,0,0,0,0,0,0,0,0,0,0,0,0,0,0,0,0,CD77,0,0,0)';
      PINUSE='GROUND';
      NO_LOAD_CHECK='Both';
      NO_IO_CHECK='Both';
      NO_ASSERT_CHECK='TRUE';
      NO_DIR_CHECK='TRUE';
      ALLOW_CONNECT='TRUE';
    'VSS'<492>:
      PIN_NUMBER='(0,0,0,0,0,0,0,0,0,0,0,0,0,0,0,0,0,0,0,0,0,0,0,0,0,0,CD79,0,0,0)';
      PINUSE='GROUND';
      NO_LOAD_CHECK='Both';
      NO_IO_CHECK='Both';
      NO_ASSERT_CHECK='TRUE';
      NO_DIR_CHECK='TRUE';
      ALLOW_CONNECT='TRUE';
    'VSS'<491>:
      PIN_NUMBER='(0,0,0,0,0,0,0,0,0,0,0,0,0,0,0,0,0,0,0,0,0,0,0,0,0,0,CD81,0,0,0)';
      PINUSE='GROUND';
      NO_LOAD_CHECK='Both';
      NO_IO_CHECK='Both';
      NO_ASSERT_CHECK='TRUE';
      NO_DIR_CHECK='TRUE';
      ALLOW_CONNECT='TRUE';
    'VSS'<490>:
      PIN_NUMBER='(0,0,0,0,0,0,0,0,0,0,0,0,0,0,0,0,0,0,0,0,0,0,0,0,0,0,CE10,0,0,0)';
      PINUSE='GROUND';
      NO_LOAD_CHECK='Both';
      NO_IO_CHECK='Both';
      NO_ASSERT_CHECK='TRUE';
      NO_DIR_CHECK='TRUE';
      ALLOW_CONNECT='TRUE';
    'VSS'<489>:
      PIN_NUMBER='(0,0,0,0,0,0,0,0,0,0,0,0,0,0,0,0,0,0,0,0,0,0,0,0,0,0,CE14,0,0,0)';
      PINUSE='GROUND';
      NO_LOAD_CHECK='Both';
      NO_IO_CHECK='Both';
      NO_ASSERT_CHECK='TRUE';
      NO_DIR_CHECK='TRUE';
      ALLOW_CONNECT='TRUE';
    'VSS'<488>:
      PIN_NUMBER='(0,0,0,0,0,0,0,0,0,0,0,0,0,0,0,0,0,0,0,0,0,0,0,0,0,0,CE20,0,0,0)';
      PINUSE='GROUND';
      NO_LOAD_CHECK='Both';
      NO_IO_CHECK='Both';
      NO_ASSERT_CHECK='TRUE';
      NO_DIR_CHECK='TRUE';
      ALLOW_CONNECT='TRUE';
    'VSS'<487>:
      PIN_NUMBER='(0,0,0,0,0,0,0,0,0,0,0,0,0,0,0,0,0,0,0,0,0,0,0,0,0,0,CE26,0,0,0)';
      PINUSE='GROUND';
      NO_LOAD_CHECK='Both';
      NO_IO_CHECK='Both';
      NO_ASSERT_CHECK='TRUE';
      NO_DIR_CHECK='TRUE';
      ALLOW_CONNECT='TRUE';
    'VSS'<486>:
      PIN_NUMBER='(0,0,0,0,0,0,0,0,0,0,0,0,0,0,0,0,0,0,0,0,0,0,0,0,0,0,CE62,0,0,0)';
      PINUSE='GROUND';
      NO_LOAD_CHECK='Both';
      NO_IO_CHECK='Both';
      NO_ASSERT_CHECK='TRUE';
      NO_DIR_CHECK='TRUE';
      ALLOW_CONNECT='TRUE';
    'VSS'<485>:
      PIN_NUMBER='(0,0,0,0,0,0,0,0,0,0,0,0,0,0,0,0,0,0,0,0,0,0,0,0,0,0,CE70,0,0,0)';
      PINUSE='GROUND';
      NO_LOAD_CHECK='Both';
      NO_IO_CHECK='Both';
      NO_ASSERT_CHECK='TRUE';
      NO_DIR_CHECK='TRUE';
      ALLOW_CONNECT='TRUE';
    'VSS'<484>:
      PIN_NUMBER='(0,0,0,0,0,0,0,0,0,0,0,0,0,0,0,0,0,0,0,0,0,0,0,0,0,0,CE82,0,0,0)';
      PINUSE='GROUND';
      NO_LOAD_CHECK='Both';
      NO_IO_CHECK='Both';
      NO_ASSERT_CHECK='TRUE';
      NO_DIR_CHECK='TRUE';
      ALLOW_CONNECT='TRUE';
    'VSS'<483>:
      PIN_NUMBER='(0,0,0,0,0,0,0,0,0,0,0,0,0,0,0,0,0,0,0,0,0,0,0,0,0,0,P53,0,0,0)';
      PINUSE='GROUND';
      NO_LOAD_CHECK='Both';
      NO_IO_CHECK='Both';
      NO_ASSERT_CHECK='TRUE';
      NO_DIR_CHECK='TRUE';
      ALLOW_CONNECT='TRUE';
    'VSS'<482>:
      PIN_NUMBER='(0,0,0,0,0,0,0,0,0,0,0,0,0,0,0,0,0,0,0,0,0,0,0,0,0,0,CF9,0,0,0)';
      PINUSE='GROUND';
      NO_LOAD_CHECK='Both';
      NO_IO_CHECK='Both';
      NO_ASSERT_CHECK='TRUE';
      NO_DIR_CHECK='TRUE';
      ALLOW_CONNECT='TRUE';
    'VSS'<481>:
      PIN_NUMBER='(0,0,0,0,0,0,0,0,0,0,0,0,0,0,0,0,0,0,0,0,0,0,0,0,0,0,CF63,0,0,0)';
      PINUSE='GROUND';
      NO_LOAD_CHECK='Both';
      NO_IO_CHECK='Both';
      NO_ASSERT_CHECK='TRUE';
      NO_DIR_CHECK='TRUE';
      ALLOW_CONNECT='TRUE';
    'VSS'<480>:
      PIN_NUMBER='(0,0,0,0,0,0,0,0,0,0,0,0,0,0,0,0,0,0,0,0,0,0,0,0,0,0,CF69,0,0,0)';
      PINUSE='GROUND';
      NO_LOAD_CHECK='Both';
      NO_IO_CHECK='Both';
      NO_ASSERT_CHECK='TRUE';
      NO_DIR_CHECK='TRUE';
      ALLOW_CONNECT='TRUE';
    'VSS'<479>:
      PIN_NUMBER='(0,0,0,0,0,0,0,0,0,0,0,0,0,0,0,0,0,0,0,0,0,0,0,0,0,0,CF71,0,0,0)';
      PINUSE='GROUND';
      NO_LOAD_CHECK='Both';
      NO_IO_CHECK='Both';
      NO_ASSERT_CHECK='TRUE';
      NO_DIR_CHECK='TRUE';
      ALLOW_CONNECT='TRUE';
    'VSS'<478>:
      PIN_NUMBER='(0,0,0,0,0,0,0,0,0,0,0,0,0,0,0,0,0,0,0,0,0,0,0,0,0,0,CF77,0,0,0)';
      PINUSE='GROUND';
      NO_LOAD_CHECK='Both';
      NO_IO_CHECK='Both';
      NO_ASSERT_CHECK='TRUE';
      NO_DIR_CHECK='TRUE';
      ALLOW_CONNECT='TRUE';
    'VSS'<477>:
      PIN_NUMBER='(0,0,0,0,0,0,0,0,0,0,0,0,0,0,0,0,0,0,0,0,0,0,0,0,0,0,CF83,0,0,0)';
      PINUSE='GROUND';
      NO_LOAD_CHECK='Both';
      NO_IO_CHECK='Both';
      NO_ASSERT_CHECK='TRUE';
      NO_DIR_CHECK='TRUE';
      ALLOW_CONNECT='TRUE';
    'VSS'<476>:
      PIN_NUMBER='(0,0,0,0,0,0,0,0,0,0,0,0,0,0,0,0,0,0,0,0,0,0,0,0,0,0,P51,0,0,0)';
      PINUSE='GROUND';
      NO_LOAD_CHECK='Both';
      NO_IO_CHECK='Both';
      NO_ASSERT_CHECK='TRUE';
      NO_DIR_CHECK='TRUE';
      ALLOW_CONNECT='TRUE';
    'VSS'<475>:
      PIN_NUMBER='(0,0,0,0,0,0,0,0,0,0,0,0,0,0,0,0,0,0,0,0,0,0,0,0,0,0,CG18,0,0,0)';
      PINUSE='GROUND';
      NO_LOAD_CHECK='Both';
      NO_IO_CHECK='Both';
      NO_ASSERT_CHECK='TRUE';
      NO_DIR_CHECK='TRUE';
      ALLOW_CONNECT='TRUE';
    'VSS'<474>:
      PIN_NUMBER='(0,0,0,0,0,0,0,0,0,0,0,0,0,0,0,0,0,0,0,0,0,0,0,0,0,0,CG22,0,0,0)';
      PINUSE='GROUND';
      NO_LOAD_CHECK='Both';
      NO_IO_CHECK='Both';
      NO_ASSERT_CHECK='TRUE';
      NO_DIR_CHECK='TRUE';
      ALLOW_CONNECT='TRUE';
    'VSS'<473>:
      PIN_NUMBER='(0,0,0,0,0,0,0,0,0,0,0,0,0,0,0,0,0,0,0,0,0,0,0,0,0,0,CG62,0,0,0)';
      PINUSE='GROUND';
      NO_LOAD_CHECK='Both';
      NO_IO_CHECK='Both';
      NO_ASSERT_CHECK='TRUE';
      NO_DIR_CHECK='TRUE';
      ALLOW_CONNECT='TRUE';
    'VSS'<472>:
      PIN_NUMBER='(0,0,0,0,0,0,0,0,0,0,0,0,0,0,0,0,0,0,0,0,0,0,0,0,0,0,CG68,0,0,0)';
      PINUSE='GROUND';
      NO_LOAD_CHECK='Both';
      NO_IO_CHECK='Both';
      NO_ASSERT_CHECK='TRUE';
      NO_DIR_CHECK='TRUE';
      ALLOW_CONNECT='TRUE';
    'VSS'<471>:
      PIN_NUMBER='(0,0,0,0,0,0,0,0,0,0,0,0,0,0,0,0,0,0,0,0,0,0,0,0,0,0,CG72,0,0,0)';
      PINUSE='GROUND';
      NO_LOAD_CHECK='Both';
      NO_IO_CHECK='Both';
      NO_ASSERT_CHECK='TRUE';
      NO_DIR_CHECK='TRUE';
      ALLOW_CONNECT='TRUE';
    'VSS'<470>:
      PIN_NUMBER='(0,0,0,0,0,0,0,0,0,0,0,0,0,0,0,0,0,0,0,0,0,0,0,0,0,0,CG80,0,0,0)';
      PINUSE='GROUND';
      NO_LOAD_CHECK='Both';
      NO_IO_CHECK='Both';
      NO_ASSERT_CHECK='TRUE';
      NO_DIR_CHECK='TRUE';
      ALLOW_CONNECT='TRUE';
    'VSS'<469>:
      PIN_NUMBER='(0,0,0,0,0,0,0,0,0,0,0,0,0,0,0,0,0,0,0,0,0,0,0,0,0,0,CH1,0,0,0)';
      PINUSE='GROUND';
      NO_LOAD_CHECK='Both';
      NO_IO_CHECK='Both';
      NO_ASSERT_CHECK='TRUE';
      NO_DIR_CHECK='TRUE';
      ALLOW_CONNECT='TRUE';
    'VSS'<468>:
      PIN_NUMBER='(0,0,0,0,0,0,0,0,0,0,0,0,0,0,0,0,0,0,0,0,0,0,0,0,0,0,CH3,0,0,0)';
      PINUSE='GROUND';
      NO_LOAD_CHECK='Both';
      NO_IO_CHECK='Both';
      NO_ASSERT_CHECK='TRUE';
      NO_DIR_CHECK='TRUE';
      ALLOW_CONNECT='TRUE';
    'VSS'<467>:
      PIN_NUMBER='(0,0,0,0,0,0,0,0,0,0,0,0,0,0,0,0,0,0,0,0,0,0,0,0,0,0,CH15,0,0,0)';
      PINUSE='GROUND';
      NO_LOAD_CHECK='Both';
      NO_IO_CHECK='Both';
      NO_ASSERT_CHECK='TRUE';
      NO_DIR_CHECK='TRUE';
      ALLOW_CONNECT='TRUE';
    'VSS'<466>:
      PIN_NUMBER='(0,0,0,0,0,0,0,0,0,0,0,0,0,0,0,0,0,0,0,0,0,0,0,0,0,0,CH19,0,0,0)';
      PINUSE='GROUND';
      NO_LOAD_CHECK='Both';
      NO_IO_CHECK='Both';
      NO_ASSERT_CHECK='TRUE';
      NO_DIR_CHECK='TRUE';
      ALLOW_CONNECT='TRUE';
    'VSS'<465>:
      PIN_NUMBER='(0,0,0,0,0,0,0,0,0,0,0,0,0,0,0,0,0,0,0,0,0,0,0,0,0,0,CH63,0,0,0)';
      PINUSE='GROUND';
      NO_LOAD_CHECK='Both';
      NO_IO_CHECK='Both';
      NO_ASSERT_CHECK='TRUE';
      NO_DIR_CHECK='TRUE';
      ALLOW_CONNECT='TRUE';
    'VSS'<464>:
      PIN_NUMBER='(0,0,0,0,0,0,0,0,0,0,0,0,0,0,0,0,0,0,0,0,0,0,0,0,0,0,CH67,0,0,0)';
      PINUSE='GROUND';
      NO_LOAD_CHECK='Both';
      NO_IO_CHECK='Both';
      NO_ASSERT_CHECK='TRUE';
      NO_DIR_CHECK='TRUE';
      ALLOW_CONNECT='TRUE';
    'VSS'<463>:
      PIN_NUMBER='(0,0,0,0,0,0,0,0,0,0,0,0,0,0,0,0,0,0,0,0,0,0,0,0,0,0,CH73,0,0,0)';
      PINUSE='GROUND';
      NO_LOAD_CHECK='Both';
      NO_IO_CHECK='Both';
      NO_ASSERT_CHECK='TRUE';
      NO_DIR_CHECK='TRUE';
      ALLOW_CONNECT='TRUE';
    'VSS'<462>:
      PIN_NUMBER='(0,0,0,0,0,0,0,0,0,0,0,0,0,0,0,0,0,0,0,0,0,0,0,0,0,0,CH79,0,0,0)';
      PINUSE='GROUND';
      NO_LOAD_CHECK='Both';
      NO_IO_CHECK='Both';
      NO_ASSERT_CHECK='TRUE';
      NO_DIR_CHECK='TRUE';
      ALLOW_CONNECT='TRUE';
    'VSS'<461>:
      PIN_NUMBER='(0,0,0,0,0,0,0,0,0,0,0,0,0,0,0,0,0,0,0,0,0,0,0,0,0,0,CH81,0,0,0)';
      PINUSE='GROUND';
      NO_LOAD_CHECK='Both';
      NO_IO_CHECK='Both';
      NO_ASSERT_CHECK='TRUE';
      NO_DIR_CHECK='TRUE';
      ALLOW_CONNECT='TRUE';
    'VSS'<460>:
      PIN_NUMBER='(0,0,0,0,0,0,0,0,0,0,0,0,0,0,0,0,0,0,0,0,0,0,0,0,0,0,CH83,0,0,0)';
      PINUSE='GROUND';
      NO_LOAD_CHECK='Both';
      NO_IO_CHECK='Both';
      NO_ASSERT_CHECK='TRUE';
      NO_DIR_CHECK='TRUE';
      ALLOW_CONNECT='TRUE';
    'VSS'<459>:
      PIN_NUMBER='(0,0,0,0,0,0,0,0,0,0,0,0,0,0,0,0,0,0,0,0,0,0,0,0,0,0,CJ2,0,0,0)';
      PINUSE='GROUND';
      NO_LOAD_CHECK='Both';
      NO_IO_CHECK='Both';
      NO_ASSERT_CHECK='TRUE';
      NO_DIR_CHECK='TRUE';
      ALLOW_CONNECT='TRUE';
    'VSS'<458>:
      PIN_NUMBER='(0,0,0,0,0,0,0,0,0,0,0,0,0,0,0,0,0,0,0,0,0,0,0,0,0,0,CJ6,0,0,0)';
      PINUSE='GROUND';
      NO_LOAD_CHECK='Both';
      NO_IO_CHECK='Both';
      NO_ASSERT_CHECK='TRUE';
      NO_DIR_CHECK='TRUE';
      ALLOW_CONNECT='TRUE';
    'VSS'<457>:
      PIN_NUMBER='(0,0,0,0,0,0,0,0,0,0,0,0,0,0,0,0,0,0,0,0,0,0,0,0,0,0,CJ8,0,0,0)';
      PINUSE='GROUND';
      NO_LOAD_CHECK='Both';
      NO_IO_CHECK='Both';
      NO_ASSERT_CHECK='TRUE';
      NO_DIR_CHECK='TRUE';
      ALLOW_CONNECT='TRUE';
    'VSS'<456>:
      PIN_NUMBER='(0,0,0,0,0,0,0,0,0,0,0,0,0,0,0,0,0,0,0,0,0,0,0,0,0,0,CJ10,0,0,0)';
      PINUSE='GROUND';
      NO_LOAD_CHECK='Both';
      NO_IO_CHECK='Both';
      NO_ASSERT_CHECK='TRUE';
      NO_DIR_CHECK='TRUE';
      ALLOW_CONNECT='TRUE';
    'VSS'<455>:
      PIN_NUMBER='(0,0,0,0,0,0,0,0,0,0,0,0,0,0,0,0,0,0,0,0,0,0,0,0,0,0,CJ12,0,0,0)';
      PINUSE='GROUND';
      NO_LOAD_CHECK='Both';
      NO_IO_CHECK='Both';
      NO_ASSERT_CHECK='TRUE';
      NO_DIR_CHECK='TRUE';
      ALLOW_CONNECT='TRUE';
    'VSS'<454>:
      PIN_NUMBER='(0,0,0,0,0,0,0,0,0,0,0,0,0,0,0,0,0,0,0,0,0,0,0,0,0,0,P49,0,0,0)';
      PINUSE='GROUND';
      NO_LOAD_CHECK='Both';
      NO_IO_CHECK='Both';
      NO_ASSERT_CHECK='TRUE';
      NO_DIR_CHECK='TRUE';
      ALLOW_CONNECT='TRUE';
    'VSS'<453>:
      PIN_NUMBER='(0,0,0,0,0,0,0,0,0,0,0,0,0,0,0,0,0,0,0,0,0,0,0,0,0,0,0,P47,0,0)';
      PINUSE='GROUND';
      NO_LOAD_CHECK='Both';
      NO_IO_CHECK='Both';
      NO_ASSERT_CHECK='TRUE';
      NO_DIR_CHECK='TRUE';
      ALLOW_CONNECT='TRUE';
    'VSS'<452>:
      PIN_NUMBER='(0,0,0,0,0,0,0,0,0,0,0,0,0,0,0,0,0,0,0,0,0,0,0,0,0,0,0,CJ62,0,0)';
      PINUSE='GROUND';
      NO_LOAD_CHECK='Both';
      NO_IO_CHECK='Both';
      NO_ASSERT_CHECK='TRUE';
      NO_DIR_CHECK='TRUE';
      ALLOW_CONNECT='TRUE';
    'VSS'<451>:
      PIN_NUMBER='(0,0,0,0,0,0,0,0,0,0,0,0,0,0,0,0,0,0,0,0,0,0,0,0,0,0,0,CJ74,0,0)';
      PINUSE='GROUND';
      NO_LOAD_CHECK='Both';
      NO_IO_CHECK='Both';
      NO_ASSERT_CHECK='TRUE';
      NO_DIR_CHECK='TRUE';
      ALLOW_CONNECT='TRUE';
    'VSS'<450>:
      PIN_NUMBER='(0,0,0,0,0,0,0,0,0,0,0,0,0,0,0,0,0,0,0,0,0,0,0,0,0,0,0,CJ76,0,0)';
      PINUSE='GROUND';
      NO_LOAD_CHECK='Both';
      NO_IO_CHECK='Both';
      NO_ASSERT_CHECK='TRUE';
      NO_DIR_CHECK='TRUE';
      ALLOW_CONNECT='TRUE';
    'VSS'<449>:
      PIN_NUMBER='(0,0,0,0,0,0,0,0,0,0,0,0,0,0,0,0,0,0,0,0,0,0,0,0,0,0,0,CJ78,0,0)';
      PINUSE='GROUND';
      NO_LOAD_CHECK='Both';
      NO_IO_CHECK='Both';
      NO_ASSERT_CHECK='TRUE';
      NO_DIR_CHECK='TRUE';
      ALLOW_CONNECT='TRUE';
    'VSS'<448>:
      PIN_NUMBER='(0,0,0,0,0,0,0,0,0,0,0,0,0,0,0,0,0,0,0,0,0,0,0,0,0,0,0,CJ82,0,0)';
      PINUSE='GROUND';
      NO_LOAD_CHECK='Both';
      NO_IO_CHECK='Both';
      NO_ASSERT_CHECK='TRUE';
      NO_DIR_CHECK='TRUE';
      ALLOW_CONNECT='TRUE';
    'VSS'<447>:
      PIN_NUMBER='(0,0,0,0,0,0,0,0,0,0,0,0,0,0,0,0,0,0,0,0,0,0,0,0,0,0,0,CJ84,0,0)';
      PINUSE='GROUND';
      NO_LOAD_CHECK='Both';
      NO_IO_CHECK='Both';
      NO_ASSERT_CHECK='TRUE';
      NO_DIR_CHECK='TRUE';
      ALLOW_CONNECT='TRUE';
    'VSS'<446>:
      PIN_NUMBER='(0,0,0,0,0,0,0,0,0,0,0,0,0,0,0,0,0,0,0,0,0,0,0,0,0,0,0,CJ86,0,0)';
      PINUSE='GROUND';
      NO_LOAD_CHECK='Both';
      NO_IO_CHECK='Both';
      NO_ASSERT_CHECK='TRUE';
      NO_DIR_CHECK='TRUE';
      ALLOW_CONNECT='TRUE';
    'VSS'<445>:
      PIN_NUMBER='(0,0,0,0,0,0,0,0,0,0,0,0,0,0,0,0,0,0,0,0,0,0,0,0,0,0,0,CK11,0,0)';
      PINUSE='GROUND';
      NO_LOAD_CHECK='Both';
      NO_IO_CHECK='Both';
      NO_ASSERT_CHECK='TRUE';
      NO_DIR_CHECK='TRUE';
      ALLOW_CONNECT='TRUE';
    'VSS'<444>:
      PIN_NUMBER='(0,0,0,0,0,0,0,0,0,0,0,0,0,0,0,0,0,0,0,0,0,0,0,0,0,0,0,CK15,0,0)';
      PINUSE='GROUND';
      NO_LOAD_CHECK='Both';
      NO_IO_CHECK='Both';
      NO_ASSERT_CHECK='TRUE';
      NO_DIR_CHECK='TRUE';
      ALLOW_CONNECT='TRUE';
    'VSS'<443>:
      PIN_NUMBER='(0,0,0,0,0,0,0,0,0,0,0,0,0,0,0,0,0,0,0,0,0,0,0,0,0,0,0,CK21,0,0)';
      PINUSE='GROUND';
      NO_LOAD_CHECK='Both';
      NO_IO_CHECK='Both';
      NO_ASSERT_CHECK='TRUE';
      NO_DIR_CHECK='TRUE';
      ALLOW_CONNECT='TRUE';
    'VSS'<442>:
      PIN_NUMBER='(0,0,0,0,0,0,0,0,0,0,0,0,0,0,0,0,0,0,0,0,0,0,0,0,0,0,0,CK27,0,0)';
      PINUSE='GROUND';
      NO_LOAD_CHECK='Both';
      NO_IO_CHECK='Both';
      NO_ASSERT_CHECK='TRUE';
      NO_DIR_CHECK='TRUE';
      ALLOW_CONNECT='TRUE';
    'VSS'<441>:
      PIN_NUMBER='(0,0,0,0,0,0,0,0,0,0,0,0,0,0,0,0,0,0,0,0,0,0,0,0,0,0,0,CK63,0,0)';
      PINUSE='GROUND';
      NO_LOAD_CHECK='Both';
      NO_IO_CHECK='Both';
      NO_ASSERT_CHECK='TRUE';
      NO_DIR_CHECK='TRUE';
      ALLOW_CONNECT='TRUE';
    'VSS'<440>:
      PIN_NUMBER='(0,0,0,0,0,0,0,0,0,0,0,0,0,0,0,0,0,0,0,0,0,0,0,0,0,0,0,CK65,0,0)';
      PINUSE='GROUND';
      NO_LOAD_CHECK='Both';
      NO_IO_CHECK='Both';
      NO_ASSERT_CHECK='TRUE';
      NO_DIR_CHECK='TRUE';
      ALLOW_CONNECT='TRUE';
    'VSS'<439>:
      PIN_NUMBER='(0,0,0,0,0,0,0,0,0,0,0,0,0,0,0,0,0,0,0,0,0,0,0,0,0,0,0,CK67,0,0)';
      PINUSE='GROUND';
      NO_LOAD_CHECK='Both';
      NO_IO_CHECK='Both';
      NO_ASSERT_CHECK='TRUE';
      NO_DIR_CHECK='TRUE';
      ALLOW_CONNECT='TRUE';
    'VSS'<438>:
      PIN_NUMBER='(0,0,0,0,0,0,0,0,0,0,0,0,0,0,0,0,0,0,0,0,0,0,0,0,0,0,0,CK69,0,0)';
      PINUSE='GROUND';
      NO_LOAD_CHECK='Both';
      NO_IO_CHECK='Both';
      NO_ASSERT_CHECK='TRUE';
      NO_DIR_CHECK='TRUE';
      ALLOW_CONNECT='TRUE';
    'VSS'<437>:
      PIN_NUMBER='(0,0,0,0,0,0,0,0,0,0,0,0,0,0,0,0,0,0,0,0,0,0,0,0,0,0,0,CK71,0,0)';
      PINUSE='GROUND';
      NO_LOAD_CHECK='Both';
      NO_IO_CHECK='Both';
      NO_ASSERT_CHECK='TRUE';
      NO_DIR_CHECK='TRUE';
      ALLOW_CONNECT='TRUE';
    'VSS'<436>:
      PIN_NUMBER='(0,0,0,0,0,0,0,0,0,0,0,0,0,0,0,0,0,0,0,0,0,0,0,0,0,0,0,CK73,0,0)';
      PINUSE='GROUND';
      NO_LOAD_CHECK='Both';
      NO_IO_CHECK='Both';
      NO_ASSERT_CHECK='TRUE';
      NO_DIR_CHECK='TRUE';
      ALLOW_CONNECT='TRUE';
    'VSS'<435>:
      PIN_NUMBER='(0,0,0,0,0,0,0,0,0,0,0,0,0,0,0,0,0,0,0,0,0,0,0,0,0,0,0,CK75,0,0)';
      PINUSE='GROUND';
      NO_LOAD_CHECK='Both';
      NO_IO_CHECK='Both';
      NO_ASSERT_CHECK='TRUE';
      NO_DIR_CHECK='TRUE';
      ALLOW_CONNECT='TRUE';
    'VSS'<434>:
      PIN_NUMBER='(0,0,0,0,0,0,0,0,0,0,0,0,0,0,0,0,0,0,0,0,0,0,0,0,0,0,0,CK83,0,0)';
      PINUSE='GROUND';
      NO_LOAD_CHECK='Both';
      NO_IO_CHECK='Both';
      NO_ASSERT_CHECK='TRUE';
      NO_DIR_CHECK='TRUE';
      ALLOW_CONNECT='TRUE';
    'VSS'<433>:
      PIN_NUMBER='(0,0,0,0,0,0,0,0,0,0,0,0,0,0,0,0,0,0,0,0,0,0,0,0,0,0,0,CK85,0,0)';
      PINUSE='GROUND';
      NO_LOAD_CHECK='Both';
      NO_IO_CHECK='Both';
      NO_ASSERT_CHECK='TRUE';
      NO_DIR_CHECK='TRUE';
      ALLOW_CONNECT='TRUE';
    'VSS'<432>:
      PIN_NUMBER='(0,0,0,0,0,0,0,0,0,0,0,0,0,0,0,0,0,0,0,0,0,0,0,0,0,0,0,CL8,0,0)';
      PINUSE='GROUND';
      NO_LOAD_CHECK='Both';
      NO_IO_CHECK='Both';
      NO_ASSERT_CHECK='TRUE';
      NO_DIR_CHECK='TRUE';
      ALLOW_CONNECT='TRUE';
    'VSS'<431>:
      PIN_NUMBER='(0,0,0,0,0,0,0,0,0,0,0,0,0,0,0,0,0,0,0,0,0,0,0,0,0,0,0,CL14,0,0)';
      PINUSE='GROUND';
      NO_LOAD_CHECK='Both';
      NO_IO_CHECK='Both';
      NO_ASSERT_CHECK='TRUE';
      NO_DIR_CHECK='TRUE';
      ALLOW_CONNECT='TRUE';
    'VSS'<430>:
      PIN_NUMBER='(0,0,0,0,0,0,0,0,0,0,0,0,0,0,0,0,0,0,0,0,0,0,0,0,0,0,0,CL18,0,0)';
      PINUSE='GROUND';
      NO_LOAD_CHECK='Both';
      NO_IO_CHECK='Both';
      NO_ASSERT_CHECK='TRUE';
      NO_DIR_CHECK='TRUE';
      ALLOW_CONNECT='TRUE';
    'VSS'<429>:
      PIN_NUMBER='(0,0,0,0,0,0,0,0,0,0,0,0,0,0,0,0,0,0,0,0,0,0,0,0,0,0,0,P45,0,0)';
      PINUSE='GROUND';
      NO_LOAD_CHECK='Both';
      NO_IO_CHECK='Both';
      NO_ASSERT_CHECK='TRUE';
      NO_DIR_CHECK='TRUE';
      ALLOW_CONNECT='TRUE';
    'VSS'<428>:
      PIN_NUMBER='(0,0,0,0,0,0,0,0,0,0,0,0,0,0,0,0,0,0,0,0,0,0,0,0,0,0,0,H63,0,0)';
      PINUSE='GROUND';
      NO_LOAD_CHECK='Both';
      NO_IO_CHECK='Both';
      NO_ASSERT_CHECK='TRUE';
      NO_DIR_CHECK='TRUE';
      ALLOW_CONNECT='TRUE';
    'VSS'<427>:
      PIN_NUMBER='(0,0,0,0,0,0,0,0,0,0,0,0,0,0,0,0,0,0,0,0,0,0,0,0,0,0,0,CL62,0,0)';
      PINUSE='GROUND';
      NO_LOAD_CHECK='Both';
      NO_IO_CHECK='Both';
      NO_ASSERT_CHECK='TRUE';
      NO_DIR_CHECK='TRUE';
      ALLOW_CONNECT='TRUE';
    'VSS'<426>:
      PIN_NUMBER='(0,0,0,0,0,0,0,0,0,0,0,0,0,0,0,0,0,0,0,0,0,0,0,0,0,0,0,CL64,0,0)';
      PINUSE='GROUND';
      NO_LOAD_CHECK='Both';
      NO_IO_CHECK='Both';
      NO_ASSERT_CHECK='TRUE';
      NO_DIR_CHECK='TRUE';
      ALLOW_CONNECT='TRUE';
    'VSS'<425>:
      PIN_NUMBER='(0,0,0,0,0,0,0,0,0,0,0,0,0,0,0,0,0,0,0,0,0,0,0,0,0,0,0,CL66,0,0)';
      PINUSE='GROUND';
      NO_LOAD_CHECK='Both';
      NO_IO_CHECK='Both';
      NO_ASSERT_CHECK='TRUE';
      NO_DIR_CHECK='TRUE';
      ALLOW_CONNECT='TRUE';
    'VSS'<424>:
      PIN_NUMBER='(0,0,0,0,0,0,0,0,0,0,0,0,0,0,0,0,0,0,0,0,0,0,0,0,0,0,0,CL74,0,0)';
      PINUSE='GROUND';
      NO_LOAD_CHECK='Both';
      NO_IO_CHECK='Both';
      NO_ASSERT_CHECK='TRUE';
      NO_DIR_CHECK='TRUE';
      ALLOW_CONNECT='TRUE';
    'VSS'<423>:
      PIN_NUMBER='(0,0,0,0,0,0,0,0,0,0,0,0,0,0,0,0,0,0,0,0,0,0,0,0,0,0,0,CL76,0,0)';
      PINUSE='GROUND';
      NO_LOAD_CHECK='Both';
      NO_IO_CHECK='Both';
      NO_ASSERT_CHECK='TRUE';
      NO_DIR_CHECK='TRUE';
      ALLOW_CONNECT='TRUE';
    'VSS'<422>:
      PIN_NUMBER='(0,0,0,0,0,0,0,0,0,0,0,0,0,0,0,0,0,0,0,0,0,0,0,0,0,0,0,CL78,0,0)';
      PINUSE='GROUND';
      NO_LOAD_CHECK='Both';
      NO_IO_CHECK='Both';
      NO_ASSERT_CHECK='TRUE';
      NO_DIR_CHECK='TRUE';
      ALLOW_CONNECT='TRUE';
    'VSS'<421>:
      PIN_NUMBER='(0,0,0,0,0,0,0,0,0,0,0,0,0,0,0,0,0,0,0,0,0,0,0,0,0,0,0,CL80,0,0)';
      PINUSE='GROUND';
      NO_LOAD_CHECK='Both';
      NO_IO_CHECK='Both';
      NO_ASSERT_CHECK='TRUE';
      NO_DIR_CHECK='TRUE';
      ALLOW_CONNECT='TRUE';
    'VSS'<420>:
      PIN_NUMBER='(0,0,0,0,0,0,0,0,0,0,0,0,0,0,0,0,0,0,0,0,0,0,0,0,0,0,0,CM19,0,0)';
      PINUSE='GROUND';
      NO_LOAD_CHECK='Both';
      NO_IO_CHECK='Both';
      NO_ASSERT_CHECK='TRUE';
      NO_DIR_CHECK='TRUE';
      ALLOW_CONNECT='TRUE';
    'VSS'<419>:
      PIN_NUMBER='(0,0,0,0,0,0,0,0,0,0,0,0,0,0,0,0,0,0,0,0,0,0,0,0,0,0,0,CM29,0,0)';
      PINUSE='GROUND';
      NO_LOAD_CHECK='Both';
      NO_IO_CHECK='Both';
      NO_ASSERT_CHECK='TRUE';
      NO_DIR_CHECK='TRUE';
      ALLOW_CONNECT='TRUE';
    'VSS'<418>:
      PIN_NUMBER='(0,0,0,0,0,0,0,0,0,0,0,0,0,0,0,0,0,0,0,0,0,0,0,0,0,0,0,CM5,0,0)';
      PINUSE='GROUND';
      NO_LOAD_CHECK='Both';
      NO_IO_CHECK='Both';
      NO_ASSERT_CHECK='TRUE';
      NO_DIR_CHECK='TRUE';
      ALLOW_CONNECT='TRUE';
    'VSS'<417>:
      PIN_NUMBER='(0,0,0,0,0,0,0,0,0,0,0,0,0,0,0,0,0,0,0,0,0,0,0,0,0,0,0,CM31,0,0)';
      PINUSE='GROUND';
      NO_LOAD_CHECK='Both';
      NO_IO_CHECK='Both';
      NO_ASSERT_CHECK='TRUE';
      NO_DIR_CHECK='TRUE';
      ALLOW_CONNECT='TRUE';
    'VSS'<416>:
      PIN_NUMBER='(0,0,0,0,0,0,0,0,0,0,0,0,0,0,0,0,0,0,0,0,0,0,0,0,0,0,0,CM61,0,0)';
      PINUSE='GROUND';
      NO_LOAD_CHECK='Both';
      NO_IO_CHECK='Both';
      NO_ASSERT_CHECK='TRUE';
      NO_DIR_CHECK='TRUE';
      ALLOW_CONNECT='TRUE';
    'VSS'<415>:
      PIN_NUMBER='(0,0,0,0,0,0,0,0,0,0,0,0,0,0,0,0,0,0,0,0,0,0,0,0,0,0,0,CM63,0,0)';
      PINUSE='GROUND';
      NO_LOAD_CHECK='Both';
      NO_IO_CHECK='Both';
      NO_ASSERT_CHECK='TRUE';
      NO_DIR_CHECK='TRUE';
      ALLOW_CONNECT='TRUE';
    'VSS'<414>:
      PIN_NUMBER='(0,0,0,0,0,0,0,0,0,0,0,0,0,0,0,0,0,0,0,0,0,0,0,0,0,0,0,CM67,0,0)';
      PINUSE='GROUND';
      NO_LOAD_CHECK='Both';
      NO_IO_CHECK='Both';
      NO_ASSERT_CHECK='TRUE';
      NO_DIR_CHECK='TRUE';
      ALLOW_CONNECT='TRUE';
    'VSS'<413>:
      PIN_NUMBER='(0,0,0,0,0,0,0,0,0,0,0,0,0,0,0,0,0,0,0,0,0,0,0,0,0,0,0,CM73,0,0)';
      PINUSE='GROUND';
      NO_LOAD_CHECK='Both';
      NO_IO_CHECK='Both';
      NO_ASSERT_CHECK='TRUE';
      NO_DIR_CHECK='TRUE';
      ALLOW_CONNECT='TRUE';
    'VSS'<412>:
      PIN_NUMBER='(0,0,0,0,0,0,0,0,0,0,0,0,0,0,0,0,0,0,0,0,0,0,0,0,0,0,0,CM77,0,0)';
      PINUSE='GROUND';
      NO_LOAD_CHECK='Both';
      NO_IO_CHECK='Both';
      NO_ASSERT_CHECK='TRUE';
      NO_DIR_CHECK='TRUE';
      ALLOW_CONNECT='TRUE';
    'VSS'<411>:
      PIN_NUMBER='(0,0,0,0,0,0,0,0,0,0,0,0,0,0,0,0,0,0,0,0,0,0,0,0,0,0,0,CM83,0,0)';
      PINUSE='GROUND';
      NO_LOAD_CHECK='Both';
      NO_IO_CHECK='Both';
      NO_ASSERT_CHECK='TRUE';
      NO_DIR_CHECK='TRUE';
      ALLOW_CONNECT='TRUE';
    'VSS'<410>:
      PIN_NUMBER='(0,0,0,0,0,0,0,0,0,0,0,0,0,0,0,0,0,0,0,0,0,0,0,0,0,0,0,CM85,0,0)';
      PINUSE='GROUND';
      NO_LOAD_CHECK='Both';
      NO_IO_CHECK='Both';
      NO_ASSERT_CHECK='TRUE';
      NO_DIR_CHECK='TRUE';
      ALLOW_CONNECT='TRUE';
    'VSS'<409>:
      PIN_NUMBER='(0,0,0,0,0,0,0,0,0,0,0,0,0,0,0,0,0,0,0,0,0,0,0,0,0,0,0,CN2,0,0)';
      PINUSE='GROUND';
      NO_LOAD_CHECK='Both';
      NO_IO_CHECK='Both';
      NO_ASSERT_CHECK='TRUE';
      NO_DIR_CHECK='TRUE';
      ALLOW_CONNECT='TRUE';
    'VSS'<408>:
      PIN_NUMBER='(0,0,0,0,0,0,0,0,0,0,0,0,0,0,0,0,0,0,0,0,0,0,0,0,0,0,0,CN12,0,0)';
      PINUSE='GROUND';
      NO_LOAD_CHECK='Both';
      NO_IO_CHECK='Both';
      NO_ASSERT_CHECK='TRUE';
      NO_DIR_CHECK='TRUE';
      ALLOW_CONNECT='TRUE';
    'VSS'<407>:
      PIN_NUMBER='(0,0,0,0,0,0,0,0,0,0,0,0,0,0,0,0,0,0,0,0,0,0,0,0,0,0,0,H61,0,0)';
      PINUSE='GROUND';
      NO_LOAD_CHECK='Both';
      NO_IO_CHECK='Both';
      NO_ASSERT_CHECK='TRUE';
      NO_DIR_CHECK='TRUE';
      ALLOW_CONNECT='TRUE';
    'VSS'<406>:
      PIN_NUMBER='(0,0,0,0,0,0,0,0,0,0,0,0,0,0,0,0,0,0,0,0,0,0,0,0,0,0,0,CN26,0,0)';
      PINUSE='GROUND';
      NO_LOAD_CHECK='Both';
      NO_IO_CHECK='Both';
      NO_ASSERT_CHECK='TRUE';
      NO_DIR_CHECK='TRUE';
      ALLOW_CONNECT='TRUE';
    'VSS'<405>:
      PIN_NUMBER='(0,0,0,0,0,0,0,0,0,0,0,0,0,0,0,0,0,0,0,0,0,0,0,0,0,0,0,CN32,0,0)';
      PINUSE='GROUND';
      NO_LOAD_CHECK='Both';
      NO_IO_CHECK='Both';
      NO_ASSERT_CHECK='TRUE';
      NO_DIR_CHECK='TRUE';
      ALLOW_CONNECT='TRUE';
    'VSS'<404>:
      PIN_NUMBER='(0,0,0,0,0,0,0,0,0,0,0,0,0,0,0,0,0,0,0,0,0,0,0,0,0,0,0,CN60,0,0)';
      PINUSE='GROUND';
      NO_LOAD_CHECK='Both';
      NO_IO_CHECK='Both';
      NO_ASSERT_CHECK='TRUE';
      NO_DIR_CHECK='TRUE';
      ALLOW_CONNECT='TRUE';
    'VSS'<403>:
      PIN_NUMBER='(0,0,0,0,0,0,0,0,0,0,0,0,0,0,0,0,0,0,0,0,0,0,0,0,0,0,0,CN62,0,0)';
      PINUSE='GROUND';
      NO_LOAD_CHECK='Both';
      NO_IO_CHECK='Both';
      NO_ASSERT_CHECK='TRUE';
      NO_DIR_CHECK='TRUE';
      ALLOW_CONNECT='TRUE';
    'VSS'<402>:
      PIN_NUMBER='(0,0,0,0,0,0,0,0,0,0,0,0,0,0,0,0,0,0,0,0,0,0,0,0,0,0,0,CN68,0,0)';
      PINUSE='GROUND';
      NO_LOAD_CHECK='Both';
      NO_IO_CHECK='Both';
      NO_ASSERT_CHECK='TRUE';
      NO_DIR_CHECK='TRUE';
      ALLOW_CONNECT='TRUE';
    'VSS'<401>:
      PIN_NUMBER='(0,0,0,0,0,0,0,0,0,0,0,0,0,0,0,0,0,0,0,0,0,0,0,0,0,0,0,CN78,0,0)';
      PINUSE='GROUND';
      NO_LOAD_CHECK='Both';
      NO_IO_CHECK='Both';
      NO_ASSERT_CHECK='TRUE';
      NO_DIR_CHECK='TRUE';
      ALLOW_CONNECT='TRUE';
    'VSS'<400>:
      PIN_NUMBER='(0,0,0,0,0,0,0,0,0,0,0,0,0,0,0,0,0,0,0,0,0,0,0,0,0,0,0,CP1,0,0)';
      PINUSE='GROUND';
      NO_LOAD_CHECK='Both';
      NO_IO_CHECK='Both';
      NO_ASSERT_CHECK='TRUE';
      NO_DIR_CHECK='TRUE';
      ALLOW_CONNECT='TRUE';
    'VSS'<399>:
      PIN_NUMBER='(0,0,0,0,0,0,0,0,0,0,0,0,0,0,0,0,0,0,0,0,0,0,0,0,0,0,0,H59,0,0)';
      PINUSE='GROUND';
      NO_LOAD_CHECK='Both';
      NO_IO_CHECK='Both';
      NO_ASSERT_CHECK='TRUE';
      NO_DIR_CHECK='TRUE';
      ALLOW_CONNECT='TRUE';
    'VSS'<398>:
      PIN_NUMBER='(0,0,0,0,0,0,0,0,0,0,0,0,0,0,0,0,0,0,0,0,0,0,0,0,0,0,0,CP25,0,0)';
      PINUSE='GROUND';
      NO_LOAD_CHECK='Both';
      NO_IO_CHECK='Both';
      NO_ASSERT_CHECK='TRUE';
      NO_DIR_CHECK='TRUE';
      ALLOW_CONNECT='TRUE';
    'VSS'<397>:
      PIN_NUMBER='(0,0,0,0,0,0,0,0,0,0,0,0,0,0,0,0,0,0,0,0,0,0,0,0,0,0,0,CP59,0,0)';
      PINUSE='GROUND';
      NO_LOAD_CHECK='Both';
      NO_IO_CHECK='Both';
      NO_ASSERT_CHECK='TRUE';
      NO_DIR_CHECK='TRUE';
      ALLOW_CONNECT='TRUE';
    'VSS'<396>:
      PIN_NUMBER='(0,0,0,0,0,0,0,0,0,0,0,0,0,0,0,0,0,0,0,0,0,0,0,0,0,0,0,CP69,0,0)';
      PINUSE='GROUND';
      NO_LOAD_CHECK='Both';
      NO_IO_CHECK='Both';
      NO_ASSERT_CHECK='TRUE';
      NO_DIR_CHECK='TRUE';
      ALLOW_CONNECT='TRUE';
    'VSS'<395>:
      PIN_NUMBER='(0,0,0,0,0,0,0,0,0,0,0,0,0,0,0,0,0,0,0,0,0,0,0,0,0,0,0,CP73,0,0)';
      PINUSE='GROUND';
      NO_LOAD_CHECK='Both';
      NO_IO_CHECK='Both';
      NO_ASSERT_CHECK='TRUE';
      NO_DIR_CHECK='TRUE';
      ALLOW_CONNECT='TRUE';
    'VSS'<394>:
      PIN_NUMBER='(0,0,0,0,0,0,0,0,0,0,0,0,0,0,0,0,0,0,0,0,0,0,0,0,0,0,0,CP75,0,0)';
      PINUSE='GROUND';
      NO_LOAD_CHECK='Both';
      NO_IO_CHECK='Both';
      NO_ASSERT_CHECK='TRUE';
      NO_DIR_CHECK='TRUE';
      ALLOW_CONNECT='TRUE';
    'VSS'<393>:
      PIN_NUMBER='(0,0,0,0,0,0,0,0,0,0,0,0,0,0,0,0,0,0,0,0,0,0,0,0,0,0,0,CP81,0,0)';
      PINUSE='GROUND';
      NO_LOAD_CHECK='Both';
      NO_IO_CHECK='Both';
      NO_ASSERT_CHECK='TRUE';
      NO_DIR_CHECK='TRUE';
      ALLOW_CONNECT='TRUE';
    'VSS'<392>:
      PIN_NUMBER='(0,0,0,0,0,0,0,0,0,0,0,0,0,0,0,0,0,0,0,0,0,0,0,0,0,0,0,CP83,0,0)';
      PINUSE='GROUND';
      NO_LOAD_CHECK='Both';
      NO_IO_CHECK='Both';
      NO_ASSERT_CHECK='TRUE';
      NO_DIR_CHECK='TRUE';
      ALLOW_CONNECT='TRUE';
    'VSS'<391>:
      PIN_NUMBER='(0,0,0,0,0,0,0,0,0,0,0,0,0,0,0,0,0,0,0,0,0,0,0,0,0,0,0,CR6,0,0)';
      PINUSE='GROUND';
      NO_LOAD_CHECK='Both';
      NO_IO_CHECK='Both';
      NO_ASSERT_CHECK='TRUE';
      NO_DIR_CHECK='TRUE';
      ALLOW_CONNECT='TRUE';
    'VSS'<390>:
      PIN_NUMBER='(0,0,0,0,0,0,0,0,0,0,0,0,0,0,0,0,0,0,0,0,0,0,0,0,0,0,0,CR10,0,0)';
      PINUSE='GROUND';
      NO_LOAD_CHECK='Both';
      NO_IO_CHECK='Both';
      NO_ASSERT_CHECK='TRUE';
      NO_DIR_CHECK='TRUE';
      ALLOW_CONNECT='TRUE';
    'VSS'<389>:
      PIN_NUMBER='(0,0,0,0,0,0,0,0,0,0,0,0,0,0,0,0,0,0,0,0,0,0,0,0,0,0,0,CR22,0,0)';
      PINUSE='GROUND';
      NO_LOAD_CHECK='Both';
      NO_IO_CHECK='Both';
      NO_ASSERT_CHECK='TRUE';
      NO_DIR_CHECK='TRUE';
      ALLOW_CONNECT='TRUE';
    'VSS'<388>:
      PIN_NUMBER='(0,0,0,0,0,0,0,0,0,0,0,0,0,0,0,0,0,0,0,0,0,0,0,0,0,0,0,CR24,0,0)';
      PINUSE='GROUND';
      NO_LOAD_CHECK='Both';
      NO_IO_CHECK='Both';
      NO_ASSERT_CHECK='TRUE';
      NO_DIR_CHECK='TRUE';
      ALLOW_CONNECT='TRUE';
    'VSS'<387>:
      PIN_NUMBER='(0,0,0,0,0,0,0,0,0,0,0,0,0,0,0,0,0,0,0,0,0,0,0,0,0,0,0,CR32,0,0)';
      PINUSE='GROUND';
      NO_LOAD_CHECK='Both';
      NO_IO_CHECK='Both';
      NO_ASSERT_CHECK='TRUE';
      NO_DIR_CHECK='TRUE';
      ALLOW_CONNECT='TRUE';
    'VSS'<386>:
      PIN_NUMBER='(0,0,0,0,0,0,0,0,0,0,0,0,0,0,0,0,0,0,0,0,0,0,0,0,0,0,0,CR58,0,0)';
      PINUSE='GROUND';
      NO_LOAD_CHECK='Both';
      NO_IO_CHECK='Both';
      NO_ASSERT_CHECK='TRUE';
      NO_DIR_CHECK='TRUE';
      ALLOW_CONNECT='TRUE';
    'VSS'<385>:
      PIN_NUMBER='(0,0,0,0,0,0,0,0,0,0,0,0,0,0,0,0,0,0,0,0,0,0,0,0,0,0,0,CR62,0,0)';
      PINUSE='GROUND';
      NO_LOAD_CHECK='Both';
      NO_IO_CHECK='Both';
      NO_ASSERT_CHECK='TRUE';
      NO_DIR_CHECK='TRUE';
      ALLOW_CONNECT='TRUE';
    'VSS'<384>:
      PIN_NUMBER='(0,0,0,0,0,0,0,0,0,0,0,0,0,0,0,0,0,0,0,0,0,0,0,0,0,0,0,CR64,0,0)';
      PINUSE='GROUND';
      NO_LOAD_CHECK='Both';
      NO_IO_CHECK='Both';
      NO_ASSERT_CHECK='TRUE';
      NO_DIR_CHECK='TRUE';
      ALLOW_CONNECT='TRUE';
    'VSS'<383>:
      PIN_NUMBER='(0,0,0,0,0,0,0,0,0,0,0,0,0,0,0,0,0,0,0,0,0,0,0,0,0,0,0,CR66,0,0)';
      PINUSE='GROUND';
      NO_LOAD_CHECK='Both';
      NO_IO_CHECK='Both';
      NO_ASSERT_CHECK='TRUE';
      NO_DIR_CHECK='TRUE';
      ALLOW_CONNECT='TRUE';
    'VSS'<382>:
      PIN_NUMBER='(0,0,0,0,0,0,0,0,0,0,0,0,0,0,0,0,0,0,0,0,0,0,0,0,0,0,0,CR68,0,0)';
      PINUSE='GROUND';
      NO_LOAD_CHECK='Both';
      NO_IO_CHECK='Both';
      NO_ASSERT_CHECK='TRUE';
      NO_DIR_CHECK='TRUE';
      ALLOW_CONNECT='TRUE';
    'VSS'<381>:
      PIN_NUMBER='(0,0,0,0,0,0,0,0,0,0,0,0,0,0,0,0,0,0,0,0,0,0,0,0,0,0,0,CR78,0,0)';
      PINUSE='GROUND';
      NO_LOAD_CHECK='Both';
      NO_IO_CHECK='Both';
      NO_ASSERT_CHECK='TRUE';
      NO_DIR_CHECK='TRUE';
      ALLOW_CONNECT='TRUE';
    'VSS'<380>:
      PIN_NUMBER='(0,0,0,0,0,0,0,0,0,0,0,0,0,0,0,0,0,0,0,0,0,0,0,0,0,0,0,CR86,0,0)';
      PINUSE='GROUND';
      NO_LOAD_CHECK='Both';
      NO_IO_CHECK='Both';
      NO_ASSERT_CHECK='TRUE';
      NO_DIR_CHECK='TRUE';
      ALLOW_CONNECT='TRUE';
    'VSS'<379>:
      PIN_NUMBER='(0,0,0,0,0,0,0,0,0,0,0,0,0,0,0,0,0,0,0,0,0,0,0,0,0,0,0,H57,0,0)';
      PINUSE='GROUND';
      NO_LOAD_CHECK='Both';
      NO_IO_CHECK='Both';
      NO_ASSERT_CHECK='TRUE';
      NO_DIR_CHECK='TRUE';
      ALLOW_CONNECT='TRUE';
    'VSS'<378>:
      PIN_NUMBER='(0,0,0,0,0,0,0,0,0,0,0,0,0,0,0,0,0,0,0,0,0,0,0,0,0,0,0,CT13,0,0)';
      PINUSE='GROUND';
      NO_LOAD_CHECK='Both';
      NO_IO_CHECK='Both';
      NO_ASSERT_CHECK='TRUE';
      NO_DIR_CHECK='TRUE';
      ALLOW_CONNECT='TRUE';
    'VSS'<377>:
      PIN_NUMBER='(0,0,0,0,0,0,0,0,0,0,0,0,0,0,0,0,0,0,0,0,0,0,0,0,0,0,0,CT19,0,0)';
      PINUSE='GROUND';
      NO_LOAD_CHECK='Both';
      NO_IO_CHECK='Both';
      NO_ASSERT_CHECK='TRUE';
      NO_DIR_CHECK='TRUE';
      ALLOW_CONNECT='TRUE';
    'VSS'<376>:
      PIN_NUMBER='(0,0,0,0,0,0,0,0,0,0,0,0,0,0,0,0,0,0,0,0,0,0,0,0,0,0,0,CT27,0,0)';
      PINUSE='GROUND';
      NO_LOAD_CHECK='Both';
      NO_IO_CHECK='Both';
      NO_ASSERT_CHECK='TRUE';
      NO_DIR_CHECK='TRUE';
      ALLOW_CONNECT='TRUE';
    'VSS'<375>:
      PIN_NUMBER='(0,0,0,0,0,0,0,0,0,0,0,0,0,0,0,0,0,0,0,0,0,0,0,0,0,0,0,CT29,0,0)';
      PINUSE='GROUND';
      NO_LOAD_CHECK='Both';
      NO_IO_CHECK='Both';
      NO_ASSERT_CHECK='TRUE';
      NO_DIR_CHECK='TRUE';
      ALLOW_CONNECT='TRUE';
    'VSS'<374>:
      PIN_NUMBER='(0,0,0,0,0,0,0,0,0,0,0,0,0,0,0,0,0,0,0,0,0,0,0,0,0,0,0,CT33,0,0)';
      PINUSE='GROUND';
      NO_LOAD_CHECK='Both';
      NO_IO_CHECK='Both';
      NO_ASSERT_CHECK='TRUE';
      NO_DIR_CHECK='TRUE';
      ALLOW_CONNECT='TRUE';
    'VSS'<373>:
      PIN_NUMBER='(0,0,0,0,0,0,0,0,0,0,0,0,0,0,0,0,0,0,0,0,0,0,0,0,0,0,0,CT35,0,0)';
      PINUSE='GROUND';
      NO_LOAD_CHECK='Both';
      NO_IO_CHECK='Both';
      NO_ASSERT_CHECK='TRUE';
      NO_DIR_CHECK='TRUE';
      ALLOW_CONNECT='TRUE';
    'VSS'<372>:
      PIN_NUMBER='(0,0,0,0,0,0,0,0,0,0,0,0,0,0,0,0,0,0,0,0,0,0,0,0,0,0,0,CT57,0,0)';
      PINUSE='GROUND';
      NO_LOAD_CHECK='Both';
      NO_IO_CHECK='Both';
      NO_ASSERT_CHECK='TRUE';
      NO_DIR_CHECK='TRUE';
      ALLOW_CONNECT='TRUE';
    'VSS'<371>:
      PIN_NUMBER='(0,0,0,0,0,0,0,0,0,0,0,0,0,0,0,0,0,0,0,0,0,0,0,0,0,0,0,CT73,0,0)';
      PINUSE='GROUND';
      NO_LOAD_CHECK='Both';
      NO_IO_CHECK='Both';
      NO_ASSERT_CHECK='TRUE';
      NO_DIR_CHECK='TRUE';
      ALLOW_CONNECT='TRUE';
    'VSS'<370>:
      PIN_NUMBER='(0,0,0,0,0,0,0,0,0,0,0,0,0,0,0,0,0,0,0,0,0,0,0,0,0,0,0,CT79,0,0)';
      PINUSE='GROUND';
      NO_LOAD_CHECK='Both';
      NO_IO_CHECK='Both';
      NO_ASSERT_CHECK='TRUE';
      NO_DIR_CHECK='TRUE';
      ALLOW_CONNECT='TRUE';
    'VSS'<369>:
      PIN_NUMBER='(0,0,0,0,0,0,0,0,0,0,0,0,0,0,0,0,0,0,0,0,0,0,0,0,0,0,0,CT83,0,0)';
      PINUSE='GROUND';
      NO_LOAD_CHECK='Both';
      NO_IO_CHECK='Both';
      NO_ASSERT_CHECK='TRUE';
      NO_DIR_CHECK='TRUE';
      ALLOW_CONNECT='TRUE';
    'VSS'<368>:
      PIN_NUMBER='(0,0,0,0,0,0,0,0,0,0,0,0,0,0,0,0,0,0,0,0,0,0,0,0,0,0,0,CT85,0,0)';
      PINUSE='GROUND';
      NO_LOAD_CHECK='Both';
      NO_IO_CHECK='Both';
      NO_ASSERT_CHECK='TRUE';
      NO_DIR_CHECK='TRUE';
      ALLOW_CONNECT='TRUE';
    'VSS'<367>:
      PIN_NUMBER='(0,0,0,0,0,0,0,0,0,0,0,0,0,0,0,0,0,0,0,0,0,0,0,0,0,0,0,CU4,0,0)';
      PINUSE='GROUND';
      NO_LOAD_CHECK='Both';
      NO_IO_CHECK='Both';
      NO_ASSERT_CHECK='TRUE';
      NO_DIR_CHECK='TRUE';
      ALLOW_CONNECT='TRUE';
    'VSS'<366>:
      PIN_NUMBER='(0,0,0,0,0,0,0,0,0,0,0,0,0,0,0,0,0,0,0,0,0,0,0,0,0,0,0,CU22,0,0)';
      PINUSE='GROUND';
      NO_LOAD_CHECK='Both';
      NO_IO_CHECK='Both';
      NO_ASSERT_CHECK='TRUE';
      NO_DIR_CHECK='TRUE';
      ALLOW_CONNECT='TRUE';
    'VSS'<365>:
      PIN_NUMBER='(0,0,0,0,0,0,0,0,0,0,0,0,0,0,0,0,0,0,0,0,0,0,0,0,0,0,0,CU28,0,0)';
      PINUSE='GROUND';
      NO_LOAD_CHECK='Both';
      NO_IO_CHECK='Both';
      NO_ASSERT_CHECK='TRUE';
      NO_DIR_CHECK='TRUE';
      ALLOW_CONNECT='TRUE';
    'VSS'<364>:
      PIN_NUMBER='(0,0,0,0,0,0,0,0,0,0,0,0,0,0,0,0,0,0,0,0,0,0,0,0,0,0,0,CU30,0,0)';
      PINUSE='GROUND';
      NO_LOAD_CHECK='Both';
      NO_IO_CHECK='Both';
      NO_ASSERT_CHECK='TRUE';
      NO_DIR_CHECK='TRUE';
      ALLOW_CONNECT='TRUE';
    'VSS'<363>:
      PIN_NUMBER='(0,0,0,0,0,0,0,0,0,0,0,0,0,0,0,0,0,0,0,0,0,0,0,0,0,0,0,CU34,0,0)';
      PINUSE='GROUND';
      NO_LOAD_CHECK='Both';
      NO_IO_CHECK='Both';
      NO_ASSERT_CHECK='TRUE';
      NO_DIR_CHECK='TRUE';
      ALLOW_CONNECT='TRUE';
    'VSS'<362>:
      PIN_NUMBER='(0,0,0,0,0,0,0,0,0,0,0,0,0,0,0,0,0,0,0,0,0,0,0,0,0,0,0,CU36,0,0)';
      PINUSE='GROUND';
      NO_LOAD_CHECK='Both';
      NO_IO_CHECK='Both';
      NO_ASSERT_CHECK='TRUE';
      NO_DIR_CHECK='TRUE';
      ALLOW_CONNECT='TRUE';
    'VSS'<361>:
      PIN_NUMBER='(0,0,0,0,0,0,0,0,0,0,0,0,0,0,0,0,0,0,0,0,0,0,0,0,0,0,0,CU56,0,0)';
      PINUSE='GROUND';
      NO_LOAD_CHECK='Both';
      NO_IO_CHECK='Both';
      NO_ASSERT_CHECK='TRUE';
      NO_DIR_CHECK='TRUE';
      ALLOW_CONNECT='TRUE';
    'VSS'<360>:
      PIN_NUMBER='(0,0,0,0,0,0,0,0,0,0,0,0,0,0,0,0,0,0,0,0,0,0,0,0,0,0,0,CU62,0,0)';
      PINUSE='GROUND';
      NO_LOAD_CHECK='Both';
      NO_IO_CHECK='Both';
      NO_ASSERT_CHECK='TRUE';
      NO_DIR_CHECK='TRUE';
      ALLOW_CONNECT='TRUE';
    'VSS'<359>:
      PIN_NUMBER='(0,0,0,0,0,0,0,0,0,0,0,0,0,0,0,0,0,0,0,0,0,0,0,0,0,0,0,CU68,0,0)';
      PINUSE='GROUND';
      NO_LOAD_CHECK='Both';
      NO_IO_CHECK='Both';
      NO_ASSERT_CHECK='TRUE';
      NO_DIR_CHECK='TRUE';
      ALLOW_CONNECT='TRUE';
    'VSS'<358>:
      PIN_NUMBER='(0,0,0,0,0,0,0,0,0,0,0,0,0,0,0,0,0,0,0,0,0,0,0,0,0,0,0,CU76,0,0)';
      PINUSE='GROUND';
      NO_LOAD_CHECK='Both';
      NO_IO_CHECK='Both';
      NO_ASSERT_CHECK='TRUE';
      NO_DIR_CHECK='TRUE';
      ALLOW_CONNECT='TRUE';
    'VSS'<357>:
      PIN_NUMBER='(0,0,0,0,0,0,0,0,0,0,0,0,0,0,0,0,0,0,0,0,0,0,0,0,0,0,0,CU78,0,0)';
      PINUSE='GROUND';
      NO_LOAD_CHECK='Both';
      NO_IO_CHECK='Both';
      NO_ASSERT_CHECK='TRUE';
      NO_DIR_CHECK='TRUE';
      ALLOW_CONNECT='TRUE';
    'VSS'<356>:
      PIN_NUMBER='(0,0,0,0,0,0,0,0,0,0,0,0,0,0,0,0,0,0,0,0,0,0,0,0,0,0,0,CU80,0,0)';
      PINUSE='GROUND';
      NO_LOAD_CHECK='Both';
      NO_IO_CHECK='Both';
      NO_ASSERT_CHECK='TRUE';
      NO_DIR_CHECK='TRUE';
      ALLOW_CONNECT='TRUE';
    'VSS'<355>:
      PIN_NUMBER='(0,0,0,0,0,0,0,0,0,0,0,0,0,0,0,0,0,0,0,0,0,0,0,0,0,0,0,CU82,0,0)';
      PINUSE='GROUND';
      NO_LOAD_CHECK='Both';
      NO_IO_CHECK='Both';
      NO_ASSERT_CHECK='TRUE';
      NO_DIR_CHECK='TRUE';
      ALLOW_CONNECT='TRUE';
    'VSS'<354>:
      PIN_NUMBER='(0,0,0,0,0,0,0,0,0,0,0,0,0,0,0,0,0,0,0,0,0,0,0,0,0,0,0,CU86,0,0)';
      PINUSE='GROUND';
      NO_LOAD_CHECK='Both';
      NO_IO_CHECK='Both';
      NO_ASSERT_CHECK='TRUE';
      NO_DIR_CHECK='TRUE';
      ALLOW_CONNECT='TRUE';
    'VSS'<353>:
      PIN_NUMBER='(0,0,0,0,0,0,0,0,0,0,0,0,0,0,0,0,0,0,0,0,0,0,0,0,0,0,0,CV1,0,0)';
      PINUSE='GROUND';
      NO_LOAD_CHECK='Both';
      NO_IO_CHECK='Both';
      NO_ASSERT_CHECK='TRUE';
      NO_DIR_CHECK='TRUE';
      ALLOW_CONNECT='TRUE';
    'VSS'<352>:
      PIN_NUMBER='(0,0,0,0,0,0,0,0,0,0,0,0,0,0,0,0,0,0,0,0,0,0,0,0,0,0,0,H55,0,0)';
      PINUSE='GROUND';
      NO_LOAD_CHECK='Both';
      NO_IO_CHECK='Both';
      NO_ASSERT_CHECK='TRUE';
      NO_DIR_CHECK='TRUE';
      ALLOW_CONNECT='TRUE';
    'VSS'<351>:
      PIN_NUMBER='(0,0,0,0,0,0,0,0,0,0,0,0,0,0,0,0,0,0,0,0,0,0,0,0,0,0,0,CV17,0,0)';
      PINUSE='GROUND';
      NO_LOAD_CHECK='Both';
      NO_IO_CHECK='Both';
      NO_ASSERT_CHECK='TRUE';
      NO_DIR_CHECK='TRUE';
      ALLOW_CONNECT='TRUE';
    'VSS'<350>:
      PIN_NUMBER='(0,0,0,0,0,0,0,0,0,0,0,0,0,0,0,0,0,0,0,0,0,0,0,0,0,0,0,CV25,0,0)';
      PINUSE='GROUND';
      NO_LOAD_CHECK='Both';
      NO_IO_CHECK='Both';
      NO_ASSERT_CHECK='TRUE';
      NO_DIR_CHECK='TRUE';
      ALLOW_CONNECT='TRUE';
    'VSS'<349>:
      PIN_NUMBER='(0,0,0,0,0,0,0,0,0,0,0,0,0,0,0,0,0,0,0,0,0,0,0,0,0,0,0,CV27,0,0)';
      PINUSE='GROUND';
      NO_LOAD_CHECK='Both';
      NO_IO_CHECK='Both';
      NO_ASSERT_CHECK='TRUE';
      NO_DIR_CHECK='TRUE';
      ALLOW_CONNECT='TRUE';
    'VSS'<348>:
      PIN_NUMBER='(0,0,0,0,0,0,0,0,0,0,0,0,0,0,0,0,0,0,0,0,0,0,0,0,0,0,0,CV31,0,0)';
      PINUSE='GROUND';
      NO_LOAD_CHECK='Both';
      NO_IO_CHECK='Both';
      NO_ASSERT_CHECK='TRUE';
      NO_DIR_CHECK='TRUE';
      ALLOW_CONNECT='TRUE';
    'VSS'<347>:
      PIN_NUMBER='(0,0,0,0,0,0,0,0,0,0,0,0,0,0,0,0,0,0,0,0,0,0,0,0,0,0,0,CV33,0,0)';
      PINUSE='GROUND';
      NO_LOAD_CHECK='Both';
      NO_IO_CHECK='Both';
      NO_ASSERT_CHECK='TRUE';
      NO_DIR_CHECK='TRUE';
      ALLOW_CONNECT='TRUE';
    'VSS'<346>:
      PIN_NUMBER='(0,0,0,0,0,0,0,0,0,0,0,0,0,0,0,0,0,0,0,0,0,0,0,0,0,0,0,CV37,0,0)';
      PINUSE='GROUND';
      NO_LOAD_CHECK='Both';
      NO_IO_CHECK='Both';
      NO_ASSERT_CHECK='TRUE';
      NO_DIR_CHECK='TRUE';
      ALLOW_CONNECT='TRUE';
    'VSS'<345>:
      PIN_NUMBER='(0,0,0,0,0,0,0,0,0,0,0,0,0,0,0,0,0,0,0,0,0,0,0,0,0,0,0,CV39,0,0)';
      PINUSE='GROUND';
      NO_LOAD_CHECK='Both';
      NO_IO_CHECK='Both';
      NO_ASSERT_CHECK='TRUE';
      NO_DIR_CHECK='TRUE';
      ALLOW_CONNECT='TRUE';
    'VSS'<344>:
      PIN_NUMBER='(0,0,0,0,0,0,0,0,0,0,0,0,0,0,0,0,0,0,0,0,0,0,0,0,0,0,0,CV41,0,0)';
      PINUSE='GROUND';
      NO_LOAD_CHECK='Both';
      NO_IO_CHECK='Both';
      NO_ASSERT_CHECK='TRUE';
      NO_DIR_CHECK='TRUE';
      ALLOW_CONNECT='TRUE';
    'VSS'<343>:
      PIN_NUMBER='(0,0,0,0,0,0,0,0,0,0,0,0,0,0,0,0,0,0,0,0,0,0,0,0,0,0,0,CV53,0,0)';
      PINUSE='GROUND';
      NO_LOAD_CHECK='Both';
      NO_IO_CHECK='Both';
      NO_ASSERT_CHECK='TRUE';
      NO_DIR_CHECK='TRUE';
      ALLOW_CONNECT='TRUE';
    'VSS'<342>:
      PIN_NUMBER='(0,0,0,0,0,0,0,0,0,0,0,0,0,0,0,0,0,0,0,0,0,0,0,0,0,0,0,CV55,0,0)';
      PINUSE='GROUND';
      NO_LOAD_CHECK='Both';
      NO_IO_CHECK='Both';
      NO_ASSERT_CHECK='TRUE';
      NO_DIR_CHECK='TRUE';
      ALLOW_CONNECT='TRUE';
    'VSS'<341>:
      PIN_NUMBER='(0,0,0,0,0,0,0,0,0,0,0,0,0,0,0,0,0,0,0,0,0,0,0,0,0,0,0,CV63,0,0)';
      PINUSE='GROUND';
      NO_LOAD_CHECK='Both';
      NO_IO_CHECK='Both';
      NO_ASSERT_CHECK='TRUE';
      NO_DIR_CHECK='TRUE';
      ALLOW_CONNECT='TRUE';
    'VSS'<340>:
      PIN_NUMBER='(0,0,0,0,0,0,0,0,0,0,0,0,0,0,0,0,0,0,0,0,0,0,0,0,0,0,0,CV67,0,0)';
      PINUSE='GROUND';
      NO_LOAD_CHECK='Both';
      NO_IO_CHECK='Both';
      NO_ASSERT_CHECK='TRUE';
      NO_DIR_CHECK='TRUE';
      ALLOW_CONNECT='TRUE';
    'VSS'<339>:
      PIN_NUMBER='(0,0,0,0,0,0,0,0,0,0,0,0,0,0,0,0,0,0,0,0,0,0,0,0,0,0,0,CV73,0,0)';
      PINUSE='GROUND';
      NO_LOAD_CHECK='Both';
      NO_IO_CHECK='Both';
      NO_ASSERT_CHECK='TRUE';
      NO_DIR_CHECK='TRUE';
      ALLOW_CONNECT='TRUE';
    'VSS'<338>:
      PIN_NUMBER='(0,0,0,0,0,0,0,0,0,0,0,0,0,0,0,0,0,0,0,0,0,0,0,0,0,0,0,CV79,0,0)';
      PINUSE='GROUND';
      NO_LOAD_CHECK='Both';
      NO_IO_CHECK='Both';
      NO_ASSERT_CHECK='TRUE';
      NO_DIR_CHECK='TRUE';
      ALLOW_CONNECT='TRUE';
    'VSS'<337>:
      PIN_NUMBER='(0,0,0,0,0,0,0,0,0,0,0,0,0,0,0,0,0,0,0,0,0,0,0,0,0,0,0,CV81,0,0)';
      PINUSE='GROUND';
      NO_LOAD_CHECK='Both';
      NO_IO_CHECK='Both';
      NO_ASSERT_CHECK='TRUE';
      NO_DIR_CHECK='TRUE';
      ALLOW_CONNECT='TRUE';
    'VSS'<336>:
      PIN_NUMBER='(0,0,0,0,0,0,0,0,0,0,0,0,0,0,0,0,0,0,0,0,0,0,0,0,0,0,0,CV83,0,0)';
      PINUSE='GROUND';
      NO_LOAD_CHECK='Both';
      NO_IO_CHECK='Both';
      NO_ASSERT_CHECK='TRUE';
      NO_DIR_CHECK='TRUE';
      ALLOW_CONNECT='TRUE';
    'VSS'<335>:
      PIN_NUMBER='(0,0,0,0,0,0,0,0,0,0,0,0,0,0,0,0,0,0,0,0,0,0,0,0,0,0,0,CW12,0,0)';
      PINUSE='GROUND';
      NO_LOAD_CHECK='Both';
      NO_IO_CHECK='Both';
      NO_ASSERT_CHECK='TRUE';
      NO_DIR_CHECK='TRUE';
      ALLOW_CONNECT='TRUE';
    'VSS'<334>:
      PIN_NUMBER='(0,0,0,0,0,0,0,0,0,0,0,0,0,0,0,0,0,0,0,0,0,0,0,0,0,0,0,CW26,0,0)';
      PINUSE='GROUND';
      NO_LOAD_CHECK='Both';
      NO_IO_CHECK='Both';
      NO_ASSERT_CHECK='TRUE';
      NO_DIR_CHECK='TRUE';
      ALLOW_CONNECT='TRUE';
    'VSS'<333>:
      PIN_NUMBER='(0,0,0,0,0,0,0,0,0,0,0,0,0,0,0,0,0,0,0,0,0,0,0,0,0,0,0,CW32,0,0)';
      PINUSE='GROUND';
      NO_LOAD_CHECK='Both';
      NO_IO_CHECK='Both';
      NO_ASSERT_CHECK='TRUE';
      NO_DIR_CHECK='TRUE';
      ALLOW_CONNECT='TRUE';
    'VSS'<332>:
      PIN_NUMBER='(0,0,0,0,0,0,0,0,0,0,0,0,0,0,0,0,0,0,0,0,0,0,0,0,0,0,0,CW38,0,0)';
      PINUSE='GROUND';
      NO_LOAD_CHECK='Both';
      NO_IO_CHECK='Both';
      NO_ASSERT_CHECK='TRUE';
      NO_DIR_CHECK='TRUE';
      ALLOW_CONNECT='TRUE';
    'VSS'<331>:
      PIN_NUMBER='(0,0,0,0,0,0,0,0,0,0,0,0,0,0,0,0,0,0,0,0,0,0,0,0,0,0,0,CW40,0,0)';
      PINUSE='GROUND';
      NO_LOAD_CHECK='Both';
      NO_IO_CHECK='Both';
      NO_ASSERT_CHECK='TRUE';
      NO_DIR_CHECK='TRUE';
      ALLOW_CONNECT='TRUE';
    'VSS'<330>:
      PIN_NUMBER='(0,0,0,0,0,0,0,0,0,0,0,0,0,0,0,0,0,0,0,0,0,0,0,0,0,0,0,CW42,0,0)';
      PINUSE='GROUND';
      NO_LOAD_CHECK='Both';
      NO_IO_CHECK='Both';
      NO_ASSERT_CHECK='TRUE';
      NO_DIR_CHECK='TRUE';
      ALLOW_CONNECT='TRUE';
    'VSS'<329>:
      PIN_NUMBER='(0,0,0,0,0,0,0,0,0,0,0,0,0,0,0,0,0,0,0,0,0,0,0,0,0,0,0,CW52,0,0)';
      PINUSE='GROUND';
      NO_LOAD_CHECK='Both';
      NO_IO_CHECK='Both';
      NO_ASSERT_CHECK='TRUE';
      NO_DIR_CHECK='TRUE';
      ALLOW_CONNECT='TRUE';
    'VSS'<328>:
      PIN_NUMBER='(0,0,0,0,0,0,0,0,0,0,0,0,0,0,0,0,0,0,0,0,0,0,0,0,0,0,0,CW54,0,0)';
      PINUSE='GROUND';
      NO_LOAD_CHECK='Both';
      NO_IO_CHECK='Both';
      NO_ASSERT_CHECK='TRUE';
      NO_DIR_CHECK='TRUE';
      ALLOW_CONNECT='TRUE';
    'VSS'<327>:
      PIN_NUMBER='(0,0,0,0,0,0,0,0,0,0,0,0,0,0,0,0,0,0,0,0,0,0,0,0,0,0,0,CW64,0,0)';
      PINUSE='GROUND';
      NO_LOAD_CHECK='Both';
      NO_IO_CHECK='Both';
      NO_ASSERT_CHECK='TRUE';
      NO_DIR_CHECK='TRUE';
      ALLOW_CONNECT='TRUE';
    'VSS'<326>:
      PIN_NUMBER='(0,0,0,0,0,0,0,0,0,0,0,0,0,0,0,0,0,0,0,0,0,0,0,0,0,0,0,CW66,0,0)';
      PINUSE='GROUND';
      NO_LOAD_CHECK='Both';
      NO_IO_CHECK='Both';
      NO_ASSERT_CHECK='TRUE';
      NO_DIR_CHECK='TRUE';
      ALLOW_CONNECT='TRUE';
    'VSS'<325>:
      PIN_NUMBER='(0,0,0,0,0,0,0,0,0,0,0,0,0,0,0,0,0,0,0,0,0,0,0,0,0,0,0,CW68,0,0)';
      PINUSE='GROUND';
      NO_LOAD_CHECK='Both';
      NO_IO_CHECK='Both';
      NO_ASSERT_CHECK='TRUE';
      NO_DIR_CHECK='TRUE';
      ALLOW_CONNECT='TRUE';
    'VSS'<324>:
      PIN_NUMBER='(0,0,0,0,0,0,0,0,0,0,0,0,0,0,0,0,0,0,0,0,0,0,0,0,0,0,0,CW74,0,0)';
      PINUSE='GROUND';
      NO_LOAD_CHECK='Both';
      NO_IO_CHECK='Both';
      NO_ASSERT_CHECK='TRUE';
      NO_DIR_CHECK='TRUE';
      ALLOW_CONNECT='TRUE';
    'VSS'<323>:
      PIN_NUMBER='(0,0,0,0,0,0,0,0,0,0,0,0,0,0,0,0,0,0,0,0,0,0,0,0,0,0,0,CW78,0,0)';
      PINUSE='GROUND';
      NO_LOAD_CHECK='Both';
      NO_IO_CHECK='Both';
      NO_ASSERT_CHECK='TRUE';
      NO_DIR_CHECK='TRUE';
      ALLOW_CONNECT='TRUE';
    'VSS'<322>:
      PIN_NUMBER='(0,0,0,0,0,0,0,0,0,0,0,0,0,0,0,0,0,0,0,0,0,0,0,0,0,0,0,CW82,0,0)';
      PINUSE='GROUND';
      NO_LOAD_CHECK='Both';
      NO_IO_CHECK='Both';
      NO_ASSERT_CHECK='TRUE';
      NO_DIR_CHECK='TRUE';
      ALLOW_CONNECT='TRUE';
    'VSS'<321>:
      PIN_NUMBER='(0,0,0,0,0,0,0,0,0,0,0,0,0,0,0,0,0,0,0,0,0,0,0,0,0,0,0,CY1,0,0)';
      PINUSE='GROUND';
      NO_LOAD_CHECK='Both';
      NO_IO_CHECK='Both';
      NO_ASSERT_CHECK='TRUE';
      NO_DIR_CHECK='TRUE';
      ALLOW_CONNECT='TRUE';
    'VSS'<320>:
      PIN_NUMBER='(0,0,0,0,0,0,0,0,0,0,0,0,0,0,0,0,0,0,0,0,0,0,0,0,0,0,0,CY9,0,0)';
      PINUSE='GROUND';
      NO_LOAD_CHECK='Both';
      NO_IO_CHECK='Both';
      NO_ASSERT_CHECK='TRUE';
      NO_DIR_CHECK='TRUE';
      ALLOW_CONNECT='TRUE';
    'VSS'<319>:
      PIN_NUMBER='(0,0,0,0,0,0,0,0,0,0,0,0,0,0,0,0,0,0,0,0,0,0,0,0,0,0,0,CY13,0,0)';
      PINUSE='GROUND';
      NO_LOAD_CHECK='Both';
      NO_IO_CHECK='Both';
      NO_ASSERT_CHECK='TRUE';
      NO_DIR_CHECK='TRUE';
      ALLOW_CONNECT='TRUE';
    'VSS'<318>:
      PIN_NUMBER='(0,0,0,0,0,0,0,0,0,0,0,0,0,0,0,0,0,0,0,0,0,0,0,0,0,0,0,CY15,0,0)';
      PINUSE='GROUND';
      NO_LOAD_CHECK='Both';
      NO_IO_CHECK='Both';
      NO_ASSERT_CHECK='TRUE';
      NO_DIR_CHECK='TRUE';
      ALLOW_CONNECT='TRUE';
    'VSS'<317>:
      PIN_NUMBER='(0,0,0,0,0,0,0,0,0,0,0,0,0,0,0,0,0,0,0,0,0,0,0,0,0,0,0,CY21,0,0)';
      PINUSE='GROUND';
      NO_LOAD_CHECK='Both';
      NO_IO_CHECK='Both';
      NO_ASSERT_CHECK='TRUE';
      NO_DIR_CHECK='TRUE';
      ALLOW_CONNECT='TRUE';
    'VSS'<316>:
      PIN_NUMBER='(0,0,0,0,0,0,0,0,0,0,0,0,0,0,0,0,0,0,0,0,0,0,0,0,0,0,0,CY41,0,0)';
      PINUSE='GROUND';
      NO_LOAD_CHECK='Both';
      NO_IO_CHECK='Both';
      NO_ASSERT_CHECK='TRUE';
      NO_DIR_CHECK='TRUE';
      ALLOW_CONNECT='TRUE';
    'VSS'<315>:
      PIN_NUMBER='(0,0,0,0,0,0,0,0,0,0,0,0,0,0,0,0,0,0,0,0,0,0,0,0,0,0,0,CY45,0,0)';
      PINUSE='GROUND';
      NO_LOAD_CHECK='Both';
      NO_IO_CHECK='Both';
      NO_ASSERT_CHECK='TRUE';
      NO_DIR_CHECK='TRUE';
      ALLOW_CONNECT='TRUE';
    'VSS'<314>:
      PIN_NUMBER='(0,0,0,0,0,0,0,0,0,0,0,0,0,0,0,0,0,0,0,0,0,0,0,0,0,0,0,CY51,0,0)';
      PINUSE='GROUND';
      NO_LOAD_CHECK='Both';
      NO_IO_CHECK='Both';
      NO_ASSERT_CHECK='TRUE';
      NO_DIR_CHECK='TRUE';
      ALLOW_CONNECT='TRUE';
    'VSS'<313>:
      PIN_NUMBER='(0,0,0,0,0,0,0,0,0,0,0,0,0,0,0,0,0,0,0,0,0,0,0,0,0,0,0,CY59,0,0)';
      PINUSE='GROUND';
      NO_LOAD_CHECK='Both';
      NO_IO_CHECK='Both';
      NO_ASSERT_CHECK='TRUE';
      NO_DIR_CHECK='TRUE';
      ALLOW_CONNECT='TRUE';
    'VSS'<312>:
      PIN_NUMBER='(0,0,0,0,0,0,0,0,0,0,0,0,0,0,0,0,0,0,0,0,0,0,0,0,0,0,0,CY61,0,0)';
      PINUSE='GROUND';
      NO_LOAD_CHECK='Both';
      NO_IO_CHECK='Both';
      NO_ASSERT_CHECK='TRUE';
      NO_DIR_CHECK='TRUE';
      ALLOW_CONNECT='TRUE';
    'VSS'<311>:
      PIN_NUMBER='(0,0,0,0,0,0,0,0,0,0,0,0,0,0,0,0,0,0,0,0,0,0,0,0,0,0,0,CY65,0,0)';
      PINUSE='GROUND';
      NO_LOAD_CHECK='Both';
      NO_IO_CHECK='Both';
      NO_ASSERT_CHECK='TRUE';
      NO_DIR_CHECK='TRUE';
      ALLOW_CONNECT='TRUE';
    'VSS'<310>:
      PIN_NUMBER='(0,0,0,0,0,0,0,0,0,0,0,0,0,0,0,0,0,0,0,0,0,0,0,0,0,0,0,CY69,0,0)';
      PINUSE='GROUND';
      NO_LOAD_CHECK='Both';
      NO_IO_CHECK='Both';
      NO_ASSERT_CHECK='TRUE';
      NO_DIR_CHECK='TRUE';
      ALLOW_CONNECT='TRUE';
    'VSS'<309>:
      PIN_NUMBER='(0,0,0,0,0,0,0,0,0,0,0,0,0,0,0,0,0,0,0,0,0,0,0,0,0,0,0,CY75,0,0)';
      PINUSE='GROUND';
      NO_LOAD_CHECK='Both';
      NO_IO_CHECK='Both';
      NO_ASSERT_CHECK='TRUE';
      NO_DIR_CHECK='TRUE';
      ALLOW_CONNECT='TRUE';
    'VSS'<308>:
      PIN_NUMBER='(0,0,0,0,0,0,0,0,0,0,0,0,0,0,0,0,0,0,0,0,0,0,0,0,0,0,0,CY77,0,0)';
      PINUSE='GROUND';
      NO_LOAD_CHECK='Both';
      NO_IO_CHECK='Both';
      NO_ASSERT_CHECK='TRUE';
      NO_DIR_CHECK='TRUE';
      ALLOW_CONNECT='TRUE';
    'VSS'<307>:
      PIN_NUMBER='(0,0,0,0,0,0,0,0,0,0,0,0,0,0,0,0,0,0,0,0,0,0,0,0,0,0,0,CY83,0,0)';
      PINUSE='GROUND';
      NO_LOAD_CHECK='Both';
      NO_IO_CHECK='Both';
      NO_ASSERT_CHECK='TRUE';
      NO_DIR_CHECK='TRUE';
      ALLOW_CONNECT='TRUE';
    'VSS'<306>:
      PIN_NUMBER='(0,0,0,0,0,0,0,0,0,0,0,0,0,0,0,0,0,0,0,0,0,0,0,0,0,0,0,CY85,0,0)';
      PINUSE='GROUND';
      NO_LOAD_CHECK='Both';
      NO_IO_CHECK='Both';
      NO_ASSERT_CHECK='TRUE';
      NO_DIR_CHECK='TRUE';
      ALLOW_CONNECT='TRUE';
    'VSS'<305>:
      PIN_NUMBER='(0,0,0,0,0,0,0,0,0,0,0,0,0,0,0,0,0,0,0,0,0,0,0,0,0,0,0,DA6,0,0)';
      PINUSE='GROUND';
      NO_LOAD_CHECK='Both';
      NO_IO_CHECK='Both';
      NO_ASSERT_CHECK='TRUE';
      NO_DIR_CHECK='TRUE';
      ALLOW_CONNECT='TRUE';
    'VSS'<304>:
      PIN_NUMBER='(0,0,0,0,0,0,0,0,0,0,0,0,0,0,0,0,0,0,0,0,0,0,0,0,0,0,0,H53,0,0)';
      PINUSE='GROUND';
      NO_LOAD_CHECK='Both';
      NO_IO_CHECK='Both';
      NO_ASSERT_CHECK='TRUE';
      NO_DIR_CHECK='TRUE';
      ALLOW_CONNECT='TRUE';
    'VSS'<303>:
      PIN_NUMBER='(0,0,0,0,0,0,0,0,0,0,0,0,0,0,0,0,0,0,0,0,0,0,0,0,0,0,0,DA18,0,0)';
      PINUSE='GROUND';
      NO_LOAD_CHECK='Both';
      NO_IO_CHECK='Both';
      NO_ASSERT_CHECK='TRUE';
      NO_DIR_CHECK='TRUE';
      ALLOW_CONNECT='TRUE';
    'VSS'<302>:
      PIN_NUMBER='(0,0,0,0,0,0,0,0,0,0,0,0,0,0,0,0,0,0,0,0,0,0,0,0,0,0,0,DA26,0,0)';
      PINUSE='GROUND';
      NO_LOAD_CHECK='Both';
      NO_IO_CHECK='Both';
      NO_ASSERT_CHECK='TRUE';
      NO_DIR_CHECK='TRUE';
      ALLOW_CONNECT='TRUE';
    'VSS'<301>:
      PIN_NUMBER='(0,0,0,0,0,0,0,0,0,0,0,0,0,0,0,0,0,0,0,0,0,0,0,0,0,0,0,DA28,0,0)';
      PINUSE='GROUND';
      NO_LOAD_CHECK='Both';
      NO_IO_CHECK='Both';
      NO_ASSERT_CHECK='TRUE';
      NO_DIR_CHECK='TRUE';
      ALLOW_CONNECT='TRUE';
    'VSS'<300>:
      PIN_NUMBER='(0,0,0,0,0,0,0,0,0,0,0,0,0,0,0,0,0,0,0,0,0,0,0,0,0,0,0,DA30,0,0)';
      PINUSE='GROUND';
      NO_LOAD_CHECK='Both';
      NO_IO_CHECK='Both';
      NO_ASSERT_CHECK='TRUE';
      NO_DIR_CHECK='TRUE';
      ALLOW_CONNECT='TRUE';
    'VSS'<299>:
      PIN_NUMBER='(0,0,0,0,0,0,0,0,0,0,0,0,0,0,0,0,0,0,0,0,0,0,0,0,0,0,0,DA32,0,0)';
      PINUSE='GROUND';
      NO_LOAD_CHECK='Both';
      NO_IO_CHECK='Both';
      NO_ASSERT_CHECK='TRUE';
      NO_DIR_CHECK='TRUE';
      ALLOW_CONNECT='TRUE';
    'VSS'<298>:
      PIN_NUMBER='(0,0,0,0,0,0,0,0,0,0,0,0,0,0,0,0,0,0,0,0,0,0,0,0,0,0,0,DA34,0,0)';
      PINUSE='GROUND';
      NO_LOAD_CHECK='Both';
      NO_IO_CHECK='Both';
      NO_ASSERT_CHECK='TRUE';
      NO_DIR_CHECK='TRUE';
      ALLOW_CONNECT='TRUE';
    'VSS'<297>:
      PIN_NUMBER='(0,0,0,0,0,0,0,0,0,0,0,0,0,0,0,0,0,0,0,0,0,0,0,0,0,0,0,DA36,0,0)';
      PINUSE='GROUND';
      NO_LOAD_CHECK='Both';
      NO_IO_CHECK='Both';
      NO_ASSERT_CHECK='TRUE';
      NO_DIR_CHECK='TRUE';
      ALLOW_CONNECT='TRUE';
    'VSS'<296>:
      PIN_NUMBER='(0,0,0,0,0,0,0,0,0,0,0,0,0,0,0,0,0,0,0,0,0,0,0,0,0,0,0,DA38,0,0)';
      PINUSE='GROUND';
      NO_LOAD_CHECK='Both';
      NO_IO_CHECK='Both';
      NO_ASSERT_CHECK='TRUE';
      NO_DIR_CHECK='TRUE';
      ALLOW_CONNECT='TRUE';
    'VSS'<295>:
      PIN_NUMBER='(0,0,0,0,0,0,0,0,0,0,0,0,0,0,0,0,0,0,0,0,0,0,0,0,0,0,0,DA44,0,0)';
      PINUSE='GROUND';
      NO_LOAD_CHECK='Both';
      NO_IO_CHECK='Both';
      NO_ASSERT_CHECK='TRUE';
      NO_DIR_CHECK='TRUE';
      ALLOW_CONNECT='TRUE';
    'VSS'<294>:
      PIN_NUMBER='(0,0,0,0,0,0,0,0,0,0,0,0,0,0,0,0,0,0,0,0,0,0,0,0,0,0,0,DA46,0,0)';
      PINUSE='GROUND';
      NO_LOAD_CHECK='Both';
      NO_IO_CHECK='Both';
      NO_ASSERT_CHECK='TRUE';
      NO_DIR_CHECK='TRUE';
      ALLOW_CONNECT='TRUE';
    'VSS'<293>:
      PIN_NUMBER='(0,0,0,0,0,0,0,0,0,0,0,0,0,0,0,0,0,0,0,0,0,0,0,0,0,0,0,0,DA48,0)';
      PINUSE='GROUND';
      NO_LOAD_CHECK='Both';
      NO_IO_CHECK='Both';
      NO_ASSERT_CHECK='TRUE';
      NO_DIR_CHECK='TRUE';
      ALLOW_CONNECT='TRUE';
    'VSS'<292>:
      PIN_NUMBER='(0,0,0,0,0,0,0,0,0,0,0,0,0,0,0,0,0,0,0,0,0,0,0,0,0,0,0,0,DA50,0)';
      PINUSE='GROUND';
      NO_LOAD_CHECK='Both';
      NO_IO_CHECK='Both';
      NO_ASSERT_CHECK='TRUE';
      NO_DIR_CHECK='TRUE';
      ALLOW_CONNECT='TRUE';
    'VSS'<291>:
      PIN_NUMBER='(0,0,0,0,0,0,0,0,0,0,0,0,0,0,0,0,0,0,0,0,0,0,0,0,0,0,0,0,DA64,0)';
      PINUSE='GROUND';
      NO_LOAD_CHECK='Both';
      NO_IO_CHECK='Both';
      NO_ASSERT_CHECK='TRUE';
      NO_DIR_CHECK='TRUE';
      ALLOW_CONNECT='TRUE';
    'VSS'<290>:
      PIN_NUMBER='(0,0,0,0,0,0,0,0,0,0,0,0,0,0,0,0,0,0,0,0,0,0,0,0,0,0,0,0,DA70,0)';
      PINUSE='GROUND';
      NO_LOAD_CHECK='Both';
      NO_IO_CHECK='Both';
      NO_ASSERT_CHECK='TRUE';
      NO_DIR_CHECK='TRUE';
      ALLOW_CONNECT='TRUE';
    'VSS'<289>:
      PIN_NUMBER='(0,0,0,0,0,0,0,0,0,0,0,0,0,0,0,0,0,0,0,0,0,0,0,0,0,0,0,0,DA74,0)';
      PINUSE='GROUND';
      NO_LOAD_CHECK='Both';
      NO_IO_CHECK='Both';
      NO_ASSERT_CHECK='TRUE';
      NO_DIR_CHECK='TRUE';
      ALLOW_CONNECT='TRUE';
    'VSS'<288>:
      PIN_NUMBER='(0,0,0,0,0,0,0,0,0,0,0,0,0,0,0,0,0,0,0,0,0,0,0,0,0,0,0,0,DA76,0)';
      PINUSE='GROUND';
      NO_LOAD_CHECK='Both';
      NO_IO_CHECK='Both';
      NO_ASSERT_CHECK='TRUE';
      NO_DIR_CHECK='TRUE';
      ALLOW_CONNECT='TRUE';
    'VSS'<287>:
      PIN_NUMBER='(0,0,0,0,0,0,0,0,0,0,0,0,0,0,0,0,0,0,0,0,0,0,0,0,0,0,0,0,DA78,0)';
      PINUSE='GROUND';
      NO_LOAD_CHECK='Both';
      NO_IO_CHECK='Both';
      NO_ASSERT_CHECK='TRUE';
      NO_DIR_CHECK='TRUE';
      ALLOW_CONNECT='TRUE';
    'VSS'<286>:
      PIN_NUMBER='(0,0,0,0,0,0,0,0,0,0,0,0,0,0,0,0,0,0,0,0,0,0,0,0,0,0,0,0,DA80,0)';
      PINUSE='GROUND';
      NO_LOAD_CHECK='Both';
      NO_IO_CHECK='Both';
      NO_ASSERT_CHECK='TRUE';
      NO_DIR_CHECK='TRUE';
      ALLOW_CONNECT='TRUE';
    'VSS'<285>:
      PIN_NUMBER='(0,0,0,0,0,0,0,0,0,0,0,0,0,0,0,0,0,0,0,0,0,0,0,0,0,0,0,0,DB3,0)';
      PINUSE='GROUND';
      NO_LOAD_CHECK='Both';
      NO_IO_CHECK='Both';
      NO_ASSERT_CHECK='TRUE';
      NO_DIR_CHECK='TRUE';
      ALLOW_CONNECT='TRUE';
    'VSS'<284>:
      PIN_NUMBER='(0,0,0,0,0,0,0,0,0,0,0,0,0,0,0,0,0,0,0,0,0,0,0,0,0,0,0,0,DB13,0)';
      PINUSE='GROUND';
      NO_LOAD_CHECK='Both';
      NO_IO_CHECK='Both';
      NO_ASSERT_CHECK='TRUE';
      NO_DIR_CHECK='TRUE';
      ALLOW_CONNECT='TRUE';
    'VSS'<283>:
      PIN_NUMBER='(0,0,0,0,0,0,0,0,0,0,0,0,0,0,0,0,0,0,0,0,0,0,0,0,0,0,0,0,DB17,0)';
      PINUSE='GROUND';
      NO_LOAD_CHECK='Both';
      NO_IO_CHECK='Both';
      NO_ASSERT_CHECK='TRUE';
      NO_DIR_CHECK='TRUE';
      ALLOW_CONNECT='TRUE';
    'VSS'<282>:
      PIN_NUMBER='(0,0,0,0,0,0,0,0,0,0,0,0,0,0,0,0,0,0,0,0,0,0,0,0,0,0,0,0,DB23,0)';
      PINUSE='GROUND';
      NO_LOAD_CHECK='Both';
      NO_IO_CHECK='Both';
      NO_ASSERT_CHECK='TRUE';
      NO_DIR_CHECK='TRUE';
      ALLOW_CONNECT='TRUE';
    'VSS'<281>:
      PIN_NUMBER='(0,0,0,0,0,0,0,0,0,0,0,0,0,0,0,0,0,0,0,0,0,0,0,0,0,0,0,0,DB25,0)';
      PINUSE='GROUND';
      NO_LOAD_CHECK='Both';
      NO_IO_CHECK='Both';
      NO_ASSERT_CHECK='TRUE';
      NO_DIR_CHECK='TRUE';
      ALLOW_CONNECT='TRUE';
    'VSS'<280>:
      PIN_NUMBER='(0,0,0,0,0,0,0,0,0,0,0,0,0,0,0,0,0,0,0,0,0,0,0,0,0,0,0,0,DB39,0)';
      PINUSE='GROUND';
      NO_LOAD_CHECK='Both';
      NO_IO_CHECK='Both';
      NO_ASSERT_CHECK='TRUE';
      NO_DIR_CHECK='TRUE';
      ALLOW_CONNECT='TRUE';
    'VSS'<279>:
      PIN_NUMBER='(0,0,0,0,0,0,0,0,0,0,0,0,0,0,0,0,0,0,0,0,0,0,0,0,0,0,0,0,DB41,0)';
      PINUSE='GROUND';
      NO_LOAD_CHECK='Both';
      NO_IO_CHECK='Both';
      NO_ASSERT_CHECK='TRUE';
      NO_DIR_CHECK='TRUE';
      ALLOW_CONNECT='TRUE';
    'VSS'<278>:
      PIN_NUMBER='(0,0,0,0,0,0,0,0,0,0,0,0,0,0,0,0,0,0,0,0,0,0,0,0,0,0,0,0,DB47,0)';
      PINUSE='GROUND';
      NO_LOAD_CHECK='Both';
      NO_IO_CHECK='Both';
      NO_ASSERT_CHECK='TRUE';
      NO_DIR_CHECK='TRUE';
      ALLOW_CONNECT='TRUE';
    'VSS'<277>:
      PIN_NUMBER='(0,0,0,0,0,0,0,0,0,0,0,0,0,0,0,0,0,0,0,0,0,0,0,0,0,0,0,0,DB49,0)';
      PINUSE='GROUND';
      NO_LOAD_CHECK='Both';
      NO_IO_CHECK='Both';
      NO_ASSERT_CHECK='TRUE';
      NO_DIR_CHECK='TRUE';
      ALLOW_CONNECT='TRUE';
    'VSS'<276>:
      PIN_NUMBER='(0,0,0,0,0,0,0,0,0,0,0,0,0,0,0,0,0,0,0,0,0,0,0,0,0,0,0,0,DB73,0)';
      PINUSE='GROUND';
      NO_LOAD_CHECK='Both';
      NO_IO_CHECK='Both';
      NO_ASSERT_CHECK='TRUE';
      NO_DIR_CHECK='TRUE';
      ALLOW_CONNECT='TRUE';
    'VSS'<275>:
      PIN_NUMBER='(0,0,0,0,0,0,0,0,0,0,0,0,0,0,0,0,0,0,0,0,0,0,0,0,0,0,0,0,DB77,0)';
      PINUSE='GROUND';
      NO_LOAD_CHECK='Both';
      NO_IO_CHECK='Both';
      NO_ASSERT_CHECK='TRUE';
      NO_DIR_CHECK='TRUE';
      ALLOW_CONNECT='TRUE';
    'VSS'<274>:
      PIN_NUMBER='(0,0,0,0,0,0,0,0,0,0,0,0,0,0,0,0,0,0,0,0,0,0,0,0,0,0,0,0,DB83,0)';
      PINUSE='GROUND';
      NO_LOAD_CHECK='Both';
      NO_IO_CHECK='Both';
      NO_ASSERT_CHECK='TRUE';
      NO_DIR_CHECK='TRUE';
      ALLOW_CONNECT='TRUE';
    'VSS'<273>:
      PIN_NUMBER='(0,0,0,0,0,0,0,0,0,0,0,0,0,0,0,0,0,0,0,0,0,0,0,0,0,0,0,0,DB85,0)';
      PINUSE='GROUND';
      NO_LOAD_CHECK='Both';
      NO_IO_CHECK='Both';
      NO_ASSERT_CHECK='TRUE';
      NO_DIR_CHECK='TRUE';
      ALLOW_CONNECT='TRUE';
    'VSS'<272>:
      PIN_NUMBER='(0,0,0,0,0,0,0,0,0,0,0,0,0,0,0,0,0,0,0,0,0,0,0,0,0,0,0,0,DC14,0)';
      PINUSE='GROUND';
      NO_LOAD_CHECK='Both';
      NO_IO_CHECK='Both';
      NO_ASSERT_CHECK='TRUE';
      NO_DIR_CHECK='TRUE';
      ALLOW_CONNECT='TRUE';
    'VSS'<271>:
      PIN_NUMBER='(0,0,0,0,0,0,0,0,0,0,0,0,0,0,0,0,0,0,0,0,0,0,0,0,0,0,0,0,DC24,0)';
      PINUSE='GROUND';
      NO_LOAD_CHECK='Both';
      NO_IO_CHECK='Both';
      NO_ASSERT_CHECK='TRUE';
      NO_DIR_CHECK='TRUE';
      ALLOW_CONNECT='TRUE';
    'VSS'<270>:
      PIN_NUMBER='(0,0,0,0,0,0,0,0,0,0,0,0,0,0,0,0,0,0,0,0,0,0,0,0,0,0,0,0,DC26,0)';
      PINUSE='GROUND';
      NO_LOAD_CHECK='Both';
      NO_IO_CHECK='Both';
      NO_ASSERT_CHECK='TRUE';
      NO_DIR_CHECK='TRUE';
      ALLOW_CONNECT='TRUE';
    'VSS'<269>:
      PIN_NUMBER='(0,0,0,0,0,0,0,0,0,0,0,0,0,0,0,0,0,0,0,0,0,0,0,0,0,0,0,0,DC32,0)';
      PINUSE='GROUND';
      NO_LOAD_CHECK='Both';
      NO_IO_CHECK='Both';
      NO_ASSERT_CHECK='TRUE';
      NO_DIR_CHECK='TRUE';
      ALLOW_CONNECT='TRUE';
    'VSS'<268>:
      PIN_NUMBER='(0,0,0,0,0,0,0,0,0,0,0,0,0,0,0,0,0,0,0,0,0,0,0,0,0,0,0,0,DC38,0)';
      PINUSE='GROUND';
      NO_LOAD_CHECK='Both';
      NO_IO_CHECK='Both';
      NO_ASSERT_CHECK='TRUE';
      NO_DIR_CHECK='TRUE';
      ALLOW_CONNECT='TRUE';
    'VSS'<267>:
      PIN_NUMBER='(0,0,0,0,0,0,0,0,0,0,0,0,0,0,0,0,0,0,0,0,0,0,0,0,0,0,0,0,DC42,0)';
      PINUSE='GROUND';
      NO_LOAD_CHECK='Both';
      NO_IO_CHECK='Both';
      NO_ASSERT_CHECK='TRUE';
      NO_DIR_CHECK='TRUE';
      ALLOW_CONNECT='TRUE';
    'VSS'<266>:
      PIN_NUMBER='(0,0,0,0,0,0,0,0,0,0,0,0,0,0,0,0,0,0,0,0,0,0,0,0,0,0,0,0,DC64,0)';
      PINUSE='GROUND';
      NO_LOAD_CHECK='Both';
      NO_IO_CHECK='Both';
      NO_ASSERT_CHECK='TRUE';
      NO_DIR_CHECK='TRUE';
      ALLOW_CONNECT='TRUE';
    'VSS'<265>:
      PIN_NUMBER='(0,0,0,0,0,0,0,0,0,0,0,0,0,0,0,0,0,0,0,0,0,0,0,0,0,0,0,0,DC66,0)';
      PINUSE='GROUND';
      NO_LOAD_CHECK='Both';
      NO_IO_CHECK='Both';
      NO_ASSERT_CHECK='TRUE';
      NO_DIR_CHECK='TRUE';
      ALLOW_CONNECT='TRUE';
    'VSS'<264>:
      PIN_NUMBER='(0,0,0,0,0,0,0,0,0,0,0,0,0,0,0,0,0,0,0,0,0,0,0,0,0,0,0,0,DC68,0)';
      PINUSE='GROUND';
      NO_LOAD_CHECK='Both';
      NO_IO_CHECK='Both';
      NO_ASSERT_CHECK='TRUE';
      NO_DIR_CHECK='TRUE';
      ALLOW_CONNECT='TRUE';
    'VSS'<263>:
      PIN_NUMBER='(0,0,0,0,0,0,0,0,0,0,0,0,0,0,0,0,0,0,0,0,0,0,0,0,0,0,0,0,DC70,0)';
      PINUSE='GROUND';
      NO_LOAD_CHECK='Both';
      NO_IO_CHECK='Both';
      NO_ASSERT_CHECK='TRUE';
      NO_DIR_CHECK='TRUE';
      ALLOW_CONNECT='TRUE';
    'VSS'<262>:
      PIN_NUMBER='(0,0,0,0,0,0,0,0,0,0,0,0,0,0,0,0,0,0,0,0,0,0,0,0,0,0,0,0,DC78,0)';
      PINUSE='GROUND';
      NO_LOAD_CHECK='Both';
      NO_IO_CHECK='Both';
      NO_ASSERT_CHECK='TRUE';
      NO_DIR_CHECK='TRUE';
      ALLOW_CONNECT='TRUE';
    'VSS'<261>:
      PIN_NUMBER='(0,0,0,0,0,0,0,0,0,0,0,0,0,0,0,0,0,0,0,0,0,0,0,0,0,0,0,0,DC84,0)';
      PINUSE='GROUND';
      NO_LOAD_CHECK='Both';
      NO_IO_CHECK='Both';
      NO_ASSERT_CHECK='TRUE';
      NO_DIR_CHECK='TRUE';
      ALLOW_CONNECT='TRUE';
    'VSS'<260>:
      PIN_NUMBER='(0,0,0,0,0,0,0,0,0,0,0,0,0,0,0,0,0,0,0,0,0,0,0,0,0,0,0,0,DC86,0)';
      PINUSE='GROUND';
      NO_LOAD_CHECK='Both';
      NO_IO_CHECK='Both';
      NO_ASSERT_CHECK='TRUE';
      NO_DIR_CHECK='TRUE';
      ALLOW_CONNECT='TRUE';
    'VSS'<259>:
      PIN_NUMBER='(0,0,0,0,0,0,0,0,0,0,0,0,0,0,0,0,0,0,0,0,0,0,0,0,0,0,0,0,DD11,0)';
      PINUSE='GROUND';
      NO_LOAD_CHECK='Both';
      NO_IO_CHECK='Both';
      NO_ASSERT_CHECK='TRUE';
      NO_DIR_CHECK='TRUE';
      ALLOW_CONNECT='TRUE';
    'VSS'<258>:
      PIN_NUMBER='(0,0,0,0,0,0,0,0,0,0,0,0,0,0,0,0,0,0,0,0,0,0,0,0,0,0,0,0,DD23,0)';
      PINUSE='GROUND';
      NO_LOAD_CHECK='Both';
      NO_IO_CHECK='Both';
      NO_ASSERT_CHECK='TRUE';
      NO_DIR_CHECK='TRUE';
      ALLOW_CONNECT='TRUE';
    'VSS'<257>:
      PIN_NUMBER='(0,0,0,0,0,0,0,0,0,0,0,0,0,0,0,0,0,0,0,0,0,0,0,0,0,0,0,0,DD27,0)';
      PINUSE='GROUND';
      NO_LOAD_CHECK='Both';
      NO_IO_CHECK='Both';
      NO_ASSERT_CHECK='TRUE';
      NO_DIR_CHECK='TRUE';
      ALLOW_CONNECT='TRUE';
    'VSS'<256>:
      PIN_NUMBER='(0,0,0,0,0,0,0,0,0,0,0,0,0,0,0,0,0,0,0,0,0,0,0,0,0,0,0,0,DD31,0)';
      PINUSE='GROUND';
      NO_LOAD_CHECK='Both';
      NO_IO_CHECK='Both';
      NO_ASSERT_CHECK='TRUE';
      NO_DIR_CHECK='TRUE';
      ALLOW_CONNECT='TRUE';
    'VSS'<255>:
      PIN_NUMBER='(0,0,0,0,0,0,0,0,0,0,0,0,0,0,0,0,0,0,0,0,0,0,0,0,0,0,0,0,DD33,0)';
      PINUSE='GROUND';
      NO_LOAD_CHECK='Both';
      NO_IO_CHECK='Both';
      NO_ASSERT_CHECK='TRUE';
      NO_DIR_CHECK='TRUE';
      ALLOW_CONNECT='TRUE';
    'VSS'<254>:
      PIN_NUMBER='(0,0,0,0,0,0,0,0,0,0,0,0,0,0,0,0,0,0,0,0,0,0,0,0,0,0,0,0,DD37,0)';
      PINUSE='GROUND';
      NO_LOAD_CHECK='Both';
      NO_IO_CHECK='Both';
      NO_ASSERT_CHECK='TRUE';
      NO_DIR_CHECK='TRUE';
      ALLOW_CONNECT='TRUE';
    'VSS'<253>:
      PIN_NUMBER='(0,0,0,0,0,0,0,0,0,0,0,0,0,0,0,0,0,0,0,0,0,0,0,0,0,0,0,0,DD71,0)';
      PINUSE='GROUND';
      NO_LOAD_CHECK='Both';
      NO_IO_CHECK='Both';
      NO_ASSERT_CHECK='TRUE';
      NO_DIR_CHECK='TRUE';
      ALLOW_CONNECT='TRUE';
    'VSS'<252>:
      PIN_NUMBER='(0,0,0,0,0,0,0,0,0,0,0,0,0,0,0,0,0,0,0,0,0,0,0,0,0,0,0,0,DD73,0)';
      PINUSE='GROUND';
      NO_LOAD_CHECK='Both';
      NO_IO_CHECK='Both';
      NO_ASSERT_CHECK='TRUE';
      NO_DIR_CHECK='TRUE';
      ALLOW_CONNECT='TRUE';
    'VSS'<251>:
      PIN_NUMBER='(0,0,0,0,0,0,0,0,0,0,0,0,0,0,0,0,0,0,0,0,0,0,0,0,0,0,0,0,DD75,0)';
      PINUSE='GROUND';
      NO_LOAD_CHECK='Both';
      NO_IO_CHECK='Both';
      NO_ASSERT_CHECK='TRUE';
      NO_DIR_CHECK='TRUE';
      ALLOW_CONNECT='TRUE';
    'VSS'<250>:
      PIN_NUMBER='(0,0,0,0,0,0,0,0,0,0,0,0,0,0,0,0,0,0,0,0,0,0,0,0,0,0,0,0,DD81,0)';
      PINUSE='GROUND';
      NO_LOAD_CHECK='Both';
      NO_IO_CHECK='Both';
      NO_ASSERT_CHECK='TRUE';
      NO_DIR_CHECK='TRUE';
      ALLOW_CONNECT='TRUE';
    'VSS'<249>:
      PIN_NUMBER='(0,0,0,0,0,0,0,0,0,0,0,0,0,0,0,0,0,0,0,0,0,0,0,0,0,0,0,0,DD83,0)';
      PINUSE='GROUND';
      NO_LOAD_CHECK='Both';
      NO_IO_CHECK='Both';
      NO_ASSERT_CHECK='TRUE';
      NO_DIR_CHECK='TRUE';
      ALLOW_CONNECT='TRUE';
    'VSS'<248>:
      PIN_NUMBER='(0,0,0,0,0,0,0,0,0,0,0,0,0,0,0,0,0,0,0,0,0,0,0,0,0,0,0,0,DE6,0)';
      PINUSE='GROUND';
      NO_LOAD_CHECK='Both';
      NO_IO_CHECK='Both';
      NO_ASSERT_CHECK='TRUE';
      NO_DIR_CHECK='TRUE';
      ALLOW_CONNECT='TRUE';
    'VSS'<247>:
      PIN_NUMBER='(0,0,0,0,0,0,0,0,0,0,0,0,0,0,0,0,0,0,0,0,0,0,0,0,0,0,0,0,DE8,0)';
      PINUSE='GROUND';
      NO_LOAD_CHECK='Both';
      NO_IO_CHECK='Both';
      NO_ASSERT_CHECK='TRUE';
      NO_DIR_CHECK='TRUE';
      ALLOW_CONNECT='TRUE';
    'VSS'<246>:
      PIN_NUMBER='(0,0,0,0,0,0,0,0,0,0,0,0,0,0,0,0,0,0,0,0,0,0,0,0,0,0,0,0,DE18,0)';
      PINUSE='GROUND';
      NO_LOAD_CHECK='Both';
      NO_IO_CHECK='Both';
      NO_ASSERT_CHECK='TRUE';
      NO_DIR_CHECK='TRUE';
      ALLOW_CONNECT='TRUE';
    'VSS'<245>:
      PIN_NUMBER='(0,0,0,0,0,0,0,0,0,0,0,0,0,0,0,0,0,0,0,0,0,0,0,0,0,0,0,0,DE20,0)';
      PINUSE='GROUND';
      NO_LOAD_CHECK='Both';
      NO_IO_CHECK='Both';
      NO_ASSERT_CHECK='TRUE';
      NO_DIR_CHECK='TRUE';
      ALLOW_CONNECT='TRUE';
    'VSS'<244>:
      PIN_NUMBER='(0,0,0,0,0,0,0,0,0,0,0,0,0,0,0,0,0,0,0,0,0,0,0,0,0,0,0,0,DE24,0)';
      PINUSE='GROUND';
      NO_LOAD_CHECK='Both';
      NO_IO_CHECK='Both';
      NO_ASSERT_CHECK='TRUE';
      NO_DIR_CHECK='TRUE';
      ALLOW_CONNECT='TRUE';
    'VSS'<243>:
      PIN_NUMBER='(0,0,0,0,0,0,0,0,0,0,0,0,0,0,0,0,0,0,0,0,0,0,0,0,0,0,0,0,DE28,0)';
      PINUSE='GROUND';
      NO_LOAD_CHECK='Both';
      NO_IO_CHECK='Both';
      NO_ASSERT_CHECK='TRUE';
      NO_DIR_CHECK='TRUE';
      ALLOW_CONNECT='TRUE';
    'VSS'<242>:
      PIN_NUMBER='(0,0,0,0,0,0,0,0,0,0,0,0,0,0,0,0,0,0,0,0,0,0,0,0,0,0,0,0,DE30,0)';
      PINUSE='GROUND';
      NO_LOAD_CHECK='Both';
      NO_IO_CHECK='Both';
      NO_ASSERT_CHECK='TRUE';
      NO_DIR_CHECK='TRUE';
      ALLOW_CONNECT='TRUE';
    'VSS'<241>:
      PIN_NUMBER='(0,0,0,0,0,0,0,0,0,0,0,0,0,0,0,0,0,0,0,0,0,0,0,0,0,0,0,0,DE34,0)';
      PINUSE='GROUND';
      NO_LOAD_CHECK='Both';
      NO_IO_CHECK='Both';
      NO_ASSERT_CHECK='TRUE';
      NO_DIR_CHECK='TRUE';
      ALLOW_CONNECT='TRUE';
    'VSS'<240>:
      PIN_NUMBER='(0,0,0,0,0,0,0,0,0,0,0,0,0,0,0,0,0,0,0,0,0,0,0,0,0,0,0,0,DE36,0)';
      PINUSE='GROUND';
      NO_LOAD_CHECK='Both';
      NO_IO_CHECK='Both';
      NO_ASSERT_CHECK='TRUE';
      NO_DIR_CHECK='TRUE';
      ALLOW_CONNECT='TRUE';
    'VSS'<239>:
      PIN_NUMBER='(0,0,0,0,0,0,0,0,0,0,0,0,0,0,0,0,0,0,0,0,0,0,0,0,0,0,0,0,DE64,0)';
      PINUSE='GROUND';
      NO_LOAD_CHECK='Both';
      NO_IO_CHECK='Both';
      NO_ASSERT_CHECK='TRUE';
      NO_DIR_CHECK='TRUE';
      ALLOW_CONNECT='TRUE';
    'VSS'<238>:
      PIN_NUMBER='(0,0,0,0,0,0,0,0,0,0,0,0,0,0,0,0,0,0,0,0,0,0,0,0,0,0,0,0,DE70,0)';
      PINUSE='GROUND';
      NO_LOAD_CHECK='Both';
      NO_IO_CHECK='Both';
      NO_ASSERT_CHECK='TRUE';
      NO_DIR_CHECK='TRUE';
      ALLOW_CONNECT='TRUE';
    'VSS'<237>:
      PIN_NUMBER='(0,0,0,0,0,0,0,0,0,0,0,0,0,0,0,0,0,0,0,0,0,0,0,0,0,0,0,0,DE72,0)';
      PINUSE='GROUND';
      NO_LOAD_CHECK='Both';
      NO_IO_CHECK='Both';
      NO_ASSERT_CHECK='TRUE';
      NO_DIR_CHECK='TRUE';
      ALLOW_CONNECT='TRUE';
    'VSS'<236>:
      PIN_NUMBER='(0,0,0,0,0,0,0,0,0,0,0,0,0,0,0,0,0,0,0,0,0,0,0,0,0,0,0,0,DE78,0)';
      PINUSE='GROUND';
      NO_LOAD_CHECK='Both';
      NO_IO_CHECK='Both';
      NO_ASSERT_CHECK='TRUE';
      NO_DIR_CHECK='TRUE';
      ALLOW_CONNECT='TRUE';
    'VSS'<235>:
      PIN_NUMBER='(0,0,0,0,0,0,0,0,0,0,0,0,0,0,0,0,0,0,0,0,0,0,0,0,0,0,0,0,DF5,0)';
      PINUSE='GROUND';
      NO_LOAD_CHECK='Both';
      NO_IO_CHECK='Both';
      NO_ASSERT_CHECK='TRUE';
      NO_DIR_CHECK='TRUE';
      ALLOW_CONNECT='TRUE';
    'VSS'<234>:
      PIN_NUMBER='(0,0,0,0,0,0,0,0,0,0,0,0,0,0,0,0,0,0,0,0,0,0,0,0,0,0,0,0,DF7,0)';
      PINUSE='GROUND';
      NO_LOAD_CHECK='Both';
      NO_IO_CHECK='Both';
      NO_ASSERT_CHECK='TRUE';
      NO_DIR_CHECK='TRUE';
      ALLOW_CONNECT='TRUE';
    'VSS'<233>:
      PIN_NUMBER='(0,0,0,0,0,0,0,0,0,0,0,0,0,0,0,0,0,0,0,0,0,0,0,0,0,0,0,0,H51,0)';
      PINUSE='GROUND';
      NO_LOAD_CHECK='Both';
      NO_IO_CHECK='Both';
      NO_ASSERT_CHECK='TRUE';
      NO_DIR_CHECK='TRUE';
      ALLOW_CONNECT='TRUE';
    'VSS'<232>:
      PIN_NUMBER='(0,0,0,0,0,0,0,0,0,0,0,0,0,0,0,0,0,0,0,0,0,0,0,0,0,0,0,0,DF19,0)';
      PINUSE='GROUND';
      NO_LOAD_CHECK='Both';
      NO_IO_CHECK='Both';
      NO_ASSERT_CHECK='TRUE';
      NO_DIR_CHECK='TRUE';
      ALLOW_CONNECT='TRUE';
    'VSS'<231>:
      PIN_NUMBER='(0,0,0,0,0,0,0,0,0,0,0,0,0,0,0,0,0,0,0,0,0,0,0,0,0,0,0,0,DF29,0)';
      PINUSE='GROUND';
      NO_LOAD_CHECK='Both';
      NO_IO_CHECK='Both';
      NO_ASSERT_CHECK='TRUE';
      NO_DIR_CHECK='TRUE';
      ALLOW_CONNECT='TRUE';
    'VSS'<230>:
      PIN_NUMBER='(0,0,0,0,0,0,0,0,0,0,0,0,0,0,0,0,0,0,0,0,0,0,0,0,0,0,0,0,DF35,0)';
      PINUSE='GROUND';
      NO_LOAD_CHECK='Both';
      NO_IO_CHECK='Both';
      NO_ASSERT_CHECK='TRUE';
      NO_DIR_CHECK='TRUE';
      ALLOW_CONNECT='TRUE';
    'VSS'<229>:
      PIN_NUMBER='(0,0,0,0,0,0,0,0,0,0,0,0,0,0,0,0,0,0,0,0,0,0,0,0,0,0,0,0,DF37,0)';
      PINUSE='GROUND';
      NO_LOAD_CHECK='Both';
      NO_IO_CHECK='Both';
      NO_ASSERT_CHECK='TRUE';
      NO_DIR_CHECK='TRUE';
      ALLOW_CONNECT='TRUE';
    'VSS'<228>:
      PIN_NUMBER='(0,0,0,0,0,0,0,0,0,0,0,0,0,0,0,0,0,0,0,0,0,0,0,0,0,0,0,0,DF39,0)';
      PINUSE='GROUND';
      NO_LOAD_CHECK='Both';
      NO_IO_CHECK='Both';
      NO_ASSERT_CHECK='TRUE';
      NO_DIR_CHECK='TRUE';
      ALLOW_CONNECT='TRUE';
    'VSS'<227>:
      PIN_NUMBER='(0,0,0,0,0,0,0,0,0,0,0,0,0,0,0,0,0,0,0,0,0,0,0,0,0,0,0,0,DF41,0)';
      PINUSE='GROUND';
      NO_LOAD_CHECK='Both';
      NO_IO_CHECK='Both';
      NO_ASSERT_CHECK='TRUE';
      NO_DIR_CHECK='TRUE';
      ALLOW_CONNECT='TRUE';
    'VSS'<226>:
      PIN_NUMBER='(0,0,0,0,0,0,0,0,0,0,0,0,0,0,0,0,0,0,0,0,0,0,0,0,0,0,0,0,DF65,0)';
      PINUSE='GROUND';
      NO_LOAD_CHECK='Both';
      NO_IO_CHECK='Both';
      NO_ASSERT_CHECK='TRUE';
      NO_DIR_CHECK='TRUE';
      ALLOW_CONNECT='TRUE';
    'VSS'<225>:
      PIN_NUMBER='(0,0,0,0,0,0,0,0,0,0,0,0,0,0,0,0,0,0,0,0,0,0,0,0,0,0,0,0,DF69,0)';
      PINUSE='GROUND';
      NO_LOAD_CHECK='Both';
      NO_IO_CHECK='Both';
      NO_ASSERT_CHECK='TRUE';
      NO_DIR_CHECK='TRUE';
      ALLOW_CONNECT='TRUE';
    'VSS'<224>:
      PIN_NUMBER='(0,0,0,0,0,0,0,0,0,0,0,0,0,0,0,0,0,0,0,0,0,0,0,0,0,0,0,0,DF73,0)';
      PINUSE='GROUND';
      NO_LOAD_CHECK='Both';
      NO_IO_CHECK='Both';
      NO_ASSERT_CHECK='TRUE';
      NO_DIR_CHECK='TRUE';
      ALLOW_CONNECT='TRUE';
    'VSS'<223>:
      PIN_NUMBER='(0,0,0,0,0,0,0,0,0,0,0,0,0,0,0,0,0,0,0,0,0,0,0,0,0,0,0,0,DF79,0)';
      PINUSE='GROUND';
      NO_LOAD_CHECK='Both';
      NO_IO_CHECK='Both';
      NO_ASSERT_CHECK='TRUE';
      NO_DIR_CHECK='TRUE';
      ALLOW_CONNECT='TRUE';
    'VSS'<222>:
      PIN_NUMBER='(0,0,0,0,0,0,0,0,0,0,0,0,0,0,0,0,0,0,0,0,0,0,0,0,0,0,0,0,DF83,0)';
      PINUSE='GROUND';
      NO_LOAD_CHECK='Both';
      NO_IO_CHECK='Both';
      NO_ASSERT_CHECK='TRUE';
      NO_DIR_CHECK='TRUE';
      ALLOW_CONNECT='TRUE';
    'VSS'<221>:
      PIN_NUMBER='(0,0,0,0,0,0,0,0,0,0,0,0,0,0,0,0,0,0,0,0,0,0,0,0,0,0,0,0,DF85,0)';
      PINUSE='GROUND';
      NO_LOAD_CHECK='Both';
      NO_IO_CHECK='Both';
      NO_ASSERT_CHECK='TRUE';
      NO_DIR_CHECK='TRUE';
      ALLOW_CONNECT='TRUE';
    'VSS'<220>:
      PIN_NUMBER='(0,0,0,0,0,0,0,0,0,0,0,0,0,0,0,0,0,0,0,0,0,0,0,0,0,0,0,0,DG2,0)';
      PINUSE='GROUND';
      NO_LOAD_CHECK='Both';
      NO_IO_CHECK='Both';
      NO_ASSERT_CHECK='TRUE';
      NO_DIR_CHECK='TRUE';
      ALLOW_CONNECT='TRUE';
    'VSS'<219>:
      PIN_NUMBER='(0,0,0,0,0,0,0,0,0,0,0,0,0,0,0,0,0,0,0,0,0,0,0,0,0,0,0,0,H49,0)';
      PINUSE='GROUND';
      NO_LOAD_CHECK='Both';
      NO_IO_CHECK='Both';
      NO_ASSERT_CHECK='TRUE';
      NO_DIR_CHECK='TRUE';
      ALLOW_CONNECT='TRUE';
    'VSS'<218>:
      PIN_NUMBER='(0,0,0,0,0,0,0,0,0,0,0,0,0,0,0,0,0,0,0,0,0,0,0,0,0,0,0,0,DG14,0)';
      PINUSE='GROUND';
      NO_LOAD_CHECK='Both';
      NO_IO_CHECK='Both';
      NO_ASSERT_CHECK='TRUE';
      NO_DIR_CHECK='TRUE';
      ALLOW_CONNECT='TRUE';
    'VSS'<217>:
      PIN_NUMBER='(0,0,0,0,0,0,0,0,0,0,0,0,0,0,0,0,0,0,0,0,0,0,0,0,0,0,0,0,DG16,0)';
      PINUSE='GROUND';
      NO_LOAD_CHECK='Both';
      NO_IO_CHECK='Both';
      NO_ASSERT_CHECK='TRUE';
      NO_DIR_CHECK='TRUE';
      ALLOW_CONNECT='TRUE';
    'VSS'<216>:
      PIN_NUMBER='(0,0,0,0,0,0,0,0,0,0,0,0,0,0,0,0,0,0,0,0,0,0,0,0,0,0,0,0,DG24,0)';
      PINUSE='GROUND';
      NO_LOAD_CHECK='Both';
      NO_IO_CHECK='Both';
      NO_ASSERT_CHECK='TRUE';
      NO_DIR_CHECK='TRUE';
      ALLOW_CONNECT='TRUE';
    'VSS'<215>:
      PIN_NUMBER='(0,0,0,0,0,0,0,0,0,0,0,0,0,0,0,0,0,0,0,0,0,0,0,0,0,0,0,0,DG66,0)';
      PINUSE='GROUND';
      NO_LOAD_CHECK='Both';
      NO_IO_CHECK='Both';
      NO_ASSERT_CHECK='TRUE';
      NO_DIR_CHECK='TRUE';
      ALLOW_CONNECT='TRUE';
    'VSS'<214>:
      PIN_NUMBER='(0,0,0,0,0,0,0,0,0,0,0,0,0,0,0,0,0,0,0,0,0,0,0,0,0,0,0,0,DG68,0)';
      PINUSE='GROUND';
      NO_LOAD_CHECK='Both';
      NO_IO_CHECK='Both';
      NO_ASSERT_CHECK='TRUE';
      NO_DIR_CHECK='TRUE';
      ALLOW_CONNECT='TRUE';
    'VSS'<213>:
      PIN_NUMBER='(0,0,0,0,0,0,0,0,0,0,0,0,0,0,0,0,0,0,0,0,0,0,0,0,0,0,0,0,DG76,0)';
      PINUSE='GROUND';
      NO_LOAD_CHECK='Both';
      NO_IO_CHECK='Both';
      NO_ASSERT_CHECK='TRUE';
      NO_DIR_CHECK='TRUE';
      ALLOW_CONNECT='TRUE';
    'VSS'<212>:
      PIN_NUMBER='(0,0,0,0,0,0,0,0,0,0,0,0,0,0,0,0,0,0,0,0,0,0,0,0,0,0,0,0,DG78,0)';
      PINUSE='GROUND';
      NO_LOAD_CHECK='Both';
      NO_IO_CHECK='Both';
      NO_ASSERT_CHECK='TRUE';
      NO_DIR_CHECK='TRUE';
      ALLOW_CONNECT='TRUE';
    'VSS'<211>:
      PIN_NUMBER='(0,0,0,0,0,0,0,0,0,0,0,0,0,0,0,0,0,0,0,0,0,0,0,0,0,0,0,0,DG80,0)';
      PINUSE='GROUND';
      NO_LOAD_CHECK='Both';
      NO_IO_CHECK='Both';
      NO_ASSERT_CHECK='TRUE';
      NO_DIR_CHECK='TRUE';
      ALLOW_CONNECT='TRUE';
    'VSS'<210>:
      PIN_NUMBER='(0,0,0,0,0,0,0,0,0,0,0,0,0,0,0,0,0,0,0,0,0,0,0,0,0,0,0,0,DG82,0)';
      PINUSE='GROUND';
      NO_LOAD_CHECK='Both';
      NO_IO_CHECK='Both';
      NO_ASSERT_CHECK='TRUE';
      NO_DIR_CHECK='TRUE';
      ALLOW_CONNECT='TRUE';
    'VSS'<209>:
      PIN_NUMBER='(0,0,0,0,0,0,0,0,0,0,0,0,0,0,0,0,0,0,0,0,0,0,0,0,0,0,0,0,DH13,0)';
      PINUSE='GROUND';
      NO_LOAD_CHECK='Both';
      NO_IO_CHECK='Both';
      NO_ASSERT_CHECK='TRUE';
      NO_DIR_CHECK='TRUE';
      ALLOW_CONNECT='TRUE';
    'VSS'<208>:
      PIN_NUMBER='(0,0,0,0,0,0,0,0,0,0,0,0,0,0,0,0,0,0,0,0,0,0,0,0,0,0,0,0,DH15,0)';
      PINUSE='GROUND';
      NO_LOAD_CHECK='Both';
      NO_IO_CHECK='Both';
      NO_ASSERT_CHECK='TRUE';
      NO_DIR_CHECK='TRUE';
      ALLOW_CONNECT='TRUE';
    'VSS'<207>:
      PIN_NUMBER='(0,0,0,0,0,0,0,0,0,0,0,0,0,0,0,0,0,0,0,0,0,0,0,0,0,0,0,0,DH23,0)';
      PINUSE='GROUND';
      NO_LOAD_CHECK='Both';
      NO_IO_CHECK='Both';
      NO_ASSERT_CHECK='TRUE';
      NO_DIR_CHECK='TRUE';
      ALLOW_CONNECT='TRUE';
    'VSS'<206>:
      PIN_NUMBER='(0,0,0,0,0,0,0,0,0,0,0,0,0,0,0,0,0,0,0,0,0,0,0,0,0,0,0,0,DH25,0)';
      PINUSE='GROUND';
      NO_LOAD_CHECK='Both';
      NO_IO_CHECK='Both';
      NO_ASSERT_CHECK='TRUE';
      NO_DIR_CHECK='TRUE';
      ALLOW_CONNECT='TRUE';
    'VSS'<205>:
      PIN_NUMBER='(0,0,0,0,0,0,0,0,0,0,0,0,0,0,0,0,0,0,0,0,0,0,0,0,0,0,0,0,DH27,0)';
      PINUSE='GROUND';
      NO_LOAD_CHECK='Both';
      NO_IO_CHECK='Both';
      NO_ASSERT_CHECK='TRUE';
      NO_DIR_CHECK='TRUE';
      ALLOW_CONNECT='TRUE';
    'VSS'<204>:
      PIN_NUMBER='(0,0,0,0,0,0,0,0,0,0,0,0,0,0,0,0,0,0,0,0,0,0,0,0,0,0,0,0,DH29,0)';
      PINUSE='GROUND';
      NO_LOAD_CHECK='Both';
      NO_IO_CHECK='Both';
      NO_ASSERT_CHECK='TRUE';
      NO_DIR_CHECK='TRUE';
      ALLOW_CONNECT='TRUE';
    'VSS'<203>:
      PIN_NUMBER='(0,0,0,0,0,0,0,0,0,0,0,0,0,0,0,0,0,0,0,0,0,0,0,0,0,0,0,0,DH31,0)';
      PINUSE='GROUND';
      NO_LOAD_CHECK='Both';
      NO_IO_CHECK='Both';
      NO_ASSERT_CHECK='TRUE';
      NO_DIR_CHECK='TRUE';
      ALLOW_CONNECT='TRUE';
    'VSS'<202>:
      PIN_NUMBER='(0,0,0,0,0,0,0,0,0,0,0,0,0,0,0,0,0,0,0,0,0,0,0,0,0,0,0,0,DH33,0)';
      PINUSE='GROUND';
      NO_LOAD_CHECK='Both';
      NO_IO_CHECK='Both';
      NO_ASSERT_CHECK='TRUE';
      NO_DIR_CHECK='TRUE';
      ALLOW_CONNECT='TRUE';
    'VSS'<201>:
      PIN_NUMBER='(0,0,0,0,0,0,0,0,0,0,0,0,0,0,0,0,0,0,0,0,0,0,0,0,0,0,0,0,DH35,0)';
      PINUSE='GROUND';
      NO_LOAD_CHECK='Both';
      NO_IO_CHECK='Both';
      NO_ASSERT_CHECK='TRUE';
      NO_DIR_CHECK='TRUE';
      ALLOW_CONNECT='TRUE';
    'VSS'<200>:
      PIN_NUMBER='(0,0,0,0,0,0,0,0,0,0,0,0,0,0,0,0,0,0,0,0,0,0,0,0,0,0,0,0,DH37,0)';
      PINUSE='GROUND';
      NO_LOAD_CHECK='Both';
      NO_IO_CHECK='Both';
      NO_ASSERT_CHECK='TRUE';
      NO_DIR_CHECK='TRUE';
      ALLOW_CONNECT='TRUE';
    'VSS'<199>:
      PIN_NUMBER='(0,0,0,0,0,0,0,0,0,0,0,0,0,0,0,0,0,0,0,0,0,0,0,0,0,0,0,0,DH41,0)';
      PINUSE='GROUND';
      NO_LOAD_CHECK='Both';
      NO_IO_CHECK='Both';
      NO_ASSERT_CHECK='TRUE';
      NO_DIR_CHECK='TRUE';
      ALLOW_CONNECT='TRUE';
    'VSS'<198>:
      PIN_NUMBER='(0,0,0,0,0,0,0,0,0,0,0,0,0,0,0,0,0,0,0,0,0,0,0,0,0,0,0,0,DH67,0)';
      PINUSE='GROUND';
      NO_LOAD_CHECK='Both';
      NO_IO_CHECK='Both';
      NO_ASSERT_CHECK='TRUE';
      NO_DIR_CHECK='TRUE';
      ALLOW_CONNECT='TRUE';
    'VSS'<197>:
      PIN_NUMBER='(0,0,0,0,0,0,0,0,0,0,0,0,0,0,0,0,0,0,0,0,0,0,0,0,0,0,0,0,DH71,0)';
      PINUSE='GROUND';
      NO_LOAD_CHECK='Both';
      NO_IO_CHECK='Both';
      NO_ASSERT_CHECK='TRUE';
      NO_DIR_CHECK='TRUE';
      ALLOW_CONNECT='TRUE';
    'VSS'<196>:
      PIN_NUMBER='(0,0,0,0,0,0,0,0,0,0,0,0,0,0,0,0,0,0,0,0,0,0,0,0,0,0,0,0,DH73,0)';
      PINUSE='GROUND';
      NO_LOAD_CHECK='Both';
      NO_IO_CHECK='Both';
      NO_ASSERT_CHECK='TRUE';
      NO_DIR_CHECK='TRUE';
      ALLOW_CONNECT='TRUE';
    'VSS'<195>:
      PIN_NUMBER='(0,0,0,0,0,0,0,0,0,0,0,0,0,0,0,0,0,0,0,0,0,0,0,0,0,0,0,0,DH79,0)';
      PINUSE='GROUND';
      NO_LOAD_CHECK='Both';
      NO_IO_CHECK='Both';
      NO_ASSERT_CHECK='TRUE';
      NO_DIR_CHECK='TRUE';
      ALLOW_CONNECT='TRUE';
    'VSS'<194>:
      PIN_NUMBER='(0,0,0,0,0,0,0,0,0,0,0,0,0,0,0,0,0,0,0,0,0,0,0,0,0,0,0,0,DH81,0)';
      PINUSE='GROUND';
      NO_LOAD_CHECK='Both';
      NO_IO_CHECK='Both';
      NO_ASSERT_CHECK='TRUE';
      NO_DIR_CHECK='TRUE';
      ALLOW_CONNECT='TRUE';
    'VSS'<193>:
      PIN_NUMBER='(0,0,0,0,0,0,0,0,0,0,0,0,0,0,0,0,0,0,0,0,0,0,0,0,0,0,0,0,DH83,0)';
      PINUSE='GROUND';
      NO_LOAD_CHECK='Both';
      NO_IO_CHECK='Both';
      NO_ASSERT_CHECK='TRUE';
      NO_DIR_CHECK='TRUE';
      ALLOW_CONNECT='TRUE';
    'VSS'<192>:
      PIN_NUMBER='(0,0,0,0,0,0,0,0,0,0,0,0,0,0,0,0,0,0,0,0,0,0,0,0,0,0,0,0,DJ2,0)';
      PINUSE='GROUND';
      NO_LOAD_CHECK='Both';
      NO_IO_CHECK='Both';
      NO_ASSERT_CHECK='TRUE';
      NO_DIR_CHECK='TRUE';
      ALLOW_CONNECT='TRUE';
    'VSS'<191>:
      PIN_NUMBER='(0,0,0,0,0,0,0,0,0,0,0,0,0,0,0,0,0,0,0,0,0,0,0,0,0,0,0,0,DJ10,0)';
      PINUSE='GROUND';
      NO_LOAD_CHECK='Both';
      NO_IO_CHECK='Both';
      NO_ASSERT_CHECK='TRUE';
      NO_DIR_CHECK='TRUE';
      ALLOW_CONNECT='TRUE';
    'VSS'<190>:
      PIN_NUMBER='(0,0,0,0,0,0,0,0,0,0,0,0,0,0,0,0,0,0,0,0,0,0,0,0,0,0,0,0,H47,0)';
      PINUSE='GROUND';
      NO_LOAD_CHECK='Both';
      NO_IO_CHECK='Both';
      NO_ASSERT_CHECK='TRUE';
      NO_DIR_CHECK='TRUE';
      ALLOW_CONNECT='TRUE';
    'VSS'<189>:
      PIN_NUMBER='(0,0,0,0,0,0,0,0,0,0,0,0,0,0,0,0,0,0,0,0,0,0,0,0,0,0,0,0,DJ22,0)';
      PINUSE='GROUND';
      NO_LOAD_CHECK='Both';
      NO_IO_CHECK='Both';
      NO_ASSERT_CHECK='TRUE';
      NO_DIR_CHECK='TRUE';
      ALLOW_CONNECT='TRUE';
    'VSS'<188>:
      PIN_NUMBER='(0,0,0,0,0,0,0,0,0,0,0,0,0,0,0,0,0,0,0,0,0,0,0,0,0,0,0,0,DJ38,0)';
      PINUSE='GROUND';
      NO_LOAD_CHECK='Both';
      NO_IO_CHECK='Both';
      NO_ASSERT_CHECK='TRUE';
      NO_DIR_CHECK='TRUE';
      ALLOW_CONNECT='TRUE';
    'VSS'<187>:
      PIN_NUMBER='(0,0,0,0,0,0,0,0,0,0,0,0,0,0,0,0,0,0,0,0,0,0,0,0,0,0,0,0,DJ42,0)';
      PINUSE='GROUND';
      NO_LOAD_CHECK='Both';
      NO_IO_CHECK='Both';
      NO_ASSERT_CHECK='TRUE';
      NO_DIR_CHECK='TRUE';
      ALLOW_CONNECT='TRUE';
    'VSS'<186>:
      PIN_NUMBER='(0,0,0,0,0,0,0,0,0,0,0,0,0,0,0,0,0,0,0,0,0,0,0,0,0,0,0,0,DJ68,0)';
      PINUSE='GROUND';
      NO_LOAD_CHECK='Both';
      NO_IO_CHECK='Both';
      NO_ASSERT_CHECK='TRUE';
      NO_DIR_CHECK='TRUE';
      ALLOW_CONNECT='TRUE';
    'VSS'<185>:
      PIN_NUMBER='(0,0,0,0,0,0,0,0,0,0,0,0,0,0,0,0,0,0,0,0,0,0,0,0,0,0,0,0,DJ74,0)';
      PINUSE='GROUND';
      NO_LOAD_CHECK='Both';
      NO_IO_CHECK='Both';
      NO_ASSERT_CHECK='TRUE';
      NO_DIR_CHECK='TRUE';
      ALLOW_CONNECT='TRUE';
    'VSS'<184>:
      PIN_NUMBER='(0,0,0,0,0,0,0,0,0,0,0,0,0,0,0,0,0,0,0,0,0,0,0,0,0,0,0,0,DJ78,0)';
      PINUSE='GROUND';
      NO_LOAD_CHECK='Both';
      NO_IO_CHECK='Both';
      NO_ASSERT_CHECK='TRUE';
      NO_DIR_CHECK='TRUE';
      ALLOW_CONNECT='TRUE';
    'VSS'<183>:
      PIN_NUMBER='(0,0,0,0,0,0,0,0,0,0,0,0,0,0,0,0,0,0,0,0,0,0,0,0,0,0,0,0,DJ82,0)';
      PINUSE='GROUND';
      NO_LOAD_CHECK='Both';
      NO_IO_CHECK='Both';
      NO_ASSERT_CHECK='TRUE';
      NO_DIR_CHECK='TRUE';
      ALLOW_CONNECT='TRUE';
    'VSS'<182>:
      PIN_NUMBER='(0,0,0,0,0,0,0,0,0,0,0,0,0,0,0,0,0,0,0,0,0,0,0,0,0,0,0,0,DJ84,0)';
      PINUSE='GROUND';
      NO_LOAD_CHECK='Both';
      NO_IO_CHECK='Both';
      NO_ASSERT_CHECK='TRUE';
      NO_DIR_CHECK='TRUE';
      ALLOW_CONNECT='TRUE';
    'VSS'<181>:
      PIN_NUMBER='(0,0,0,0,0,0,0,0,0,0,0,0,0,0,0,0,0,0,0,0,0,0,0,0,0,0,0,0,DK7,0)';
      PINUSE='GROUND';
      NO_LOAD_CHECK='Both';
      NO_IO_CHECK='Both';
      NO_ASSERT_CHECK='TRUE';
      NO_DIR_CHECK='TRUE';
      ALLOW_CONNECT='TRUE';
    'VSS'<180>:
      PIN_NUMBER='(0,0,0,0,0,0,0,0,0,0,0,0,0,0,0,0,0,0,0,0,0,0,0,0,0,0,0,0,DK23,0)';
      PINUSE='GROUND';
      NO_LOAD_CHECK='Both';
      NO_IO_CHECK='Both';
      NO_ASSERT_CHECK='TRUE';
      NO_DIR_CHECK='TRUE';
      ALLOW_CONNECT='TRUE';
    'VSS'<179>:
      PIN_NUMBER='(0,0,0,0,0,0,0,0,0,0,0,0,0,0,0,0,0,0,0,0,0,0,0,0,0,0,0,0,DK29,0)';
      PINUSE='GROUND';
      NO_LOAD_CHECK='Both';
      NO_IO_CHECK='Both';
      NO_ASSERT_CHECK='TRUE';
      NO_DIR_CHECK='TRUE';
      ALLOW_CONNECT='TRUE';
    'VSS'<178>:
      PIN_NUMBER='(0,0,0,0,0,0,0,0,0,0,0,0,0,0,0,0,0,0,0,0,0,0,0,0,0,0,0,0,DK35,0)';
      PINUSE='GROUND';
      NO_LOAD_CHECK='Both';
      NO_IO_CHECK='Both';
      NO_ASSERT_CHECK='TRUE';
      NO_DIR_CHECK='TRUE';
      ALLOW_CONNECT='TRUE';
    'VSS'<177>:
      PIN_NUMBER='(0,0,0,0,0,0,0,0,0,0,0,0,0,0,0,0,0,0,0,0,0,0,0,0,0,0,0,0,DK39,0)';
      PINUSE='GROUND';
      NO_LOAD_CHECK='Both';
      NO_IO_CHECK='Both';
      NO_ASSERT_CHECK='TRUE';
      NO_DIR_CHECK='TRUE';
      ALLOW_CONNECT='TRUE';
    'VSS'<176>:
      PIN_NUMBER='(0,0,0,0,0,0,0,0,0,0,0,0,0,0,0,0,0,0,0,0,0,0,0,0,0,0,0,0,DK41,0)';
      PINUSE='GROUND';
      NO_LOAD_CHECK='Both';
      NO_IO_CHECK='Both';
      NO_ASSERT_CHECK='TRUE';
      NO_DIR_CHECK='TRUE';
      ALLOW_CONNECT='TRUE';
    'VSS'<175>:
      PIN_NUMBER='(0,0,0,0,0,0,0,0,0,0,0,0,0,0,0,0,0,0,0,0,0,0,0,0,0,0,0,0,DK73,0)';
      PINUSE='GROUND';
      NO_LOAD_CHECK='Both';
      NO_IO_CHECK='Both';
      NO_ASSERT_CHECK='TRUE';
      NO_DIR_CHECK='TRUE';
      ALLOW_CONNECT='TRUE';
    'VSS'<174>:
      PIN_NUMBER='(0,0,0,0,0,0,0,0,0,0,0,0,0,0,0,0,0,0,0,0,0,0,0,0,0,0,0,0,DK75,0)';
      PINUSE='GROUND';
      NO_LOAD_CHECK='Both';
      NO_IO_CHECK='Both';
      NO_ASSERT_CHECK='TRUE';
      NO_DIR_CHECK='TRUE';
      ALLOW_CONNECT='TRUE';
    'VSS'<173>:
      PIN_NUMBER='(0,0,0,0,0,0,0,0,0,0,0,0,0,0,0,0,0,0,0,0,0,0,0,0,0,0,0,0,DK77,0)';
      PINUSE='GROUND';
      NO_LOAD_CHECK='Both';
      NO_IO_CHECK='Both';
      NO_ASSERT_CHECK='TRUE';
      NO_DIR_CHECK='TRUE';
      ALLOW_CONNECT='TRUE';
    'VSS'<172>:
      PIN_NUMBER='(0,0,0,0,0,0,0,0,0,0,0,0,0,0,0,0,0,0,0,0,0,0,0,0,0,0,0,0,DK83,0)';
      PINUSE='GROUND';
      NO_LOAD_CHECK='Both';
      NO_IO_CHECK='Both';
      NO_ASSERT_CHECK='TRUE';
      NO_DIR_CHECK='TRUE';
      ALLOW_CONNECT='TRUE';
    'VSS'<171>:
      PIN_NUMBER='(0,0,0,0,0,0,0,0,0,0,0,0,0,0,0,0,0,0,0,0,0,0,0,0,0,0,0,0,DK85,0)';
      PINUSE='GROUND';
      NO_LOAD_CHECK='Both';
      NO_IO_CHECK='Both';
      NO_ASSERT_CHECK='TRUE';
      NO_DIR_CHECK='TRUE';
      ALLOW_CONNECT='TRUE';
    'VSS'<170>:
      PIN_NUMBER='(0,0,0,0,0,0,0,0,0,0,0,0,0,0,0,0,0,0,0,0,0,0,0,0,0,0,0,0,DL16,0)';
      PINUSE='GROUND';
      NO_LOAD_CHECK='Both';
      NO_IO_CHECK='Both';
      NO_ASSERT_CHECK='TRUE';
      NO_DIR_CHECK='TRUE';
      ALLOW_CONNECT='TRUE';
    'VSS'<169>:
      PIN_NUMBER='(0,0,0,0,0,0,0,0,0,0,0,0,0,0,0,0,0,0,0,0,0,0,0,0,0,0,0,0,DL18,0)';
      PINUSE='GROUND';
      NO_LOAD_CHECK='Both';
      NO_IO_CHECK='Both';
      NO_ASSERT_CHECK='TRUE';
      NO_DIR_CHECK='TRUE';
      ALLOW_CONNECT='TRUE';
    'VSS'<168>:
      PIN_NUMBER='(0,0,0,0,0,0,0,0,0,0,0,0,0,0,0,0,0,0,0,0,0,0,0,0,0,0,0,0,DL4,0)';
      PINUSE='GROUND';
      NO_LOAD_CHECK='Both';
      NO_IO_CHECK='Both';
      NO_ASSERT_CHECK='TRUE';
      NO_DIR_CHECK='TRUE';
      ALLOW_CONNECT='TRUE';
    'VSS'<167>:
      PIN_NUMBER='(0,0,0,0,0,0,0,0,0,0,0,0,0,0,0,0,0,0,0,0,0,0,0,0,0,0,0,0,DL22,0)';
      PINUSE='GROUND';
      NO_LOAD_CHECK='Both';
      NO_IO_CHECK='Both';
      NO_ASSERT_CHECK='TRUE';
      NO_DIR_CHECK='TRUE';
      ALLOW_CONNECT='TRUE';
    'VSS'<166>:
      PIN_NUMBER='(0,0,0,0,0,0,0,0,0,0,0,0,0,0,0,0,0,0,0,0,0,0,0,0,0,0,0,0,DL24,0)';
      PINUSE='GROUND';
      NO_LOAD_CHECK='Both';
      NO_IO_CHECK='Both';
      NO_ASSERT_CHECK='TRUE';
      NO_DIR_CHECK='TRUE';
      ALLOW_CONNECT='TRUE';
    'VSS'<165>:
      PIN_NUMBER='(0,0,0,0,0,0,0,0,0,0,0,0,0,0,0,0,0,0,0,0,0,0,0,0,0,0,0,0,DL28,0)';
      PINUSE='GROUND';
      NO_LOAD_CHECK='Both';
      NO_IO_CHECK='Both';
      NO_ASSERT_CHECK='TRUE';
      NO_DIR_CHECK='TRUE';
      ALLOW_CONNECT='TRUE';
    'VSS'<164>:
      PIN_NUMBER='(0,0,0,0,0,0,0,0,0,0,0,0,0,0,0,0,0,0,0,0,0,0,0,0,0,0,0,0,DL30,0)';
      PINUSE='GROUND';
      NO_LOAD_CHECK='Both';
      NO_IO_CHECK='Both';
      NO_ASSERT_CHECK='TRUE';
      NO_DIR_CHECK='TRUE';
      ALLOW_CONNECT='TRUE';
    'VSS'<163>:
      PIN_NUMBER='(0,0,0,0,0,0,0,0,0,0,0,0,0,0,0,0,0,0,0,0,0,0,0,0,0,0,0,0,DL34,0)';
      PINUSE='GROUND';
      NO_LOAD_CHECK='Both';
      NO_IO_CHECK='Both';
      NO_ASSERT_CHECK='TRUE';
      NO_DIR_CHECK='TRUE';
      ALLOW_CONNECT='TRUE';
    'VSS'<162>:
      PIN_NUMBER='(0,0,0,0,0,0,0,0,0,0,0,0,0,0,0,0,0,0,0,0,0,0,0,0,0,0,0,0,DL36,0)';
      PINUSE='GROUND';
      NO_LOAD_CHECK='Both';
      NO_IO_CHECK='Both';
      NO_ASSERT_CHECK='TRUE';
      NO_DIR_CHECK='TRUE';
      ALLOW_CONNECT='TRUE';
    'VSS'<161>:
      PIN_NUMBER='(0,0,0,0,0,0,0,0,0,0,0,0,0,0,0,0,0,0,0,0,0,0,0,0,0,0,0,0,DL40,0)';
      PINUSE='GROUND';
      NO_LOAD_CHECK='Both';
      NO_IO_CHECK='Both';
      NO_ASSERT_CHECK='TRUE';
      NO_DIR_CHECK='TRUE';
      ALLOW_CONNECT='TRUE';
    'VSS'<160>:
      PIN_NUMBER='(0,0,0,0,0,0,0,0,0,0,0,0,0,0,0,0,0,0,0,0,0,0,0,0,0,0,0,0,DL68,0)';
      PINUSE='GROUND';
      NO_LOAD_CHECK='Both';
      NO_IO_CHECK='Both';
      NO_ASSERT_CHECK='TRUE';
      NO_DIR_CHECK='TRUE';
      ALLOW_CONNECT='TRUE';
    'VSS'<159>:
      PIN_NUMBER='(0,0,0,0,0,0,0,0,0,0,0,0,0,0,0,0,0,0,0,0,0,0,0,0,0,0,0,0,DL70,0)';
      PINUSE='GROUND';
      NO_LOAD_CHECK='Both';
      NO_IO_CHECK='Both';
      NO_ASSERT_CHECK='TRUE';
      NO_DIR_CHECK='TRUE';
      ALLOW_CONNECT='TRUE';
    'VSS'<158>:
      PIN_NUMBER='(0,0,0,0,0,0,0,0,0,0,0,0,0,0,0,0,0,0,0,0,0,0,0,0,0,0,0,0,DL74,0)';
      PINUSE='GROUND';
      NO_LOAD_CHECK='Both';
      NO_IO_CHECK='Both';
      NO_ASSERT_CHECK='TRUE';
      NO_DIR_CHECK='TRUE';
      ALLOW_CONNECT='TRUE';
    'VSS'<157>:
      PIN_NUMBER='(0,0,0,0,0,0,0,0,0,0,0,0,0,0,0,0,0,0,0,0,0,0,0,0,0,0,0,0,DL76,0)';
      PINUSE='GROUND';
      NO_LOAD_CHECK='Both';
      NO_IO_CHECK='Both';
      NO_ASSERT_CHECK='TRUE';
      NO_DIR_CHECK='TRUE';
      ALLOW_CONNECT='TRUE';
    'VSS'<156>:
      PIN_NUMBER='(0,0,0,0,0,0,0,0,0,0,0,0,0,0,0,0,0,0,0,0,0,0,0,0,0,0,0,0,DL78,0)';
      PINUSE='GROUND';
      NO_LOAD_CHECK='Both';
      NO_IO_CHECK='Both';
      NO_ASSERT_CHECK='TRUE';
      NO_DIR_CHECK='TRUE';
      ALLOW_CONNECT='TRUE';
    'VSS'<155>:
      PIN_NUMBER='(0,0,0,0,0,0,0,0,0,0,0,0,0,0,0,0,0,0,0,0,0,0,0,0,0,0,0,0,DL80,0)';
      PINUSE='GROUND';
      NO_LOAD_CHECK='Both';
      NO_IO_CHECK='Both';
      NO_ASSERT_CHECK='TRUE';
      NO_DIR_CHECK='TRUE';
      ALLOW_CONNECT='TRUE';
    'VSS'<154>:
      PIN_NUMBER='(0,0,0,0,0,0,0,0,0,0,0,0,0,0,0,0,0,0,0,0,0,0,0,0,0,0,0,0,DM15,0)';
      PINUSE='GROUND';
      NO_LOAD_CHECK='Both';
      NO_IO_CHECK='Both';
      NO_ASSERT_CHECK='TRUE';
      NO_DIR_CHECK='TRUE';
      ALLOW_CONNECT='TRUE';
    'VSS'<153>:
      PIN_NUMBER='(0,0,0,0,0,0,0,0,0,0,0,0,0,0,0,0,0,0,0,0,0,0,0,0,0,0,0,0,H45,0)';
      PINUSE='GROUND';
      NO_LOAD_CHECK='Both';
      NO_IO_CHECK='Both';
      NO_ASSERT_CHECK='TRUE';
      NO_DIR_CHECK='TRUE';
      ALLOW_CONNECT='TRUE';
    'VSS'<152>:
      PIN_NUMBER='(0,0,0,0,0,0,0,0,0,0,0,0,0,0,0,0,0,0,0,0,0,0,0,0,0,0,0,0,DM25,0)';
      PINUSE='GROUND';
      NO_LOAD_CHECK='Both';
      NO_IO_CHECK='Both';
      NO_ASSERT_CHECK='TRUE';
      NO_DIR_CHECK='TRUE';
      ALLOW_CONNECT='TRUE';
    'VSS'<151>:
      PIN_NUMBER='(0,0,0,0,0,0,0,0,0,0,0,0,0,0,0,0,0,0,0,0,0,0,0,0,0,0,0,0,DM27,0)';
      PINUSE='GROUND';
      NO_LOAD_CHECK='Both';
      NO_IO_CHECK='Both';
      NO_ASSERT_CHECK='TRUE';
      NO_DIR_CHECK='TRUE';
      ALLOW_CONNECT='TRUE';
    'VSS'<150>:
      PIN_NUMBER='(0,0,0,0,0,0,0,0,0,0,0,0,0,0,0,0,0,0,0,0,0,0,0,0,0,0,0,0,DM31,0)';
      PINUSE='GROUND';
      NO_LOAD_CHECK='Both';
      NO_IO_CHECK='Both';
      NO_ASSERT_CHECK='TRUE';
      NO_DIR_CHECK='TRUE';
      ALLOW_CONNECT='TRUE';
    'VSS'<149>:
      PIN_NUMBER='(0,0,0,0,0,0,0,0,0,0,0,0,0,0,0,0,0,0,0,0,0,0,0,0,0,0,0,0,DM33,0)';
      PINUSE='GROUND';
      NO_LOAD_CHECK='Both';
      NO_IO_CHECK='Both';
      NO_ASSERT_CHECK='TRUE';
      NO_DIR_CHECK='TRUE';
      ALLOW_CONNECT='TRUE';
    'VSS'<148>:
      PIN_NUMBER='(0,0,0,0,0,0,0,0,0,0,0,0,0,0,0,0,0,0,0,0,0,0,0,0,0,0,0,0,DM37,0)';
      PINUSE='GROUND';
      NO_LOAD_CHECK='Both';
      NO_IO_CHECK='Both';
      NO_ASSERT_CHECK='TRUE';
      NO_DIR_CHECK='TRUE';
      ALLOW_CONNECT='TRUE';
    'VSS'<147>:
      PIN_NUMBER='(0,0,0,0,0,0,0,0,0,0,0,0,0,0,0,0,0,0,0,0,0,0,0,0,0,0,0,0,DM39,0)';
      PINUSE='GROUND';
      NO_LOAD_CHECK='Both';
      NO_IO_CHECK='Both';
      NO_ASSERT_CHECK='TRUE';
      NO_DIR_CHECK='TRUE';
      ALLOW_CONNECT='TRUE';
    'VSS'<146>:
      PIN_NUMBER='(0,0,0,0,0,0,0,0,0,0,0,0,0,0,0,0,0,0,0,0,0,0,0,0,0,0,0,0,DM65,0)';
      PINUSE='GROUND';
      NO_LOAD_CHECK='Both';
      NO_IO_CHECK='Both';
      NO_ASSERT_CHECK='TRUE';
      NO_DIR_CHECK='TRUE';
      ALLOW_CONNECT='TRUE';
    'VSS'<145>:
      PIN_NUMBER='(0,0,0,0,0,0,0,0,0,0,0,0,0,0,0,0,0,0,0,0,0,0,0,0,0,0,0,0,DM73,0)';
      PINUSE='GROUND';
      NO_LOAD_CHECK='Both';
      NO_IO_CHECK='Both';
      NO_ASSERT_CHECK='TRUE';
      NO_DIR_CHECK='TRUE';
      ALLOW_CONNECT='TRUE';
    'VSS'<144>:
      PIN_NUMBER='(0,0,0,0,0,0,0,0,0,0,0,0,0,0,0,0,0,0,0,0,0,0,0,0,0,0,0,0,DM77,0)';
      PINUSE='GROUND';
      NO_LOAD_CHECK='Both';
      NO_IO_CHECK='Both';
      NO_ASSERT_CHECK='TRUE';
      NO_DIR_CHECK='TRUE';
      ALLOW_CONNECT='TRUE';
    'VSS'<143>:
      PIN_NUMBER='(0,0,0,0,0,0,0,0,0,0,0,0,0,0,0,0,0,0,0,0,0,0,0,0,0,0,0,0,DM83,0)';
      PINUSE='GROUND';
      NO_LOAD_CHECK='Both';
      NO_IO_CHECK='Both';
      NO_ASSERT_CHECK='TRUE';
      NO_DIR_CHECK='TRUE';
      ALLOW_CONNECT='TRUE';
    'VSS'<142>:
      PIN_NUMBER='(0,0,0,0,0,0,0,0,0,0,0,0,0,0,0,0,0,0,0,0,0,0,0,0,0,0,0,0,DN2,0)';
      PINUSE='GROUND';
      NO_LOAD_CHECK='Both';
      NO_IO_CHECK='Both';
      NO_ASSERT_CHECK='TRUE';
      NO_DIR_CHECK='TRUE';
      ALLOW_CONNECT='TRUE';
    'VSS'<141>:
      PIN_NUMBER='(0,0,0,0,0,0,0,0,0,0,0,0,0,0,0,0,0,0,0,0,0,0,0,0,0,0,0,0,BH17,0)';
      PINUSE='GROUND';
      NO_LOAD_CHECK='Both';
      NO_IO_CHECK='Both';
      NO_ASSERT_CHECK='TRUE';
      NO_DIR_CHECK='TRUE';
      ALLOW_CONNECT='TRUE';
    'VSS'<140>:
      PIN_NUMBER='(0,0,0,0,0,0,0,0,0,0,0,0,0,0,0,0,0,0,0,0,0,0,0,0,0,0,0,0,DN12,0)';
      PINUSE='GROUND';
      NO_LOAD_CHECK='Both';
      NO_IO_CHECK='Both';
      NO_ASSERT_CHECK='TRUE';
      NO_DIR_CHECK='TRUE';
      ALLOW_CONNECT='TRUE';
    'VSS'<139>:
      PIN_NUMBER='(0,0,0,0,0,0,0,0,0,0,0,0,0,0,0,0,0,0,0,0,0,0,0,0,0,0,0,0,DN22,0)';
      PINUSE='GROUND';
      NO_LOAD_CHECK='Both';
      NO_IO_CHECK='Both';
      NO_ASSERT_CHECK='TRUE';
      NO_DIR_CHECK='TRUE';
      ALLOW_CONNECT='TRUE';
    'VSS'<138>:
      PIN_NUMBER='(0,0,0,0,0,0,0,0,0,0,0,0,0,0,0,0,0,0,0,0,0,0,0,0,0,0,0,0,DN26,0)';
      PINUSE='GROUND';
      NO_LOAD_CHECK='Both';
      NO_IO_CHECK='Both';
      NO_ASSERT_CHECK='TRUE';
      NO_DIR_CHECK='TRUE';
      ALLOW_CONNECT='TRUE';
    'VSS'<137>:
      PIN_NUMBER='(0,0,0,0,0,0,0,0,0,0,0,0,0,0,0,0,0,0,0,0,0,0,0,0,0,0,0,0,DN32,0)';
      PINUSE='GROUND';
      NO_LOAD_CHECK='Both';
      NO_IO_CHECK='Both';
      NO_ASSERT_CHECK='TRUE';
      NO_DIR_CHECK='TRUE';
      ALLOW_CONNECT='TRUE';
    'VSS'<136>:
      PIN_NUMBER='(0,0,0,0,0,0,0,0,0,0,0,0,0,0,0,0,0,0,0,0,0,0,0,0,0,0,0,0,DN38,0)';
      PINUSE='GROUND';
      NO_LOAD_CHECK='Both';
      NO_IO_CHECK='Both';
      NO_ASSERT_CHECK='TRUE';
      NO_DIR_CHECK='TRUE';
      ALLOW_CONNECT='TRUE';
    'VSS'<135>:
      PIN_NUMBER='(0,0,0,0,0,0,0,0,0,0,0,0,0,0,0,0,0,0,0,0,0,0,0,0,0,0,0,0,DN68,0)';
      PINUSE='GROUND';
      NO_LOAD_CHECK='Both';
      NO_IO_CHECK='Both';
      NO_ASSERT_CHECK='TRUE';
      NO_DIR_CHECK='TRUE';
      ALLOW_CONNECT='TRUE';
    'VSS'<134>:
      PIN_NUMBER='(0,0,0,0,0,0,0,0,0,0,0,0,0,0,0,0,0,0,0,0,0,0,0,0,0,0,0,0,DN72,0)';
      PINUSE='GROUND';
      NO_LOAD_CHECK='Both';
      NO_IO_CHECK='Both';
      NO_ASSERT_CHECK='TRUE';
      NO_DIR_CHECK='TRUE';
      ALLOW_CONNECT='TRUE';
    'VSS'<133>:
      PIN_NUMBER='(0,0,0,0,0,0,0,0,0,0,0,0,0,0,0,0,0,0,0,0,0,0,0,0,0,0,0,0,0,DN78)';
      PINUSE='GROUND';
      NO_LOAD_CHECK='Both';
      NO_IO_CHECK='Both';
      NO_ASSERT_CHECK='TRUE';
      NO_DIR_CHECK='TRUE';
      ALLOW_CONNECT='TRUE';
    'VSS'<132>:
      PIN_NUMBER='(0,0,0,0,0,0,0,0,0,0,0,0,0,0,0,0,0,0,0,0,0,0,0,0,0,0,0,0,0,DP67)';
      PINUSE='GROUND';
      NO_LOAD_CHECK='Both';
      NO_IO_CHECK='Both';
      NO_ASSERT_CHECK='TRUE';
      NO_DIR_CHECK='TRUE';
      ALLOW_CONNECT='TRUE';
    'VSS'<131>:
      PIN_NUMBER='(0,0,0,0,0,0,0,0,0,0,0,0,0,0,0,0,0,0,0,0,0,0,0,0,0,0,0,0,0,DP69)';
      PINUSE='GROUND';
      NO_LOAD_CHECK='Both';
      NO_IO_CHECK='Both';
      NO_ASSERT_CHECK='TRUE';
      NO_DIR_CHECK='TRUE';
      ALLOW_CONNECT='TRUE';
    'VSS'<130>:
      PIN_NUMBER='(0,0,0,0,0,0,0,0,0,0,0,0,0,0,0,0,0,0,0,0,0,0,0,0,0,0,0,0,0,DP71)';
      PINUSE='GROUND';
      NO_LOAD_CHECK='Both';
      NO_IO_CHECK='Both';
      NO_ASSERT_CHECK='TRUE';
      NO_DIR_CHECK='TRUE';
      ALLOW_CONNECT='TRUE';
    'VSS'<129>:
      PIN_NUMBER='(0,0,0,0,0,0,0,0,0,0,0,0,0,0,0,0,0,0,0,0,0,0,0,0,0,0,0,0,0,DP81)';
      PINUSE='GROUND';
      NO_LOAD_CHECK='Both';
      NO_IO_CHECK='Both';
      NO_ASSERT_CHECK='TRUE';
      NO_DIR_CHECK='TRUE';
      ALLOW_CONNECT='TRUE';
    'VSS'<128>:
      PIN_NUMBER='(0,0,0,0,0,0,0,0,0,0,0,0,0,0,0,0,0,0,0,0,0,0,0,0,0,0,0,0,0,DP83)';
      PINUSE='GROUND';
      NO_LOAD_CHECK='Both';
      NO_IO_CHECK='Both';
      NO_ASSERT_CHECK='TRUE';
      NO_DIR_CHECK='TRUE';
      ALLOW_CONNECT='TRUE';
    'VSS'<127>:
      PIN_NUMBER='(0,0,0,0,0,0,0,0,0,0,0,0,0,0,0,0,0,0,0,0,0,0,0,0,0,0,0,0,0,BR26)';
      PINUSE='GROUND';
      NO_LOAD_CHECK='Both';
      NO_IO_CHECK='Both';
      NO_ASSERT_CHECK='TRUE';
      NO_DIR_CHECK='TRUE';
      ALLOW_CONNECT='TRUE';
    'VSS'<126>:
      PIN_NUMBER='(0,0,0,0,0,0,0,0,0,0,0,0,0,0,0,0,0,0,0,0,0,0,0,0,0,0,0,0,0,DR6)';
      PINUSE='GROUND';
      NO_LOAD_CHECK='Both';
      NO_IO_CHECK='Both';
      NO_ASSERT_CHECK='TRUE';
      NO_DIR_CHECK='TRUE';
      ALLOW_CONNECT='TRUE';
    'VSS'<125>:
      PIN_NUMBER='(0,0,0,0,0,0,0,0,0,0,0,0,0,0,0,0,0,0,0,0,0,0,0,0,0,0,0,0,0,CA20)';
      PINUSE='GROUND';
      NO_LOAD_CHECK='Both';
      NO_IO_CHECK='Both';
      NO_ASSERT_CHECK='TRUE';
      NO_DIR_CHECK='TRUE';
      ALLOW_CONNECT='TRUE';
    'VSS'<124>:
      PIN_NUMBER='(0,0,0,0,0,0,0,0,0,0,0,0,0,0,0,0,0,0,0,0,0,0,0,0,0,0,0,0,0,CL22)';
      PINUSE='GROUND';
      NO_LOAD_CHECK='Both';
      NO_IO_CHECK='Both';
      NO_ASSERT_CHECK='TRUE';
      NO_DIR_CHECK='TRUE';
      ALLOW_CONNECT='TRUE';
    'VSS'<123>:
      PIN_NUMBER='(0,0,0,0,0,0,0,0,0,0,0,0,0,0,0,0,0,0,0,0,0,0,0,0,0,0,0,0,0,DR20)';
      PINUSE='GROUND';
      NO_LOAD_CHECK='Both';
      NO_IO_CHECK='Both';
      NO_ASSERT_CHECK='TRUE';
      NO_DIR_CHECK='TRUE';
      ALLOW_CONNECT='TRUE';
    'VSS'<122>:
      PIN_NUMBER='(0,0,0,0,0,0,0,0,0,0,0,0,0,0,0,0,0,0,0,0,0,0,0,0,0,0,0,0,0,DR22)';
      PINUSE='GROUND';
      NO_LOAD_CHECK='Both';
      NO_IO_CHECK='Both';
      NO_ASSERT_CHECK='TRUE';
      NO_DIR_CHECK='TRUE';
      ALLOW_CONNECT='TRUE';
    'VSS'<121>:
      PIN_NUMBER='(0,0,0,0,0,0,0,0,0,0,0,0,0,0,0,0,0,0,0,0,0,0,0,0,0,0,0,0,0,DR24)';
      PINUSE='GROUND';
      NO_LOAD_CHECK='Both';
      NO_IO_CHECK='Both';
      NO_ASSERT_CHECK='TRUE';
      NO_DIR_CHECK='TRUE';
      ALLOW_CONNECT='TRUE';
    'VSS'<120>:
      PIN_NUMBER='(0,0,0,0,0,0,0,0,0,0,0,0,0,0,0,0,0,0,0,0,0,0,0,0,0,0,0,0,0,DR26)';
      PINUSE='GROUND';
      NO_LOAD_CHECK='Both';
      NO_IO_CHECK='Both';
      NO_ASSERT_CHECK='TRUE';
      NO_DIR_CHECK='TRUE';
      ALLOW_CONNECT='TRUE';
    'VSS'<119>:
      PIN_NUMBER='(0,0,0,0,0,0,0,0,0,0,0,0,0,0,0,0,0,0,0,0,0,0,0,0,0,0,0,0,0,DR28)';
      PINUSE='GROUND';
      NO_LOAD_CHECK='Both';
      NO_IO_CHECK='Both';
      NO_ASSERT_CHECK='TRUE';
      NO_DIR_CHECK='TRUE';
      ALLOW_CONNECT='TRUE';
    'VSS'<118>:
      PIN_NUMBER='(0,0,0,0,0,0,0,0,0,0,0,0,0,0,0,0,0,0,0,0,0,0,0,0,0,0,0,0,0,DR30)';
      PINUSE='GROUND';
      NO_LOAD_CHECK='Both';
      NO_IO_CHECK='Both';
      NO_ASSERT_CHECK='TRUE';
      NO_DIR_CHECK='TRUE';
      ALLOW_CONNECT='TRUE';
    'VSS'<117>:
      PIN_NUMBER='(0,0,0,0,0,0,0,0,0,0,0,0,0,0,0,0,0,0,0,0,0,0,0,0,0,0,0,0,0,DR32)';
      PINUSE='GROUND';
      NO_LOAD_CHECK='Both';
      NO_IO_CHECK='Both';
      NO_ASSERT_CHECK='TRUE';
      NO_DIR_CHECK='TRUE';
      ALLOW_CONNECT='TRUE';
    'VSS'<116>:
      PIN_NUMBER='(0,0,0,0,0,0,0,0,0,0,0,0,0,0,0,0,0,0,0,0,0,0,0,0,0,0,0,0,0,DR34)';
      PINUSE='GROUND';
      NO_LOAD_CHECK='Both';
      NO_IO_CHECK='Both';
      NO_ASSERT_CHECK='TRUE';
      NO_DIR_CHECK='TRUE';
      ALLOW_CONNECT='TRUE';
    'VSS'<115>:
      PIN_NUMBER='(0,0,0,0,0,0,0,0,0,0,0,0,0,0,0,0,0,0,0,0,0,0,0,0,0,0,0,0,0,DR36)';
      PINUSE='GROUND';
      NO_LOAD_CHECK='Both';
      NO_IO_CHECK='Both';
      NO_ASSERT_CHECK='TRUE';
      NO_DIR_CHECK='TRUE';
      ALLOW_CONNECT='TRUE';
    'VSS'<114>:
      PIN_NUMBER='(0,0,0,0,0,0,0,0,0,0,0,0,0,0,0,0,0,0,0,0,0,0,0,0,0,0,0,0,0,DR38)';
      PINUSE='GROUND';
      NO_LOAD_CHECK='Both';
      NO_IO_CHECK='Both';
      NO_ASSERT_CHECK='TRUE';
      NO_DIR_CHECK='TRUE';
      ALLOW_CONNECT='TRUE';
    'VSS'<113>:
      PIN_NUMBER='(0,0,0,0,0,0,0,0,0,0,0,0,0,0,0,0,0,0,0,0,0,0,0,0,0,0,0,0,0,DR40)';
      PINUSE='GROUND';
      NO_LOAD_CHECK='Both';
      NO_IO_CHECK='Both';
      NO_ASSERT_CHECK='TRUE';
      NO_DIR_CHECK='TRUE';
      ALLOW_CONNECT='TRUE';
    'VSS'<112>:
      PIN_NUMBER='(0,0,0,0,0,0,0,0,0,0,0,0,0,0,0,0,0,0,0,0,0,0,0,0,0,0,0,0,0,DR42)';
      PINUSE='GROUND';
      NO_LOAD_CHECK='Both';
      NO_IO_CHECK='Both';
      NO_ASSERT_CHECK='TRUE';
      NO_DIR_CHECK='TRUE';
      ALLOW_CONNECT='TRUE';
    'VSS'<111>:
      PIN_NUMBER='(0,0,0,0,0,0,0,0,0,0,0,0,0,0,0,0,0,0,0,0,0,0,0,0,0,0,0,0,0,DR66)';
      PINUSE='GROUND';
      NO_LOAD_CHECK='Both';
      NO_IO_CHECK='Both';
      NO_ASSERT_CHECK='TRUE';
      NO_DIR_CHECK='TRUE';
      ALLOW_CONNECT='TRUE';
    'VSS'<110>:
      PIN_NUMBER='(0,0,0,0,0,0,0,0,0,0,0,0,0,0,0,0,0,0,0,0,0,0,0,0,0,0,0,0,0,DR68)';
      PINUSE='GROUND';
      NO_LOAD_CHECK='Both';
      NO_IO_CHECK='Both';
      NO_ASSERT_CHECK='TRUE';
      NO_DIR_CHECK='TRUE';
      ALLOW_CONNECT='TRUE';
    'VSS'<109>:
      PIN_NUMBER='(0,0,0,0,0,0,0,0,0,0,0,0,0,0,0,0,0,0,0,0,0,0,0,0,0,0,0,0,0,DR70)';
      PINUSE='GROUND';
      NO_LOAD_CHECK='Both';
      NO_IO_CHECK='Both';
      NO_ASSERT_CHECK='TRUE';
      NO_DIR_CHECK='TRUE';
      ALLOW_CONNECT='TRUE';
    'VSS'<108>:
      PIN_NUMBER='(0,0,0,0,0,0,0,0,0,0,0,0,0,0,0,0,0,0,0,0,0,0,0,0,0,0,0,0,0,DR72)';
      PINUSE='GROUND';
      NO_LOAD_CHECK='Both';
      NO_IO_CHECK='Both';
      NO_ASSERT_CHECK='TRUE';
      NO_DIR_CHECK='TRUE';
      ALLOW_CONNECT='TRUE';
    'VSS'<107>:
      PIN_NUMBER='(0,0,0,0,0,0,0,0,0,0,0,0,0,0,0,0,0,0,0,0,0,0,0,0,0,0,0,0,0,DR74)';
      PINUSE='GROUND';
      NO_LOAD_CHECK='Both';
      NO_IO_CHECK='Both';
      NO_ASSERT_CHECK='TRUE';
      NO_DIR_CHECK='TRUE';
      ALLOW_CONNECT='TRUE';
    'VSS'<106>:
      PIN_NUMBER='(0,0,0,0,0,0,0,0,0,0,0,0,0,0,0,0,0,0,0,0,0,0,0,0,0,0,0,0,0,DR76)';
      PINUSE='GROUND';
      NO_LOAD_CHECK='Both';
      NO_IO_CHECK='Both';
      NO_ASSERT_CHECK='TRUE';
      NO_DIR_CHECK='TRUE';
      ALLOW_CONNECT='TRUE';
    'VSS'<105>:
      PIN_NUMBER='(0,0,0,0,0,0,0,0,0,0,0,0,0,0,0,0,0,0,0,0,0,0,0,0,0,0,0,0,0,DR78)';
      PINUSE='GROUND';
      NO_LOAD_CHECK='Both';
      NO_IO_CHECK='Both';
      NO_ASSERT_CHECK='TRUE';
      NO_DIR_CHECK='TRUE';
      ALLOW_CONNECT='TRUE';
    'VSS'<104>:
      PIN_NUMBER='(0,0,0,0,0,0,0,0,0,0,0,0,0,0,0,0,0,0,0,0,0,0,0,0,0,0,0,0,0,DT3)';
      PINUSE='GROUND';
      NO_LOAD_CHECK='Both';
      NO_IO_CHECK='Both';
      NO_ASSERT_CHECK='TRUE';
      NO_DIR_CHECK='TRUE';
      ALLOW_CONNECT='TRUE';
    'VSS'<103>:
      PIN_NUMBER='(0,0,0,0,0,0,0,0,0,0,0,0,0,0,0,0,0,0,0,0,0,0,0,0,0,0,0,0,0,DT17)';
      PINUSE='GROUND';
      NO_LOAD_CHECK='Both';
      NO_IO_CHECK='Both';
      NO_ASSERT_CHECK='TRUE';
      NO_DIR_CHECK='TRUE';
      ALLOW_CONNECT='TRUE';
    'VSS'<102>:
      PIN_NUMBER='(0,0,0,0,0,0,0,0,0,0,0,0,0,0,0,0,0,0,0,0,0,0,0,0,0,0,0,0,0,DH21)';
      PINUSE='GROUND';
      NO_LOAD_CHECK='Both';
      NO_IO_CHECK='Both';
      NO_ASSERT_CHECK='TRUE';
      NO_DIR_CHECK='TRUE';
      ALLOW_CONNECT='TRUE';
    'VSS'<101>:
      PIN_NUMBER='(0,0,0,0,0,0,0,0,0,0,0,0,0,0,0,0,0,0,0,0,0,0,0,0,0,0,0,0,0,DT65)';
      PINUSE='GROUND';
      NO_LOAD_CHECK='Both';
      NO_IO_CHECK='Both';
      NO_ASSERT_CHECK='TRUE';
      NO_DIR_CHECK='TRUE';
      ALLOW_CONNECT='TRUE';
    'VSS'<100>:
      PIN_NUMBER='(0,0,0,0,0,0,0,0,0,0,0,0,0,0,0,0,0,0,0,0,0,0,0,0,0,0,0,0,0,DT69)';
      PINUSE='GROUND';
      NO_LOAD_CHECK='Both';
      NO_IO_CHECK='Both';
      NO_ASSERT_CHECK='TRUE';
      NO_DIR_CHECK='TRUE';
      ALLOW_CONNECT='TRUE';
    'VSS'<99>:
      PIN_NUMBER='(0,0,0,0,0,0,0,0,0,0,0,0,0,0,0,0,0,0,0,0,0,0,0,0,0,0,0,0,0,DT79)';
      PINUSE='GROUND';
      NO_LOAD_CHECK='Both';
      NO_IO_CHECK='Both';
      NO_ASSERT_CHECK='TRUE';
      NO_DIR_CHECK='TRUE';
      ALLOW_CONNECT='TRUE';
    'VSS'<98>:
      PIN_NUMBER='(0,0,0,0,0,0,0,0,0,0,0,0,0,0,0,0,0,0,0,0,0,0,0,0,0,0,0,0,0,DT83)';
      PINUSE='GROUND';
      NO_LOAD_CHECK='Both';
      NO_IO_CHECK='Both';
      NO_ASSERT_CHECK='TRUE';
      NO_DIR_CHECK='TRUE';
      ALLOW_CONNECT='TRUE';
    'VSS'<97>:
      PIN_NUMBER='(0,0,0,0,0,0,0,0,0,0,0,0,0,0,0,0,0,0,0,0,0,0,0,0,0,0,0,0,0,DT85)';
      PINUSE='GROUND';
      NO_LOAD_CHECK='Both';
      NO_IO_CHECK='Both';
      NO_ASSERT_CHECK='TRUE';
      NO_DIR_CHECK='TRUE';
      ALLOW_CONNECT='TRUE';
    'VSS'<96>:
      PIN_NUMBER='(0,0,0,0,0,0,0,0,0,0,0,0,0,0,0,0,0,0,0,0,0,0,0,0,0,0,0,0,0,DU10)';
      PINUSE='GROUND';
      NO_LOAD_CHECK='Both';
      NO_IO_CHECK='Both';
      NO_ASSERT_CHECK='TRUE';
      NO_DIR_CHECK='TRUE';
      ALLOW_CONNECT='TRUE';
    'VSS'<95>:
      PIN_NUMBER='(0,0,0,0,0,0,0,0,0,0,0,0,0,0,0,0,0,0,0,0,0,0,0,0,0,0,0,0,0,DU14)';
      PINUSE='GROUND';
      NO_LOAD_CHECK='Both';
      NO_IO_CHECK='Both';
      NO_ASSERT_CHECK='TRUE';
      NO_DIR_CHECK='TRUE';
      ALLOW_CONNECT='TRUE';
    'VSS'<94>:
      PIN_NUMBER='(0,0,0,0,0,0,0,0,0,0,0,0,0,0,0,0,0,0,0,0,0,0,0,0,0,0,0,0,0,CN14)';
      PINUSE='GROUND';
      NO_LOAD_CHECK='Both';
      NO_IO_CHECK='Both';
      NO_ASSERT_CHECK='TRUE';
      NO_DIR_CHECK='TRUE';
      ALLOW_CONNECT='TRUE';
    'VSS'<93>:
      PIN_NUMBER='(0,0,0,0,0,0,0,0,0,0,0,0,0,0,0,0,0,0,0,0,0,0,0,0,0,0,0,0,0,DU22)';
      PINUSE='GROUND';
      NO_LOAD_CHECK='Both';
      NO_IO_CHECK='Both';
      NO_ASSERT_CHECK='TRUE';
      NO_DIR_CHECK='TRUE';
      ALLOW_CONNECT='TRUE';
    'VSS'<92>:
      PIN_NUMBER='(0,0,0,0,0,0,0,0,0,0,0,0,0,0,0,0,0,0,0,0,0,0,0,0,0,0,0,0,0,DU26)';
      PINUSE='GROUND';
      NO_LOAD_CHECK='Both';
      NO_IO_CHECK='Both';
      NO_ASSERT_CHECK='TRUE';
      NO_DIR_CHECK='TRUE';
      ALLOW_CONNECT='TRUE';
    'VSS'<91>:
      PIN_NUMBER='(0,0,0,0,0,0,0,0,0,0,0,0,0,0,0,0,0,0,0,0,0,0,0,0,0,0,0,0,0,DU32)';
      PINUSE='GROUND';
      NO_LOAD_CHECK='Both';
      NO_IO_CHECK='Both';
      NO_ASSERT_CHECK='TRUE';
      NO_DIR_CHECK='TRUE';
      ALLOW_CONNECT='TRUE';
    'VSS'<90>:
      PIN_NUMBER='(0,0,0,0,0,0,0,0,0,0,0,0,0,0,0,0,0,0,0,0,0,0,0,0,0,0,0,0,0,DU38)';
      PINUSE='GROUND';
      NO_LOAD_CHECK='Both';
      NO_IO_CHECK='Both';
      NO_ASSERT_CHECK='TRUE';
      NO_DIR_CHECK='TRUE';
      ALLOW_CONNECT='TRUE';
    'VSS'<89>:
      PIN_NUMBER='(0,0,0,0,0,0,0,0,0,0,0,0,0,0,0,0,0,0,0,0,0,0,0,0,0,0,0,0,0,DU70)';
      PINUSE='GROUND';
      NO_LOAD_CHECK='Both';
      NO_IO_CHECK='Both';
      NO_ASSERT_CHECK='TRUE';
      NO_DIR_CHECK='TRUE';
      ALLOW_CONNECT='TRUE';
    'VSS'<88>:
      PIN_NUMBER='(0,0,0,0,0,0,0,0,0,0,0,0,0,0,0,0,0,0,0,0,0,0,0,0,0,0,0,0,0,DU72)';
      PINUSE='GROUND';
      NO_LOAD_CHECK='Both';
      NO_IO_CHECK='Both';
      NO_ASSERT_CHECK='TRUE';
      NO_DIR_CHECK='TRUE';
      ALLOW_CONNECT='TRUE';
    'VSS'<87>:
      PIN_NUMBER='(0,0,0,0,0,0,0,0,0,0,0,0,0,0,0,0,0,0,0,0,0,0,0,0,0,0,0,0,0,DU78)';
      PINUSE='GROUND';
      NO_LOAD_CHECK='Both';
      NO_IO_CHECK='Both';
      NO_ASSERT_CHECK='TRUE';
      NO_DIR_CHECK='TRUE';
      ALLOW_CONNECT='TRUE';
    'VSS'<86>:
      PIN_NUMBER='(0,0,0,0,0,0,0,0,0,0,0,0,0,0,0,0,0,0,0,0,0,0,0,0,0,0,0,0,0,DU80)';
      PINUSE='GROUND';
      NO_LOAD_CHECK='Both';
      NO_IO_CHECK='Both';
      NO_ASSERT_CHECK='TRUE';
      NO_DIR_CHECK='TRUE';
      ALLOW_CONNECT='TRUE';
    'VSS'<85>:
      PIN_NUMBER='(0,0,0,0,0,0,0,0,0,0,0,0,0,0,0,0,0,0,0,0,0,0,0,0,0,0,0,0,0,DU82)';
      PINUSE='GROUND';
      NO_LOAD_CHECK='Both';
      NO_IO_CHECK='Both';
      NO_ASSERT_CHECK='TRUE';
      NO_DIR_CHECK='TRUE';
      ALLOW_CONNECT='TRUE';
    'VSS'<84>:
      PIN_NUMBER='(0,0,0,0,0,0,0,0,0,0,0,0,0,0,0,0,0,0,0,0,0,0,0,0,0,0,0,0,0,DU84)';
      PINUSE='GROUND';
      NO_LOAD_CHECK='Both';
      NO_IO_CHECK='Both';
      NO_ASSERT_CHECK='TRUE';
      NO_DIR_CHECK='TRUE';
      ALLOW_CONNECT='TRUE';
    'VSS'<83>:
      PIN_NUMBER='(0,0,0,0,0,0,0,0,0,0,0,0,0,0,0,0,0,0,0,0,0,0,0,0,0,0,0,0,0,DV21)';
      PINUSE='GROUND';
      NO_LOAD_CHECK='Both';
      NO_IO_CHECK='Both';
      NO_ASSERT_CHECK='TRUE';
      NO_DIR_CHECK='TRUE';
      ALLOW_CONNECT='TRUE';
    'VSS'<82>:
      PIN_NUMBER='(0,0,0,0,0,0,0,0,0,0,0,0,0,0,0,0,0,0,0,0,0,0,0,0,0,0,0,0,0,DV25)';
      PINUSE='GROUND';
      NO_LOAD_CHECK='Both';
      NO_IO_CHECK='Both';
      NO_ASSERT_CHECK='TRUE';
      NO_DIR_CHECK='TRUE';
      ALLOW_CONNECT='TRUE';
    'VSS'<81>:
      PIN_NUMBER='(0,0,0,0,0,0,0,0,0,0,0,0,0,0,0,0,0,0,0,0,0,0,0,0,0,0,0,0,0,DV27)';
      PINUSE='GROUND';
      NO_LOAD_CHECK='Both';
      NO_IO_CHECK='Both';
      NO_ASSERT_CHECK='TRUE';
      NO_DIR_CHECK='TRUE';
      ALLOW_CONNECT='TRUE';
    'VSS'<80>:
      PIN_NUMBER='(0,0,0,0,0,0,0,0,0,0,0,0,0,0,0,0,0,0,0,0,0,0,0,0,0,0,0,0,0,DV31)';
      PINUSE='GROUND';
      NO_LOAD_CHECK='Both';
      NO_IO_CHECK='Both';
      NO_ASSERT_CHECK='TRUE';
      NO_DIR_CHECK='TRUE';
      ALLOW_CONNECT='TRUE';
    'VSS'<79>:
      PIN_NUMBER='(0,0,0,0,0,0,0,0,0,0,0,0,0,0,0,0,0,0,0,0,0,0,0,0,0,0,0,0,0,DV33)';
      PINUSE='GROUND';
      NO_LOAD_CHECK='Both';
      NO_IO_CHECK='Both';
      NO_ASSERT_CHECK='TRUE';
      NO_DIR_CHECK='TRUE';
      ALLOW_CONNECT='TRUE';
    'VSS'<78>:
      PIN_NUMBER='(0,0,0,0,0,0,0,0,0,0,0,0,0,0,0,0,0,0,0,0,0,0,0,0,0,0,0,0,0,DV37)';
      PINUSE='GROUND';
      NO_LOAD_CHECK='Both';
      NO_IO_CHECK='Both';
      NO_ASSERT_CHECK='TRUE';
      NO_DIR_CHECK='TRUE';
      ALLOW_CONNECT='TRUE';
    'VSS'<77>:
      PIN_NUMBER='(0,0,0,0,0,0,0,0,0,0,0,0,0,0,0,0,0,0,0,0,0,0,0,0,0,0,0,0,0,DV39)';
      PINUSE='GROUND';
      NO_LOAD_CHECK='Both';
      NO_IO_CHECK='Both';
      NO_ASSERT_CHECK='TRUE';
      NO_DIR_CHECK='TRUE';
      ALLOW_CONNECT='TRUE';
    'VSS'<76>:
      PIN_NUMBER='(0,0,0,0,0,0,0,0,0,0,0,0,0,0,0,0,0,0,0,0,0,0,0,0,0,0,0,0,0,DV73)';
      PINUSE='GROUND';
      NO_LOAD_CHECK='Both';
      NO_IO_CHECK='Both';
      NO_ASSERT_CHECK='TRUE';
      NO_DIR_CHECK='TRUE';
      ALLOW_CONNECT='TRUE';
    'VSS'<75>:
      PIN_NUMBER='(0,0,0,0,0,0,0,0,0,0,0,0,0,0,0,0,0,0,0,0,0,0,0,0,0,0,0,0,0,DV77)';
      PINUSE='GROUND';
      NO_LOAD_CHECK='Both';
      NO_IO_CHECK='Both';
      NO_ASSERT_CHECK='TRUE';
      NO_DIR_CHECK='TRUE';
      ALLOW_CONNECT='TRUE';
    'VSS'<74>:
      PIN_NUMBER='(0,0,0,0,0,0,0,0,0,0,0,0,0,0,0,0,0,0,0,0,0,0,0,0,0,0,0,0,0,DV81)';
      PINUSE='GROUND';
      NO_LOAD_CHECK='Both';
      NO_IO_CHECK='Both';
      NO_ASSERT_CHECK='TRUE';
      NO_DIR_CHECK='TRUE';
      ALLOW_CONNECT='TRUE';
    'VSS'<73>:
      PIN_NUMBER='(0,0,0,0,0,0,0,0,0,0,0,0,0,0,0,0,0,0,0,0,0,0,0,0,0,0,0,0,0,DW12)';
      PINUSE='GROUND';
      NO_LOAD_CHECK='Both';
      NO_IO_CHECK='Both';
      NO_ASSERT_CHECK='TRUE';
      NO_DIR_CHECK='TRUE';
      ALLOW_CONNECT='TRUE';
    'VSS'<72>:
      PIN_NUMBER='(0,0,0,0,0,0,0,0,0,0,0,0,0,0,0,0,0,0,0,0,0,0,0,0,0,0,0,0,0,DW20)';
      PINUSE='GROUND';
      NO_LOAD_CHECK='Both';
      NO_IO_CHECK='Both';
      NO_ASSERT_CHECK='TRUE';
      NO_DIR_CHECK='TRUE';
      ALLOW_CONNECT='TRUE';
    'VSS'<71>:
      PIN_NUMBER='(0,0,0,0,0,0,0,0,0,0,0,0,0,0,0,0,0,0,0,0,0,0,0,0,0,0,0,0,0,DW24)';
      PINUSE='GROUND';
      NO_LOAD_CHECK='Both';
      NO_IO_CHECK='Both';
      NO_ASSERT_CHECK='TRUE';
      NO_DIR_CHECK='TRUE';
      ALLOW_CONNECT='TRUE';
    'VSS'<70>:
      PIN_NUMBER='(0,0,0,0,0,0,0,0,0,0,0,0,0,0,0,0,0,0,0,0,0,0,0,0,0,0,0,0,0,DW28)';
      PINUSE='GROUND';
      NO_LOAD_CHECK='Both';
      NO_IO_CHECK='Both';
      NO_ASSERT_CHECK='TRUE';
      NO_DIR_CHECK='TRUE';
      ALLOW_CONNECT='TRUE';
    'VSS'<69>:
      PIN_NUMBER='(0,0,0,0,0,0,0,0,0,0,0,0,0,0,0,0,0,0,0,0,0,0,0,0,0,0,0,0,0,DW30)';
      PINUSE='GROUND';
      NO_LOAD_CHECK='Both';
      NO_IO_CHECK='Both';
      NO_ASSERT_CHECK='TRUE';
      NO_DIR_CHECK='TRUE';
      ALLOW_CONNECT='TRUE';
    'VSS'<68>:
      PIN_NUMBER='(0,0,0,0,0,0,0,0,0,0,0,0,0,0,0,0,0,0,0,0,0,0,0,0,0,0,0,0,0,DW34)';
      PINUSE='GROUND';
      NO_LOAD_CHECK='Both';
      NO_IO_CHECK='Both';
      NO_ASSERT_CHECK='TRUE';
      NO_DIR_CHECK='TRUE';
      ALLOW_CONNECT='TRUE';
    'VSS'<67>:
      PIN_NUMBER='(0,0,0,0,0,0,0,0,0,0,0,0,0,0,0,0,0,0,0,0,0,0,0,0,0,0,0,0,0,DW36)';
      PINUSE='GROUND';
      NO_LOAD_CHECK='Both';
      NO_IO_CHECK='Both';
      NO_ASSERT_CHECK='TRUE';
      NO_DIR_CHECK='TRUE';
      ALLOW_CONNECT='TRUE';
    'VSS'<66>:
      PIN_NUMBER='(0,0,0,0,0,0,0,0,0,0,0,0,0,0,0,0,0,0,0,0,0,0,0,0,0,0,0,0,0,DW40)';
      PINUSE='GROUND';
      NO_LOAD_CHECK='Both';
      NO_IO_CHECK='Both';
      NO_ASSERT_CHECK='TRUE';
      NO_DIR_CHECK='TRUE';
      ALLOW_CONNECT='TRUE';
    'VSS'<65>:
      PIN_NUMBER='(0,0,0,0,0,0,0,0,0,0,0,0,0,0,0,0,0,0,0,0,0,0,0,0,0,0,0,0,0,DW64)';
      PINUSE='GROUND';
      NO_LOAD_CHECK='Both';
      NO_IO_CHECK='Both';
      NO_ASSERT_CHECK='TRUE';
      NO_DIR_CHECK='TRUE';
      ALLOW_CONNECT='TRUE';
    'VSS'<64>:
      PIN_NUMBER='(0,0,0,0,0,0,0,0,0,0,0,0,0,0,0,0,0,0,0,0,0,0,0,0,0,0,0,0,0,DW66)';
      PINUSE='GROUND';
      NO_LOAD_CHECK='Both';
      NO_IO_CHECK='Both';
      NO_ASSERT_CHECK='TRUE';
      NO_DIR_CHECK='TRUE';
      ALLOW_CONNECT='TRUE';
    'VSS'<63>:
      PIN_NUMBER='(0,0,0,0,0,0,0,0,0,0,0,0,0,0,0,0,0,0,0,0,0,0,0,0,0,0,0,0,0,DW68)';
      PINUSE='GROUND';
      NO_LOAD_CHECK='Both';
      NO_IO_CHECK='Both';
      NO_ASSERT_CHECK='TRUE';
      NO_DIR_CHECK='TRUE';
      ALLOW_CONNECT='TRUE';
    'VSS'<62>:
      PIN_NUMBER='(0,0,0,0,0,0,0,0,0,0,0,0,0,0,0,0,0,0,0,0,0,0,0,0,0,0,0,0,0,DW70)';
      PINUSE='GROUND';
      NO_LOAD_CHECK='Both';
      NO_IO_CHECK='Both';
      NO_ASSERT_CHECK='TRUE';
      NO_DIR_CHECK='TRUE';
      ALLOW_CONNECT='TRUE';
    'VSS'<61>:
      PIN_NUMBER='(0,0,0,0,0,0,0,0,0,0,0,0,0,0,0,0,0,0,0,0,0,0,0,0,0,0,0,0,0,DW72)';
      PINUSE='GROUND';
      NO_LOAD_CHECK='Both';
      NO_IO_CHECK='Both';
      NO_ASSERT_CHECK='TRUE';
      NO_DIR_CHECK='TRUE';
      ALLOW_CONNECT='TRUE';
    'VSS'<60>:
      PIN_NUMBER='(0,0,0,0,0,0,0,0,0,0,0,0,0,0,0,0,0,0,0,0,0,0,0,0,0,0,0,0,0,DW74)';
      PINUSE='GROUND';
      NO_LOAD_CHECK='Both';
      NO_IO_CHECK='Both';
      NO_ASSERT_CHECK='TRUE';
      NO_DIR_CHECK='TRUE';
      ALLOW_CONNECT='TRUE';
    'VSS'<59>:
      PIN_NUMBER='(0,0,0,0,0,0,0,0,0,0,0,0,0,0,0,0,0,0,0,0,0,0,0,0,0,0,0,0,0,DW76)';
      PINUSE='GROUND';
      NO_LOAD_CHECK='Both';
      NO_IO_CHECK='Both';
      NO_ASSERT_CHECK='TRUE';
      NO_DIR_CHECK='TRUE';
      ALLOW_CONNECT='TRUE';
    'VSS'<58>:
      PIN_NUMBER='(0,0,0,0,0,0,0,0,0,0,0,0,0,0,0,0,0,0,0,0,0,0,0,0,0,0,0,0,0,DW8)';
      PINUSE='GROUND';
      NO_LOAD_CHECK='Both';
      NO_IO_CHECK='Both';
      NO_ASSERT_CHECK='TRUE';
      NO_DIR_CHECK='TRUE';
      ALLOW_CONNECT='TRUE';
    'VSS'<57>:
      PIN_NUMBER='(0,0,0,0,0,0,0,0,0,0,0,0,0,0,0,0,0,0,0,0,0,0,0,0,0,0,0,0,0,DW82)';
      PINUSE='GROUND';
      NO_LOAD_CHECK='Both';
      NO_IO_CHECK='Both';
      NO_ASSERT_CHECK='TRUE';
      NO_DIR_CHECK='TRUE';
      ALLOW_CONNECT='TRUE';
    'VSS'<56>:
      PIN_NUMBER='(0,0,0,0,0,0,0,0,0,0,0,0,0,0,0,0,0,0,0,0,0,0,0,0,0,0,0,0,0,DW84)';
      PINUSE='GROUND';
      NO_LOAD_CHECK='Both';
      NO_IO_CHECK='Both';
      NO_ASSERT_CHECK='TRUE';
      NO_DIR_CHECK='TRUE';
      ALLOW_CONNECT='TRUE';
    'VSS'<55>:
      PIN_NUMBER='(0,0,0,0,0,0,0,0,0,0,0,0,0,0,0,0,0,0,0,0,0,0,0,0,0,0,0,0,0,DY5)';
      PINUSE='GROUND';
      NO_LOAD_CHECK='Both';
      NO_IO_CHECK='Both';
      NO_ASSERT_CHECK='TRUE';
      NO_DIR_CHECK='TRUE';
      ALLOW_CONNECT='TRUE';
    'VSS'<54>:
      PIN_NUMBER='(0,0,0,0,0,0,0,0,0,0,0,0,0,0,0,0,0,0,0,0,0,0,0,0,0,0,0,0,0,DY19)';
      PINUSE='GROUND';
      NO_LOAD_CHECK='Both';
      NO_IO_CHECK='Both';
      NO_ASSERT_CHECK='TRUE';
      NO_DIR_CHECK='TRUE';
      ALLOW_CONNECT='TRUE';
    'VSS'<53>:
      PIN_NUMBER='(0,0,0,0,0,0,0,0,0,0,0,0,0,0,0,0,0,0,0,0,0,0,0,0,0,0,0,0,0,DY23)';
      PINUSE='GROUND';
      NO_LOAD_CHECK='Both';
      NO_IO_CHECK='Both';
      NO_ASSERT_CHECK='TRUE';
      NO_DIR_CHECK='TRUE';
      ALLOW_CONNECT='TRUE';
    'VSS'<52>:
      PIN_NUMBER='(0,0,0,0,0,0,0,0,0,0,0,0,0,0,0,0,0,0,0,0,0,0,0,0,0,0,0,0,0,DY29)';
      PINUSE='GROUND';
      NO_LOAD_CHECK='Both';
      NO_IO_CHECK='Both';
      NO_ASSERT_CHECK='TRUE';
      NO_DIR_CHECK='TRUE';
      ALLOW_CONNECT='TRUE';
    'VSS'<51>:
      PIN_NUMBER='(0,0,0,0,0,0,0,0,0,0,0,0,0,0,0,0,0,0,0,0,0,0,0,0,0,0,0,0,0,DY35)';
      PINUSE='GROUND';
      NO_LOAD_CHECK='Both';
      NO_IO_CHECK='Both';
      NO_ASSERT_CHECK='TRUE';
      NO_DIR_CHECK='TRUE';
      ALLOW_CONNECT='TRUE';
    'VSS'<50>:
      PIN_NUMBER='(0,0,0,0,0,0,0,0,0,0,0,0,0,0,0,0,0,0,0,0,0,0,0,0,0,0,0,0,0,DY41)';
      PINUSE='GROUND';
      NO_LOAD_CHECK='Both';
      NO_IO_CHECK='Both';
      NO_ASSERT_CHECK='TRUE';
      NO_DIR_CHECK='TRUE';
      ALLOW_CONNECT='TRUE';
    'VSS'<49>:
      PIN_NUMBER='(0,0,0,0,0,0,0,0,0,0,0,0,0,0,0,0,0,0,0,0,0,0,0,0,0,0,0,0,0,DY71)';
      PINUSE='GROUND';
      NO_LOAD_CHECK='Both';
      NO_IO_CHECK='Both';
      NO_ASSERT_CHECK='TRUE';
      NO_DIR_CHECK='TRUE';
      ALLOW_CONNECT='TRUE';
    'VSS'<48>:
      PIN_NUMBER='(0,0,0,0,0,0,0,0,0,0,0,0,0,0,0,0,0,0,0,0,0,0,0,0,0,0,0,0,0,DY75)';
      PINUSE='GROUND';
      NO_LOAD_CHECK='Both';
      NO_IO_CHECK='Both';
      NO_ASSERT_CHECK='TRUE';
      NO_DIR_CHECK='TRUE';
      ALLOW_CONNECT='TRUE';
    'VSS'<47>:
      PIN_NUMBER='(0,0,0,0,0,0,0,0,0,0,0,0,0,0,0,0,0,0,0,0,0,0,0,0,0,0,0,0,0,EA6)';
      PINUSE='GROUND';
      NO_LOAD_CHECK='Both';
      NO_IO_CHECK='Both';
      NO_ASSERT_CHECK='TRUE';
      NO_DIR_CHECK='TRUE';
      ALLOW_CONNECT='TRUE';
    'VSS'<46>:
      PIN_NUMBER='(0,0,0,0,0,0,0,0,0,0,0,0,0,0,0,0,0,0,0,0,0,0,0,0,0,0,0,0,0,J16)';
      PINUSE='GROUND';
      NO_LOAD_CHECK='Both';
      NO_IO_CHECK='Both';
      NO_ASSERT_CHECK='TRUE';
      NO_DIR_CHECK='TRUE';
      ALLOW_CONNECT='TRUE';
    'VSS'<45>:
      PIN_NUMBER='(0,0,0,0,0,0,0,0,0,0,0,0,0,0,0,0,0,0,0,0,0,0,0,0,0,0,0,0,0,EA16)';
      PINUSE='GROUND';
      NO_LOAD_CHECK='Both';
      NO_IO_CHECK='Both';
      NO_ASSERT_CHECK='TRUE';
      NO_DIR_CHECK='TRUE';
      ALLOW_CONNECT='TRUE';
    'VSS'<44>:
      PIN_NUMBER='(0,0,0,0,0,0,0,0,0,0,0,0,0,0,0,0,0,0,0,0,0,0,0,0,0,0,0,0,0,EA20)';
      PINUSE='GROUND';
      NO_LOAD_CHECK='Both';
      NO_IO_CHECK='Both';
      NO_ASSERT_CHECK='TRUE';
      NO_DIR_CHECK='TRUE';
      ALLOW_CONNECT='TRUE';
    'VSS'<43>:
      PIN_NUMBER='(0,0,0,0,0,0,0,0,0,0,0,0,0,0,0,0,0,0,0,0,0,0,0,0,0,0,0,0,0,EA22)';
      PINUSE='GROUND';
      NO_LOAD_CHECK='Both';
      NO_IO_CHECK='Both';
      NO_ASSERT_CHECK='TRUE';
      NO_DIR_CHECK='TRUE';
      ALLOW_CONNECT='TRUE';
    'VSS'<42>:
      PIN_NUMBER='(0,0,0,0,0,0,0,0,0,0,0,0,0,0,0,0,0,0,0,0,0,0,0,0,0,0,0,0,0,EA42)';
      PINUSE='GROUND';
      NO_LOAD_CHECK='Both';
      NO_IO_CHECK='Both';
      NO_ASSERT_CHECK='TRUE';
      NO_DIR_CHECK='TRUE';
      ALLOW_CONNECT='TRUE';
    'VSS'<41>:
      PIN_NUMBER='(0,0,0,0,0,0,0,0,0,0,0,0,0,0,0,0,0,0,0,0,0,0,0,0,0,0,0,0,0,EA64)';
      PINUSE='GROUND';
      NO_LOAD_CHECK='Both';
      NO_IO_CHECK='Both';
      NO_ASSERT_CHECK='TRUE';
      NO_DIR_CHECK='TRUE';
      ALLOW_CONNECT='TRUE';
    'VSS'<40>:
      PIN_NUMBER='(0,0,0,0,0,0,0,0,0,0,0,0,0,0,0,0,0,0,0,0,0,0,0,0,0,0,0,0,0,EA70)';
      PINUSE='GROUND';
      NO_LOAD_CHECK='Both';
      NO_IO_CHECK='Both';
      NO_ASSERT_CHECK='TRUE';
      NO_DIR_CHECK='TRUE';
      ALLOW_CONNECT='TRUE';
    'VSS'<39>:
      PIN_NUMBER='(0,0,0,0,0,0,0,0,0,0,0,0,0,0,0,0,0,0,0,0,0,0,0,0,0,0,0,0,0,EA76)';
      PINUSE='GROUND';
      NO_LOAD_CHECK='Both';
      NO_IO_CHECK='Both';
      NO_ASSERT_CHECK='TRUE';
      NO_DIR_CHECK='TRUE';
      ALLOW_CONNECT='TRUE';
    'VSS'<38>:
      PIN_NUMBER='(0,0,0,0,0,0,0,0,0,0,0,0,0,0,0,0,0,0,0,0,0,0,0,0,0,0,0,0,0,EA78)';
      PINUSE='GROUND';
      NO_LOAD_CHECK='Both';
      NO_IO_CHECK='Both';
      NO_ASSERT_CHECK='TRUE';
      NO_DIR_CHECK='TRUE';
      ALLOW_CONNECT='TRUE';
    'VSS'<37>:
      PIN_NUMBER='(0,0,0,0,0,0,0,0,0,0,0,0,0,0,0,0,0,0,0,0,0,0,0,0,0,0,0,0,0,EA80)';
      PINUSE='GROUND';
      NO_LOAD_CHECK='Both';
      NO_IO_CHECK='Both';
      NO_ASSERT_CHECK='TRUE';
      NO_DIR_CHECK='TRUE';
      ALLOW_CONNECT='TRUE';
    'VSS'<36>:
      PIN_NUMBER='(0,0,0,0,0,0,0,0,0,0,0,0,0,0,0,0,0,0,0,0,0,0,0,0,0,0,0,0,0,EA82)';
      PINUSE='GROUND';
      NO_LOAD_CHECK='Both';
      NO_IO_CHECK='Both';
      NO_ASSERT_CHECK='TRUE';
      NO_DIR_CHECK='TRUE';
      ALLOW_CONNECT='TRUE';
    'VSS'<35>:
      PIN_NUMBER='(0,0,0,0,0,0,0,0,0,0,0,0,0,0,0,0,0,0,0,0,0,0,0,0,0,0,0,0,0,EB13)';
      PINUSE='GROUND';
      NO_LOAD_CHECK='Both';
      NO_IO_CHECK='Both';
      NO_ASSERT_CHECK='TRUE';
      NO_DIR_CHECK='TRUE';
      ALLOW_CONNECT='TRUE';
    'VSS'<34>:
      PIN_NUMBER='(0,0,0,0,0,0,0,0,0,0,0,0,0,0,0,0,0,0,0,0,0,0,0,0,0,0,0,0,0,BR18)';
      PINUSE='GROUND';
      NO_LOAD_CHECK='Both';
      NO_IO_CHECK='Both';
      NO_ASSERT_CHECK='TRUE';
      NO_DIR_CHECK='TRUE';
      ALLOW_CONNECT='TRUE';
    'VSS'<33>:
      PIN_NUMBER='(0,0,0,0,0,0,0,0,0,0,0,0,0,0,0,0,0,0,0,0,0,0,0,0,0,0,0,0,0,EB23)';
      PINUSE='GROUND';
      NO_LOAD_CHECK='Both';
      NO_IO_CHECK='Both';
      NO_ASSERT_CHECK='TRUE';
      NO_DIR_CHECK='TRUE';
      ALLOW_CONNECT='TRUE';
    'VSS'<32>:
      PIN_NUMBER='(0,0,0,0,0,0,0,0,0,0,0,0,0,0,0,0,0,0,0,0,0,0,0,0,0,0,0,0,0,EB25)';
      PINUSE='GROUND';
      NO_LOAD_CHECK='Both';
      NO_IO_CHECK='Both';
      NO_ASSERT_CHECK='TRUE';
      NO_DIR_CHECK='TRUE';
      ALLOW_CONNECT='TRUE';
    'VSS'<31>:
      PIN_NUMBER='(0,0,0,0,0,0,0,0,0,0,0,0,0,0,0,0,0,0,0,0,0,0,0,0,0,0,0,0,0,EB27)';
      PINUSE='GROUND';
      NO_LOAD_CHECK='Both';
      NO_IO_CHECK='Both';
      NO_ASSERT_CHECK='TRUE';
      NO_DIR_CHECK='TRUE';
      ALLOW_CONNECT='TRUE';
    'VSS'<30>:
      PIN_NUMBER='(0,0,0,0,0,0,0,0,0,0,0,0,0,0,0,0,0,0,0,0,0,0,0,0,0,0,0,0,0,EB29)';
      PINUSE='GROUND';
      NO_LOAD_CHECK='Both';
      NO_IO_CHECK='Both';
      NO_ASSERT_CHECK='TRUE';
      NO_DIR_CHECK='TRUE';
      ALLOW_CONNECT='TRUE';
    'VSS'<29>:
      PIN_NUMBER='(0,0,0,0,0,0,0,0,0,0,0,0,0,0,0,0,0,0,0,0,0,0,0,0,0,0,0,0,0,EB31)';
      PINUSE='GROUND';
      NO_LOAD_CHECK='Both';
      NO_IO_CHECK='Both';
      NO_ASSERT_CHECK='TRUE';
      NO_DIR_CHECK='TRUE';
      ALLOW_CONNECT='TRUE';
    'VSS'<28>:
      PIN_NUMBER='(0,0,0,0,0,0,0,0,0,0,0,0,0,0,0,0,0,0,0,0,0,0,0,0,0,0,0,0,0,EB33)';
      PINUSE='GROUND';
      NO_LOAD_CHECK='Both';
      NO_IO_CHECK='Both';
      NO_ASSERT_CHECK='TRUE';
      NO_DIR_CHECK='TRUE';
      ALLOW_CONNECT='TRUE';
    'VSS'<27>:
      PIN_NUMBER='(0,0,0,0,0,0,0,0,0,0,0,0,0,0,0,0,0,0,0,0,0,0,0,0,0,0,0,0,0,EB35)';
      PINUSE='GROUND';
      NO_LOAD_CHECK='Both';
      NO_IO_CHECK='Both';
      NO_ASSERT_CHECK='TRUE';
      NO_DIR_CHECK='TRUE';
      ALLOW_CONNECT='TRUE';
    'VSS'<26>:
      PIN_NUMBER='(0,0,0,0,0,0,0,0,0,0,0,0,0,0,0,0,0,0,0,0,0,0,0,0,0,0,0,0,0,EB37)';
      PINUSE='GROUND';
      NO_LOAD_CHECK='Both';
      NO_IO_CHECK='Both';
      NO_ASSERT_CHECK='TRUE';
      NO_DIR_CHECK='TRUE';
      ALLOW_CONNECT='TRUE';
    'VSS'<25>:
      PIN_NUMBER='(0,0,0,0,0,0,0,0,0,0,0,0,0,0,0,0,0,0,0,0,0,0,0,0,0,0,0,0,0,EB39)';
      PINUSE='GROUND';
      NO_LOAD_CHECK='Both';
      NO_IO_CHECK='Both';
      NO_ASSERT_CHECK='TRUE';
      NO_DIR_CHECK='TRUE';
      ALLOW_CONNECT='TRUE';
    'VSS'<24>:
      PIN_NUMBER='(0,0,0,0,0,0,0,0,0,0,0,0,0,0,0,0,0,0,0,0,0,0,0,0,0,0,0,0,0,EB41)';
      PINUSE='GROUND';
      NO_LOAD_CHECK='Both';
      NO_IO_CHECK='Both';
      NO_ASSERT_CHECK='TRUE';
      NO_DIR_CHECK='TRUE';
      ALLOW_CONNECT='TRUE';
    'VSS'<23>:
      PIN_NUMBER='(0,0,0,0,0,0,0,0,0,0,0,0,0,0,0,0,0,0,0,0,0,0,0,0,0,0,0,0,0,EB65)';
      PINUSE='GROUND';
      NO_LOAD_CHECK='Both';
      NO_IO_CHECK='Both';
      NO_ASSERT_CHECK='TRUE';
      NO_DIR_CHECK='TRUE';
      ALLOW_CONNECT='TRUE';
    'VSS'<22>:
      PIN_NUMBER='(0,0,0,0,0,0,0,0,0,0,0,0,0,0,0,0,0,0,0,0,0,0,0,0,0,0,0,0,0,EB69)';
      PINUSE='GROUND';
      NO_LOAD_CHECK='Both';
      NO_IO_CHECK='Both';
      NO_ASSERT_CHECK='TRUE';
      NO_DIR_CHECK='TRUE';
      ALLOW_CONNECT='TRUE';
    'VSS'<21>:
      PIN_NUMBER='(0,0,0,0,0,0,0,0,0,0,0,0,0,0,0,0,0,0,0,0,0,0,0,0,0,0,0,0,0,EC10)';
      PINUSE='GROUND';
      NO_LOAD_CHECK='Both';
      NO_IO_CHECK='Both';
      NO_ASSERT_CHECK='TRUE';
      NO_DIR_CHECK='TRUE';
      ALLOW_CONNECT='TRUE';
    'VSS'<20>:
      PIN_NUMBER='(0,0,0,0,0,0,0,0,0,0,0,0,0,0,0,0,0,0,0,0,0,0,0,0,0,0,0,0,0,EC70)';
      PINUSE='GROUND';
      NO_LOAD_CHECK='Both';
      NO_IO_CHECK='Both';
      NO_ASSERT_CHECK='TRUE';
      NO_DIR_CHECK='TRUE';
      ALLOW_CONNECT='TRUE';
    'VSS'<19>:
      PIN_NUMBER='(0,0,0,0,0,0,0,0,0,0,0,0,0,0,0,0,0,0,0,0,0,0,0,0,0,0,0,0,0,EC72)';
      PINUSE='GROUND';
      NO_LOAD_CHECK='Both';
      NO_IO_CHECK='Both';
      NO_ASSERT_CHECK='TRUE';
      NO_DIR_CHECK='TRUE';
      ALLOW_CONNECT='TRUE';
    'VSS'<18>:
      PIN_NUMBER='(0,0,0,0,0,0,0,0,0,0,0,0,0,0,0,0,0,0,0,0,0,0,0,0,0,0,0,0,0,EC74)';
      PINUSE='GROUND';
      NO_LOAD_CHECK='Both';
      NO_IO_CHECK='Both';
      NO_ASSERT_CHECK='TRUE';
      NO_DIR_CHECK='TRUE';
      ALLOW_CONNECT='TRUE';
    'VSS'<17>:
      PIN_NUMBER='(0,0,0,0,0,0,0,0,0,0,0,0,0,0,0,0,0,0,0,0,0,0,0,0,0,0,0,0,0,EC76)';
      PINUSE='GROUND';
      NO_LOAD_CHECK='Both';
      NO_IO_CHECK='Both';
      NO_ASSERT_CHECK='TRUE';
      NO_DIR_CHECK='TRUE';
      ALLOW_CONNECT='TRUE';
    'VSS'<16>:
      PIN_NUMBER='(0,0,0,0,0,0,0,0,0,0,0,0,0,0,0,0,0,0,0,0,0,0,0,0,0,0,0,0,0,ED11)';
      PINUSE='GROUND';
      NO_LOAD_CHECK='Both';
      NO_IO_CHECK='Both';
      NO_ASSERT_CHECK='TRUE';
      NO_DIR_CHECK='TRUE';
      ALLOW_CONNECT='TRUE';
    'VSS'<15>:
      PIN_NUMBER='(0,0,0,0,0,0,0,0,0,0,0,0,0,0,0,0,0,0,0,0,0,0,0,0,0,0,0,0,0,ED15)';
      PINUSE='GROUND';
      NO_LOAD_CHECK='Both';
      NO_IO_CHECK='Both';
      NO_ASSERT_CHECK='TRUE';
      NO_DIR_CHECK='TRUE';
      ALLOW_CONNECT='TRUE';
    'VSS'<14>:
      PIN_NUMBER='(0,0,0,0,0,0,0,0,0,0,0,0,0,0,0,0,0,0,0,0,0,0,0,0,0,0,0,0,0,ED23)';
      PINUSE='GROUND';
      NO_LOAD_CHECK='Both';
      NO_IO_CHECK='Both';
      NO_ASSERT_CHECK='TRUE';
      NO_DIR_CHECK='TRUE';
      ALLOW_CONNECT='TRUE';
    'VSS'<13>:
      PIN_NUMBER='(0,0,0,0,0,0,0,0,0,0,0,0,0,0,0,0,0,0,0,0,0,0,0,0,0,0,0,0,0,ED29)';
      PINUSE='GROUND';
      NO_LOAD_CHECK='Both';
      NO_IO_CHECK='Both';
      NO_ASSERT_CHECK='TRUE';
      NO_DIR_CHECK='TRUE';
      ALLOW_CONNECT='TRUE';
    'VSS'<12>:
      PIN_NUMBER='(0,0,0,0,0,0,0,0,0,0,0,0,0,0,0,0,0,0,0,0,0,0,0,0,0,0,0,0,0,ED35)';
      PINUSE='GROUND';
      NO_LOAD_CHECK='Both';
      NO_IO_CHECK='Both';
      NO_ASSERT_CHECK='TRUE';
      NO_DIR_CHECK='TRUE';
      ALLOW_CONNECT='TRUE';
    'VSS'<11>:
      PIN_NUMBER='(0,0,0,0,0,0,0,0,0,0,0,0,0,0,0,0,0,0,0,0,0,0,0,0,0,0,0,0,0,ED77)';
      PINUSE='GROUND';
      NO_LOAD_CHECK='Both';
      NO_IO_CHECK='Both';
      NO_ASSERT_CHECK='TRUE';
      NO_DIR_CHECK='TRUE';
      ALLOW_CONNECT='TRUE';
    'VSS'<10>:
      PIN_NUMBER='(0,0,0,0,0,0,0,0,0,0,0,0,0,0,0,0,0,0,0,0,0,0,0,0,0,0,0,0,0,EE24)';
      PINUSE='GROUND';
      NO_LOAD_CHECK='Both';
      NO_IO_CHECK='Both';
      NO_ASSERT_CHECK='TRUE';
      NO_DIR_CHECK='TRUE';
      ALLOW_CONNECT='TRUE';
    'VSS'<9>:
      PIN_NUMBER='(0,0,0,0,0,0,0,0,0,0,0,0,0,0,0,0,0,0,0,0,0,0,0,0,0,0,0,0,0,EE28)';
      PINUSE='GROUND';
      NO_LOAD_CHECK='Both';
      NO_IO_CHECK='Both';
      NO_ASSERT_CHECK='TRUE';
      NO_DIR_CHECK='TRUE';
      ALLOW_CONNECT='TRUE';
    'VSS'<8>:
      PIN_NUMBER='(0,0,0,0,0,0,0,0,0,0,0,0,0,0,0,0,0,0,0,0,0,0,0,0,0,0,0,0,0,EE30)';
      PINUSE='GROUND';
      NO_LOAD_CHECK='Both';
      NO_IO_CHECK='Both';
      NO_ASSERT_CHECK='TRUE';
      NO_DIR_CHECK='TRUE';
      ALLOW_CONNECT='TRUE';
    'VSS'<7>:
      PIN_NUMBER='(0,0,0,0,0,0,0,0,0,0,0,0,0,0,0,0,0,0,0,0,0,0,0,0,0,0,0,0,0,EE34)';
      PINUSE='GROUND';
      NO_LOAD_CHECK='Both';
      NO_IO_CHECK='Both';
      NO_ASSERT_CHECK='TRUE';
      NO_DIR_CHECK='TRUE';
      ALLOW_CONNECT='TRUE';
    'VSS'<6>:
      PIN_NUMBER='(0,0,0,0,0,0,0,0,0,0,0,0,0,0,0,0,0,0,0,0,0,0,0,0,0,0,0,0,0,EE36)';
      PINUSE='GROUND';
      NO_LOAD_CHECK='Both';
      NO_IO_CHECK='Both';
      NO_ASSERT_CHECK='TRUE';
      NO_DIR_CHECK='TRUE';
      ALLOW_CONNECT='TRUE';
    'VSS'<5>:
      PIN_NUMBER='(0,0,0,0,0,0,0,0,0,0,0,0,0,0,0,0,0,0,0,0,0,0,0,0,0,0,0,0,0,EE70)';
      PINUSE='GROUND';
      NO_LOAD_CHECK='Both';
      NO_IO_CHECK='Both';
      NO_ASSERT_CHECK='TRUE';
      NO_DIR_CHECK='TRUE';
      ALLOW_CONNECT='TRUE';
    'VSS'<4>:
      PIN_NUMBER='(0,0,0,0,0,0,0,0,0,0,0,0,0,0,0,0,0,0,0,0,0,0,0,0,0,0,0,0,0,EE76)';
      PINUSE='GROUND';
      NO_LOAD_CHECK='Both';
      NO_IO_CHECK='Both';
      NO_ASSERT_CHECK='TRUE';
      NO_DIR_CHECK='TRUE';
      ALLOW_CONNECT='TRUE';
    'VSS'<3>:
      PIN_NUMBER='(0,0,0,0,0,0,0,0,0,0,0,0,0,0,0,0,0,0,0,0,0,0,0,0,0,0,0,0,0,EE78)';
      PINUSE='GROUND';
      NO_LOAD_CHECK='Both';
      NO_IO_CHECK='Both';
      NO_ASSERT_CHECK='TRUE';
      NO_DIR_CHECK='TRUE';
      ALLOW_CONNECT='TRUE';
    'VSS'<2>:
      PIN_NUMBER='(0,0,0,0,0,0,0,0,0,0,0,0,0,0,0,0,0,0,0,0,0,0,0,0,0,0,0,0,0,EF71)';
      PINUSE='GROUND';
      NO_LOAD_CHECK='Both';
      NO_IO_CHECK='Both';
      NO_ASSERT_CHECK='TRUE';
      NO_DIR_CHECK='TRUE';
      ALLOW_CONNECT='TRUE';
    'VSS'<1>:
      PIN_NUMBER='(0,0,0,0,0,0,0,0,0,0,0,0,0,0,0,0,0,0,0,0,0,0,0,0,0,0,0,0,0,EF75)';
      PINUSE='GROUND';
      NO_LOAD_CHECK='Both';
      NO_IO_CHECK='Both';
      NO_ASSERT_CHECK='TRUE';
      NO_DIR_CHECK='TRUE';
      ALLOW_CONNECT='TRUE';
    'VSS'<0>:
      PIN_NUMBER='(0,0,0,0,0,0,0,0,0,0,0,0,0,0,0,0,0,0,0,0,0,0,0,0,0,0,0,0,0,EF79)';
      PINUSE='GROUND';
      NO_LOAD_CHECK='Both';
      NO_IO_CHECK='Both';
      NO_ASSERT_CHECK='TRUE';
      NO_DIR_CHECK='TRUE';
      ALLOW_CONNECT='TRUE';
    'VSS_VCCIN_SENSE':
      PIN_NUMBER='(0,0,0,0,0,0,0,0,0,0,0,0,0,0,0,0,0,0,AY85,0,0,0,0,0,0,0,0,0,0,0)';
      PINUSE='POWER';
      NO_LOAD_CHECK='Both';
      NO_IO_CHECK='Both';
      NO_ASSERT_CHECK='TRUE';
      NO_DIR_CHECK='TRUE';
      ALLOW_CONNECT='TRUE';
    'VSS_VCCIO_SENSE':
      PIN_NUMBER='(0,0,0,0,0,0,0,0,0,0,0,0,0,0,0,0,0,0,0,0,0,BF5,0,0,0,0,0,0,0,0)';
      PINUSE='POWER';
      NO_LOAD_CHECK='Both';
      NO_IO_CHECK='Both';
      NO_ASSERT_CHECK='TRUE';
      NO_DIR_CHECK='TRUE';
      ALLOW_CONNECT='TRUE';
    'VSS_VCCSA_SENSE':
      PIN_NUMBER='(0,0,0,0,0,0,0,0,0,0,0,0,0,0,0,0,0,0,0,0,0,CG76,0,0,0,0,0,0,0,0)';
      PINUSE='POWER';
      NO_LOAD_CHECK='Both';
      NO_IO_CHECK='Both';
      NO_ASSERT_CHECK='TRUE';
      NO_DIR_CHECK='TRUE';
      ALLOW_CONNECT='TRUE';
  end_pin;
  body
    PART_NAME='SKX_EXT_B';
    PHYS_DES_PREFIX='U';
  end_body;
end_primitive;

END.
